P  JOB   DAT6MTH3AD0_t6m_cm_d_brd_103112_274.brd
P  UNITS CUST 
P  DIM   N
C  
C  Nov 26 10:33:10 2013
C  
C  IPC-D-356 Netlist From Allegro
C  
317N/C              10_NUT-1    D0100PA00X-029453Y+104485               S1      
317N/C              TTERY1-1    D0100PA00X-028133Y+104485               S1      
317N/C              10_SRW-1    D0100PA00X-028793Y+104485               S1      
317N/C              PCB   -1    D0100PA00X-026701Y+104492               S1      
317N/C              J30   -     D0500UA00X-004487Y+012521               S0      
317N/C              J30   -     D0500UA00X-004487Y+014121               S0      
317N/C              J4    -     D0500UA00X-004487Y+023253               S0      
317N/C              J29   -     D0500UA00X-004487Y+023253               S0      
317N/C              J4    -     D0500UA00X-004487Y+024853               S0      
317N/C              J29   -     D0500UA00X-004487Y+024853               S0      
317N/C              J25   -     D0500UA00X-004487Y+073849               S0      
317IN3_85OHM        VIA   -     D0100PA00X-003986Y+073138               S3      
317N/C              J25   -     D0500UA00X-004487Y+075449               S0      
317N/C              J30   -     D0500UA00X-002687Y+012521               S0      
327THRU_85_OHM      J30   -2          A01X-003499Y+013321X0120Y0080R090 S2      
327THRU_85_OHM      J30   -3          A01X-003676Y+013321X0120Y0080R090 S2      
317GND              J30   -1    D0100PA00X-003587Y+013071               S2      
317N/C              J30   -     D0500UA00X-002687Y+014121               S0      
317N/C              J4    -     D0500UA00X-002687Y+023253               S0      
317N/C              J29   -     D0500UA00X-002687Y+023253               S0      
327TOP_85OHM        J4    -2          A01X-003499Y+024053X0120Y0080R090 S2      
327TOP_85OHM        J4    -3          A01X-003676Y+024053X0120Y0080R090 S2      
317GND              J4    -1    D0100PA00X-003587Y+023803               S2      
317N/C              J4    -     D0500UA00X-002687Y+024853               S0      
327BOT_85OHM        J29   -2          A10X-003676Y+024053X0120Y0080R270 S1      
327BOT_85OHM        J29   -3          A10X-003499Y+024053X0120Y0080R270 S1      
317GND              J29   -1    D0100PA00X-003587Y+023803               S1      
317N/C              J29   -     D0500UA00X-002687Y+024853               S0      
317N/C              J25   -     D0500UA00X-002687Y+073849               S0      
317GND              VIA   -     D0100PA00X-003586Y+073138               S3      
317IN3_85OHM        VIA   -     D0100PA00X-003186Y+073138               S3      
317N/C              J25   -     D0500UA00X-002687Y+075449               S0      
327IN3_85OHM        J25   -2          A01X-003676Y+074649X0120Y0080R270 S2      
327IN3_85OHM        J25   -3          A01X-003499Y+074649X0120Y0080R270 S2      
317GND              J25   -1    D0100PA00X-003587Y+074899               S2      
317P3V3_SUS_NODE1   VIA   -     D0100PA00X+000439Y+053378               S3      
317GND              J36   -1    D0400PA00X+001086Y+010956               S0      
317MATE_N           J36   -2    D0400PA00X+002086Y+010956               S0      
317N/C              J19   -6    D1200UA00X+002544Y+030326               S0      
317P12V_DBG         J19   -4    D0570PA00X+002363Y+032176               S0      
317P12V_DBG         J19   -3    D0570PA00X+002363Y+033830               S0      
317N/C              J19   -5    D1200UA00X+002544Y+035680               S0      
327P12V_DBG         D28   -1          A01X+001999Y+037423X0600Y0800R270 S2      
317P12V_DBG         VIA   -     D0100PA00X+001317Y+037267               S3      
317P12V_DBG         VIA   -     D0100PA00X+001834Y+036645               S3      
317P12V_DBG         VIA   -     D0100PA00X+001312Y+037587               S3      
317P12V_DBG         VIA   -     D0100PA00X+001601Y+036917               S3      
317P12V_DBG         VIA   -     D0100PA00X+002153Y+036899               S3      
327P12V_PDB         D28   -2          A01X+001999Y+039194X0600Y0800R090 S2      
317P12V_PDB         VIA   -     D0100PA00X+001414Y+039183               S3      
317P12V_PDB         VIA   -     D0100PA00X+001821Y+038653               S3      
317P12V_PDB         VIA   -     D0100PA00X+001395Y+038862               S3      
317P12V_PDB         VIA   -     D0100PA00X+001339Y+039754               S3      
317P12V_PDB         VIA   -     D0100PA00X+001424Y+039487               S3      
317UART_DSR_P6_N    VIA   -     D0100PA00X+001945Y+055030               S3      
317UART_CTS_P6_N    VIA   -     D0100PA00X+002065Y+054624               S1      
327NNAME10000       U56   -18         A01X+002044Y+056122X0140Y0590R180 S2      
327UART_DSR_P6_N    U56   -17         A01X+001788Y+056122X0140Y0590R180 S2      
327UART_CTS_P6_N    U56   -16         A01X+001532Y+056122X0140Y0590R180 S2      
327N/C              U56   -15         A01X+001276Y+056122X0140Y0590R180 S2      
317UART_RX_P6       VIA   -     D0100PA00X+002035Y+055581               S1      
317UART_TX_P6       VIA   -     D0100PA00X+001896Y+057206               S3      
317UART_DTR_P6_N    VIA   -     D0100PA00X+001788Y+057842               S3      
317UART_RTS_P6_N    VIA   -     D0100PA00X+001620Y+056692               S1      
327UART_RTS_P6_N    U56   -14         A01X+001276Y+058422X0140Y0590R180 S2      
327UART_TX_P6       U56   -13         A01X+001532Y+058422X0140Y0590R180 S2      
327UART_DTR_P6_N    U56   -12         A01X+001788Y+058422X0140Y0590R180 S2      
327NNAME10001       U56   -11         A01X+002044Y+058422X0140Y0590R180 S2      
327UART_RI_P5_N     U144  -D          A01X+001382Y+059718X0400Y0500R180 S2      
317GND              VIA   -     D0100PA00X+002188Y+059579               S3      
317P3V3_NODE1       VIA   -     D0100PA00X+001702Y+059293               S3      
317UART_RI_P5_N     VIA   -     D0100PA00X+001351Y+059194               S3      
327UART_RI_P5_N     R1068 -2          A01X+001218Y+061213X0180Y0200R180 S2      
327NNAME10002       R1068 -1          A01X+000903Y+061213X0180Y0200R180 S2      
327UART_RI_P5_N     R1262 -2          A01X+002294Y+060295X0180Y0200R270 S2      
327P3V3_NODE1       R1262 -1          A01X+002294Y+059980X0180Y0200R270 S2      
327P3V3_NODE1       R1310 -1          A01X+001860Y+061176X0180Y0200R270 S2      
327NNAME10002       U144  -S          A01X+000982Y+060598X0400Y0500R180 S2      
327TACKOVER_EN      U144  -G          A01X+001782Y+060598X0400Y0500R180 S2      
317P3V3_NODE1       VIA   -     D0100PA00X+001585Y+061098               S3      
317UART_RX_P5       VIA   -     D0100PA00X+001450Y+060196               S3      
327UART_RX_P5       U55   -19         A01X+002051Y+062291X0140Y0590R180 S2      
327NNAME10002       U55   -18         A01X+001795Y+062291X0140Y0590R180 S2      
327UART_DSR_P5_N    U55   -17         A01X+001539Y+062291X0140Y0590R180 S2      
327UART_CTS_P5_N    U55   -16         A01X+001283Y+062291X0140Y0590R180 S2      
327N/C              U55   -15         A01X+001027Y+062291X0140Y0590R180 S2      
327NNAME10002       R1310 -2          A01X+001860Y+061491X0180Y0200R270 S2      
317UART_CTS_P5_N    VIA   -     D0100PA00X+001198Y+061796               S1      
317UART_DSR_P5_N    VIA   -     D0100PA00X+001535Y+061414               S1      
317NNAME10002       VIA   -     D0100PA00X+001455Y+062830               S1      
327UART_RTS_P5_N    U55   -14         A01X+001027Y+064591X0140Y0590R180 S2      
327UART_TX_P5       U55   -13         A01X+001283Y+064591X0140Y0590R180 S2      
327UART_DTR_P5_N    U55   -12         A01X+001539Y+064591X0140Y0590R180 S2      
327NNAME10003       U55   -11         A01X+001795Y+064591X0140Y0590R180 S2      
327UART_TX_P5_L     U55   -10         A01X+002051Y+064591X0140Y0590R180 S2      
317UART_DTR_P5_N    VIA   -     D0100PA00X+001381Y+063483               S1      
317UART_TX_P5       VIA   -     D0100PA00X+000930Y+063147               S1      
317UART_RTS_P5_N    VIA   -     D0100PA00X+000924Y+063870               S3      
327GND              R1297 -1          A01X+002002Y+065895X0180Y0200R180 S2      
317GND              VIA   -     D0100PA00X+001707Y+065895               S3      
317P12V_PDB         VIA   -     D0100PA00X+001168Y+065634               S3      
317P12V_PDB         VIA   -     D0100PA00X+000926Y+065832               S3      
317P12V_PDB         VIA   -     D0100PA00X+001400Y+065837               S3      
317P12V_PDB         VIA   -     D0100PA00X+001417Y+065399               S3      
317P12V_PDB         VIA   -     D0100PA00X+000936Y+065394               S3      
327P3V3_STB_NODE1   C179  -1          A01X+002702Y+001304X0180Y0200R270 S2      
327NNAME10004       U10   -3          A01X+003690Y+001288X0140Y0440     S2      
327GND              U10   -2          A01X+003434Y+001288X0140Y0440     S2      
327P3V3_STB_NODE1   U10   -1          A01X+003178Y+001288X0140Y0440     S2      
317GND              VIA   -     D0100PA00X+003384Y+000918               S1      
317P3V3_STB_NODE1   VIA   -     D0100PA00X+002399Y+001298               S3      
327GND              C179  -2          A01X+002702Y+001619X0180Y0200R270 S2      
327GND              R213  -2          A01X+003126Y+003041X0180Y0200     S2      
327NNAME10005       R213  -1          A01X+003441Y+003041X0180Y0200     S2      
327NNAME10005       R214  -2          A01X+003441Y+002641X0180Y0200R180 S2      
327PV_VDDR_NODE1    R214  -1          A01X+003126Y+002641X0180Y0200R180 S2      
327PV_VDDR_NODE1    U10   -6          A01X+003178Y+002076X0140Y0440     S2      
327NNAME10005       U10   -5          A01X+003434Y+002076X0140Y0440     S2      
327NNAME10006       U10   -4          A01X+003690Y+002076X0140Y0440     S2      
317GND              VIA   -     D0100PA00X+002810Y+003041               S3      
317GND              VIA   -     D0100PA00X+002441Y+001619               S3      
317NNAME10005       VIA   -     D0100PA00X+003685Y+002520               S3      
317PV_VDDR_NODE1    VIA   -     D0100PA00X+002841Y+002641               S3      
327GND              C181  -2          A01X+003760Y+004415X0180Y0200R090 S2      
327GND              C180  -2          A01X+003368Y+003456X0180Y0200R090 S2      
327P5V_STB_NODE1    C180  -1          A01X+003368Y+003771X0180Y0200R090 S2      
317GND              VIA   -     D0100PA00X+003415Y+004415               S3      
317GND              VIA   -     D0100PA00X+003028Y+003456               S3      
317P5V_STB_NODE1    VIA   -     D0100PA00X+003027Y+003771               S3      
317NNAME10005       VIA   -     D0100PA00X+003659Y+003228               S1      
327NNAME10007       C181  -1          A01X+003760Y+004730X0180Y0200R090 S2      
327UART_CTS_P2_N    U52   -17         A01X+003657Y+007954X0140Y0590R180 S2      
327N/C              U52   -16         A01X+003401Y+007954X0140Y0590R180 S2      
327N/C              U52   -15         A01X+003145Y+007954X0140Y0590R180 S2      
317UART_CTS_P2_N    VIA   -     D0100PA00X+003657Y+007315               S3      
317UART_DSR_P2_N    VIA   -     D0100PA00X+003913Y+008463               S3      
317UART_TX_P2       VIA   -     D0100PA00X+003401Y+009102               S1      
327UART_RTS_P2_N    U52   -14         A01X+003145Y+010254X0140Y0590R180 S2      
327UART_TX_P2       U52   -13         A01X+003401Y+010254X0140Y0590R180 S2      
327UART_DTR_P2_N    U52   -12         A01X+003657Y+010254X0140Y0590R180 S2      
317UART_DTR_P2_N    VIA   -     D0100PA00X+003657Y+010799               S3      
317UART_RTS_P2_N    VIA   -     D0100PA00X+003226Y+009690               S1      
317GND              J9    -7    D0330PA00X+003602Y+018723               S0      
317N/C              J9    -11   D0330PA00X+003602Y+018123               S0      
317P5V_CRT          J9    -9    D0330PA00X+003602Y+020526               S0      
317CRT_HSYNC        J9    -13   D0330PA00X+003602Y+019925               S0      
317CRT_G            J9    -2    D0330PA00X+003602Y+019324               S0      
317CRT_DDCCLK       J9    -15   D0330PA00X+003602Y+021727               S0      
317N/C              J9    -4    D0330PA00X+003602Y+021126               S0      
327P12V_DBG         D29   -1          A01X+003225Y+037423X0600Y0800R270 S2      
317P12V_DBG         VIA   -     D0100PA00X+003828Y+036218               S3      
317P12V_DBG         VIA   -     D0100PA00X+003575Y+036459               S3      
317P12V_DBG         VIA   -     D0100PA00X+003342Y+036731               S3      
317P12V_DBG         VIA   -     D0100PA00X+002386Y+036628               S3      
327P12V_PDB         D29   -2          A01X+003225Y+039194X0600Y0800R090 S2      
317GND              VIA   -     D0100PA00X+002825Y+043874               S3      
317GND              VIA   -     D0100PA00X+003799Y+045302               S3      
317GND              VIA   -     D0100PA00X+002825Y+047208               S3      
317GND              VIA   -     D0100PA00X+003799Y+052022               S3      
327GND              C555  -2          A01X+003881Y+054703X0180Y0200     S2      
327N54310543        R1302 -2          A01X+003414Y+054732X0180Y0200R270 S2      
327P3V3_NODE1       R1302 -1          A01X+003414Y+054417X0180Y0200R270 S2      
327N54310545        R1301 -2          A01X+003014Y+054732X0180Y0200R270 S2      
327P3V3_NODE1       R1301 -1          A01X+003014Y+054417X0180Y0200R270 S2      
327NNAME10000       R1311 -2          A01X+002615Y+054737X0180Y0200R270 S2      
327P3V3_NODE1       R1311 -1          A01X+002615Y+054422X0180Y0200R270 S2      
317GND              VIA   -     D0100PA00X+003881Y+054354               S3      
317P3V3_NODE1       VIA   -     D0100PA00X+003414Y+054035               S3      
317P3V3_NODE1       VIA   -     D0100PA00X+003424Y+053697               S3      
327GND              U56   -25         A01X+003835Y+056122X0140Y0590R180 S2      
327N54310592        U56   -24         A01X+003579Y+056122X0140Y0590R180 S2      
327N54310543        U56   -23         A01X+003323Y+056122X0140Y0590R180 S2      
327N54310545        U56   -22         A01X+003067Y+056122X0140Y0590R180 S2      
327N/C              U56   -21         A01X+002811Y+056122X0140Y0590R180 S2      
327N/C              U56   -20         A01X+002555Y+056122X0140Y0590R180 S2      
327UART_RX_P6       U56   -19         A01X+002299Y+056122X0140Y0590R180 S2      
317GND              VIA   -     D0100PA00X+003835Y+055573               S3      
317N54310543        VIA   -     D0100PA00X+003323Y+055635               S1      
317N54310545        VIA   -     D0100PA00X+003067Y+055125               S1      
317NNAME10000       VIA   -     D0100PA00X+002361Y+056811               S1      
327UART_TX_P6_L     U56   -10         A01X+002299Y+058422X0140Y0590R180 S2      
327NNAME10008       U56   -9          A01X+002555Y+058422X0140Y0590R180 S2      
327N54310531        U56   -8          A01X+002811Y+058422X0140Y0590R180 S2      
327NNAME10009       U56   -7          A01X+003067Y+058422X0140Y0590R180 S2      
327NNAME10010       U56   -6          A01X+003323Y+058422X0140Y0590R180 S2      
327UART_RI_P6_L_N   U56   -5          A01X+003579Y+058422X0140Y0590R180 S2      
327UART_RX_P6_L     U56   -4          A01X+003835Y+058422X0140Y0590R180 S2      
327GND              C553  -1          A01X+003720Y+059729X0180Y0200R180 S2      
327N54310531        R1300 -2          A01X+002811Y+059579X0180Y0200R180 S2      
327GND              R1300 -1          A01X+002496Y+059579X0180Y0200R180 S2      
317GND              VIA   -     D0100PA00X+003444Y+059729               S1      
317N54310531        VIA   -     D0100PA00X+002811Y+059172               S1      
327GND              C550  -2          A01X+003694Y+060813X0180Y0200     S2      
327N54258474        R1299 -2          A01X+003227Y+060842X0180Y0200R270 S2      
327P3V3_NODE1       R1299 -1          A01X+003227Y+060527X0180Y0200R270 S2      
327N54258476        R1298 -2          A01X+002827Y+060842X0180Y0200R270 S2      
327P3V3_NODE1       R1298 -1          A01X+002827Y+060527X0180Y0200R270 S2      
317GND              VIA   -     D0100PA00X+003693Y+061108               S3      
317P3V3_NODE1       VIA   -     D0100PA00X+002827Y+060219               S3      
317P3V3_NODE1       VIA   -     D0100PA00X+003314Y+060223               S3      
317N54258476        VIA   -     D0100PA00X+002819Y+061209               S1      
327P3V3_NODE1       U55   -26         A01X+003842Y+062291X0140Y0590R180 S2      
327GND              U55   -25         A01X+003586Y+062291X0140Y0590R180 S2      
327N54258515        U55   -24         A01X+003330Y+062291X0140Y0590R180 S2      
327N54258474        U55   -23         A01X+003074Y+062291X0140Y0590R180 S2      
327N54258476        U55   -22         A01X+002819Y+062291X0140Y0590R180 S2      
327N/C              U55   -21         A01X+002563Y+062291X0140Y0590R180 S2      
327N/C              U55   -20         A01X+002307Y+062291X0140Y0590R180 S2      
317GND              VIA   -     D0100PA00X+003586Y+061705               S3      
317N54258474        VIA   -     D0100PA00X+003074Y+061790               S1      
327NNAME10011       U55   -9          A01X+002307Y+064591X0140Y0590R180 S2      
327N54258454        U55   -8          A01X+002563Y+064591X0140Y0590R180 S2      
327NNAME10012       U55   -7          A01X+002819Y+064591X0140Y0590R180 S2      
327NNAME10013       U55   -6          A01X+003074Y+064591X0140Y0590R180 S2      
327UART_RI_P5_L_N   U55   -5          A01X+003330Y+064591X0140Y0590R180 S2      
327UART_RX_P5_L     U55   -4          A01X+003586Y+064591X0140Y0590R180 S2      
327N54258537        U55   -3          A01X+003842Y+064591X0140Y0590R180 S2      
327N54258537        C548  -2          A01X+003596Y+065895X0180Y0200R180 S2      
327GND              C548  -1          A01X+003281Y+065895X0180Y0200R180 S2      
327N54258454        R1297 -2          A01X+002317Y+065895X0180Y0200R180 S2      
317GND              VIA   -     D0100PA00X+002996Y+065895               S3      
317N54258454        VIA   -     D0100PA00X+002417Y+065575               S1      
317N54258537        VIA   -     D0100PA00X+003792Y+065183               S1      
327NNAME10014       R471  -2          A01X+004536Y+001459X0180Y0200R180 S2      
327NNAME10004       R471  -1          A01X+004221Y+001459X0180Y0200R180 S2      
327NNAME10015       R472  -2          A01X+004536Y+001859X0180Y0200R180 S2      
327NNAME10006       R472  -1          A01X+004221Y+001859X0180Y0200R180 S2      
327NNAME10016       U11   -3          A01X+004722Y+002806X0220Y0530     S2      
327GND              U11   -2          A01X+004348Y+002806X0220Y0530     S2      
327NNAME10005       U11   -1          A01X+003974Y+002806X0220Y0530     S2      
317GND              VIA   -     D0100PA00X+004541Y+002156               S3      
317GND              VIA   -     D0100PA00X+005486Y+001695               S3      
317NNAME10016       VIA   -     D0100PA00X+004989Y+003039               S1      
317NNAME10004       VIA   -     D0100PA00X+005158Y+001760               S1      
317NNAME10006       VIA   -     D0100PA00X+004221Y+002152               S1      
317NNAME10015       VIA   -     D0100PA00X+005480Y+002555               S1      
327NNAME10016       R216  -1          A01X+004160Y+004415X0180Y0200R270 S2      
327NNAME10016       R218  -1          A01X+004558Y+004415X0180Y0200R270 S2      
327NNAME10016       R215  -2          A01X+004956Y+004415X0180Y0200R090 S2      
327P5V_STB_NODE1    U11   -5          A01X+003974Y+003771X0220Y0530     S2      
327NNAME10016       U11   -4          A01X+004722Y+003771X0220Y0530     S2      
317GND              VIA   -     D0100PA00X+004348Y+003459               S3      
327NNAME10007       R216  -2          A01X+004160Y+004730X0180Y0200R270 S2      
327GND              R218  -2          A01X+004558Y+004730X0180Y0200R270 S2      
327PV_VDDR_NODE1    R215  -1          A01X+004956Y+004730X0180Y0200R090 S2      
317GND              VIA   -     D0100PA00X+004558Y+005048               S3      
317P3V3_NODE1       VIA   -     D0100PA00X+005098Y+005868               S3      
317P3V3_NODE1       VIA   -     D0100PA00X+004698Y+005869               S3      
317NNAME10007       VIA   -     D0100PA00X+004401Y+005517               S1      
317N54251517        VIA   -     D0100PA00X+005498Y+005942               S1      
317PV_VDDR_NODE1    VIA   -     D0100PA00X+004956Y+005058               S3      
327N54251487        U52   -23         A01X+005192Y+007954X0140Y0590R180 S2      
327N54251489        U52   -22         A01X+004936Y+007954X0140Y0590R180 S2      
327N/C              U52   -21         A01X+004680Y+007954X0140Y0590R180 S2      
327N/C              U52   -20         A01X+004424Y+007954X0140Y0590R180 S2      
327UART_RX_P2       U52   -19         A01X+004169Y+007954X0140Y0590R180 S2      
327UART_DSR_P2_N    U52   -18         A01X+003913Y+007954X0140Y0590R180 S2      
327N54251489        R652  -2          A01X+004698Y+006559X0180Y0200R270 S2      
327P3V3_NODE1       R652  -1          A01X+004698Y+006244X0180Y0200R270 S2      
327N54251487        R651  -2          A01X+005098Y+006559X0180Y0200R270 S2      
327P3V3_NODE1       R651  -1          A01X+005098Y+006244X0180Y0200R270 S2      
317UART_RX_P2       VIA   -     D0100PA00X+004169Y+007311               S3      
317N54251519        VIA   -     D0100PA00X+005410Y+007425               S1      
317N54251487        VIA   -     D0100PA00X+005134Y+006918               S1      
317N54251489        VIA   -     D0100PA00X+004657Y+007389               S1      
327NNAME10017       U52   -11         A01X+003913Y+010254X0140Y0590R180 S2      
327UART_TX_P2_L     U52   -10         A01X+004169Y+010254X0140Y0590R180 S2      
327NNAME10018       U52   -9          A01X+004424Y+010254X0140Y0590R180 S2      
327N54251449        U52   -8          A01X+004680Y+010254X0140Y0590R180 S2      
327N54251449        U52   -7          A01X+004936Y+010254X0140Y0590R180 S2      
327NNAME10019       U52   -6          A01X+005192Y+010254X0140Y0590R180 S2      
317N54251449        VIA   -     D0100PA00X+004751Y+010942               S1      
327N54251541        C545  -2          A01X+005470Y+011595X0180Y0200R090 S2      
327GND              C545  -1          A01X+005470Y+011910X0180Y0200R090 S2      
327N54251449        R654  -2          A01X+004681Y+011566X0180Y0200R090 S2      
327GND              R654  -1          A01X+004681Y+011881X0180Y0200R090 S2      
317GND              VIA   -     D0100PA00X+005470Y+012280               S3      
317GND              VIA   -     D0100PA00X+004681Y+012293               S3      
317GND              J9    -G1   D0280PA00X+004075Y+015081               S0      
317N/C              J9    -H1   D0590UA00X+004390Y+016854               S0      
317CRT_R            J9    -1    D0330PA00X+004193Y+018423               S0      
317GND              J9    -6    D0330PA00X+004193Y+017822               S0      
317CRT_B            J9    -3    D0330PA00X+004193Y+020225               S0      
317GND              J9    -8    D0330PA00X+004193Y+019625               S0      
317CRT_DDCDATA      J9    -12   D0330PA00X+004193Y+019024               S0      
317GND              J9    -5    D0330PA00X+004193Y+022028               S0      
317GND              J9    -10   D0330PA00X+004193Y+021427               S0      
317CRT_VSYNC        J9    -14   D0330PA00X+004193Y+020826               S0      
317N/C              J9    -H2   D0590UA00X+004390Y+023146               S0      
317GND              J9    -G2   D0280PA00X+004075Y+024919               S0      
317GND              VIA   -     D0100PA00X+005406Y+025705               S3      
317GND              J19   -2    D0570PA00X+004528Y+032176               S0      
317GND              J19   -1    D0570PA00X+004528Y+033830               S0      
317GND              VIA   -     D0100PA00X+004924Y+036035               S3      
317P12V_DBG         VIA   -     D0100PA00X+004069Y+035956               S3      
327P12V_DBG         R1071 -1          A01X+004428Y+037403X0560Y0950R090 S2      
327P12V_PDB         R1071 -2          A01X+004428Y+039254X0560Y0950R090 S2      
317P12V_PDB         VIA   -     D0100PA00X+005334Y+039313               S3      
317P12V_PDB         VIA   -     D0100PA00X+004975Y+038731               S3      
317P12V_PDB         VIA   -     D0100PA00X+005172Y+038481               S3      
317P12V_PDB         VIA   -     D0100PA00X+005084Y+039576               S3      
317P12V_PDB         VIA   -     D0100PA00X+004782Y+039883               S3      
327GND              PC64  -2          A01X+004729Y+042263X0950Y1110R180 S2      
317GND              VIA   -     D0100PA00X+004973Y+041247               S3      
317GND              VIA   -     D0100PA00X+004553Y+041247               S3      
317GND              VIA   -     D0100PA00X+005215Y+041490               S3      
317GND              VIA   -     D0100PA00X+004790Y+041466               S3      
317GND              VIA   -     D0100PA00X+004436Y+041492               S3      
327GND              PC63  -2          A01X+004729Y+044145X0950Y1110R180 S2      
317GND              VIA   -     D0100PA00X+004964Y+043024               S3      
317GND              VIA   -     D0100PA00X+004541Y+043044               S3      
317GND              VIA   -     D0100PA00X+005135Y+043370               S3      
317GND              VIA   -     D0100PA00X+004742Y+043373               S1      
317GND              VIA   -     D0100PA00X+004436Y+043373               S3      
327P12V_AUX         PR22  -2          A01X+004522Y+047199X0460Y0620     S2      
317P12V_AUX         VIA   -     D0100PA00X+005167Y+046289               S3      
317P12V_AUX         VIA   -     D0100PA00X+004759Y+046388               S3      
317P12V_AUX         VIA   -     D0100PA00X+004983Y+046550               S3      
317P12V_AUX         VIA   -     D0100PA00X+004720Y+046726               S3      
317P12V_AUX         VIA   -     D0100PA00X+004959Y+046943               S3      
327GND              PC57  -2          A10X+004555Y+048856X0460Y0620R180 S1      
327GND              PC56  -2          A01X+004555Y+048856X0460Y0620     S2      
327GND              PC55  -2          A01X+004533Y+048023X0460Y0620     S2      
317GND              VIA   -     D0100PA00X+004963Y+047847               S3      
317GND              VIA   -     D0100PA00X+004963Y+048097               S3      
317P12V_AUX         VIA   -     D0100PA00X+004919Y+047271               S3      
327GND              PC58  -2          A01X+004982Y+049457X0180Y0200     S2      
327NNAME10020       PC58  -1          A01X+005297Y+049457X0180Y0200     S2      
327GND              PC54  -2          A10X+004984Y+049462X0180Y0200R180 S1      
327NNAME10020       PC54  -1          A10X+005299Y+049462X0180Y0200R180 S1      
327GND              PC59  -1          A01X+005140Y+050084X0280Y0320R270 S2      
317GND              VIA   -     D0100PA00X+005033Y+049794               S3      
317GND              VIA   -     D0100PA00X+005333Y+049794               S3      
317GND              VIA   -     D0100PA00X+004965Y+049180               S3      
317GND              VIA   -     D0100PA00X+004965Y+048930               S3      
317GND              VIA   -     D0100PA00X+004738Y+049464               S3      
327NNAME10021       PR30  -2          A01X+005133Y+051807X0180Y0200R180 S2      
327P1V05_NODE1      PR30  -1          A01X+004818Y+051807X0180Y0200R180 S2      
327GND              PR28  -2          A01X+005091Y+051071X0180Y0200R090 S2      
327NNAME10022       PR28  -1          A01X+005091Y+051386X0180Y0200R090 S2      
317GND              VIA   -     D0100PA00X+005362Y+050928               S3      
317GND              VIA   -     D0100PA00X+005333Y+050642               S3      
317GND              VIA   -     D0100PA00X+005333Y+050382               S3      
317GND              VIA   -     D0100PA00X+005033Y+050382               S3      
317NNAME10022       VIA   -     D0100PA00X+005377Y+051303               S1      
317NNAME10023       VIA   -     D0100PA00X+005499Y+051868               S1      
327NNAME10024       PR29  -2          A01X+005134Y+052606X0180Y0200R270 S2      
327NNAME10021       PR29  -1          A01X+005134Y+052291X0180Y0200R270 S2      
317P3V3_NODE1       VIA   -     D0100PA00X+005412Y+052910               S3      
317NNAME10021       VIA   -     D0100PA00X+004986Y+052052               S1      
317NNAME10024       VIA   -     D0100PA00X+005063Y+052928               S1      
327N54310604        C562  -2          A01X+004614Y+054732X0180Y0200R270 S2      
327GND              C562  -1          A01X+004614Y+054417X0180Y0200R270 S2      
327N54310592        C554  -2          A01X+005014Y+054417X0180Y0200R090 S2      
327N54310590        C554  -1          A01X+005014Y+054732X0180Y0200R090 S2      
327P3V3_NODE1       C555  -1          A01X+004196Y+054703X0180Y0200     S2      
317GND              VIA   -     D0100PA00X+004614Y+054171               S3      
317P3V3_NODE1       VIA   -     D0100PA00X+004196Y+054332               S3      
317N54310590        VIA   -     D0100PA00X+005014Y+055057               S1      
317N54310592        VIA   -     D0100PA00X+003954Y+053846               S1      
327N54310590        U56   -28         A01X+004603Y+056122X0140Y0590R180 S2      
327N54310604        U56   -27         A01X+004347Y+056122X0140Y0590R180 S2      
327P3V3_NODE1       U56   -26         A01X+004091Y+056122X0140Y0590R180 S2      
317NNAME10001       VIA   -     D0100PA00X+005087Y+056401               S1      
317N54310604        VIA   -     D0100PA00X+004347Y+055594               S1      
317UART_TX_P6_L     VIA   -     D0100PA00X+005399Y+056875               S3      
317UART_RI_P6_L_N   VIA   -     D0100PA00X+004968Y+057971               S1      
317NNAME10009       VIA   -     D0100PA00X+004962Y+057421               S1      
327N54310606        U56   -3          A01X+004091Y+058422X0140Y0590R180 S2      
327N54310598        U56   -2          A01X+004347Y+058422X0140Y0590R180 S2      
327N54310596        U56   -1          A01X+004603Y+058422X0140Y0590R180 S2      
327N54310598        C552  -2          A01X+004451Y+059729X0180Y0200     S2      
327N54310596        C552  -1          A01X+004766Y+059729X0180Y0200     S2      
327N54310606        C553  -2          A01X+004035Y+059729X0180Y0200R180 S2      
317N54310596        VIA   -     D0100PA00X+004756Y+058897               S1      
317N54310598        VIA   -     D0100PA00X+004451Y+059408               S1      
317N54310606        VIA   -     D0100PA00X+004091Y+058969               S1      
327P3V3_NODE1       C550  -1          A01X+004009Y+060813X0180Y0200     S2      
327N54258535        C551  -2          A01X+004427Y+060842X0180Y0200R270 S2      
327GND              C551  -1          A01X+004427Y+060527X0180Y0200R270 S2      
327N54258515        C549  -2          A01X+004827Y+060527X0180Y0200R090 S2      
327N54258513        C549  -1          A01X+004827Y+060842X0180Y0200R090 S2      
317GND              VIA   -     D0100PA00X+004385Y+060280               S3      
317P3V3_NODE1       VIA   -     D0100PA00X+003936Y+060459               S3      
317N54258515        VIA   -     D0100PA00X+003937Y+060096               S1      
317N54258535        VIA   -     D0100PA00X+004295Y+061249               S1      
327N54065132        C540  -1          A01X+005526Y+062573X0460Y0620R270 S2      
327N54258513        U55   -28         A01X+004354Y+062291X0140Y0590R180 S2      
327N54258535        U55   -27         A01X+004098Y+062291X0140Y0590R180 S2      
317UART_TX_P5_L     VIA   -     D0100PA00X+005027Y+062779               S3      
317NNAME10003       VIA   -     D0100PA00X+004854Y+062495               S1      
317N54065132        VIA   -     D0100PA00X+005223Y+061491               S1      
317N54065132        VIA   -     D0100PA00X+005105Y+061941               S3      
317N54065132        VIA   -     D0100PA00X+004806Y+062123               S3      
317N54258513        VIA   -     D0100PA00X+004748Y+061685               S1      
327GND              C540  -2          A01X+005526Y+063733X0460Y0620R270 S2      
327N54258525        U55   -2          A01X+004098Y+064591X0140Y0590R180 S2      
327N54258523        U55   -1          A01X+004354Y+064591X0140Y0590R180 S2      
327N54065132        R1275 -1          A01X+005375Y+064393X0180Y0200R180 S2      
317GND              VIA   -     D0100PA00X+005017Y+063690               S3      
317N54065132        VIA   -     D0100PA00X+005104Y+064393               S3      
317NNAME10012       VIA   -     D0100PA00X+004689Y+063356               S1      
327N54258525        C542  -2          A01X+004032Y+065895X0180Y0200     S2      
327N54258523        C542  -1          A01X+004347Y+065895X0180Y0200     S2      
327N54065132        R1276 -1          A01X+005375Y+064843X0180Y0200R180 S2      
317N54065132        VIA   -     D0100PA00X+005375Y+065203               S1      
317N54258523        VIA   -     D0100PA00X+004464Y+065103               S1      
317N54258525        VIA   -     D0100PA00X+004098Y+065640               S1      
317P12V_PDB         VIA   -     D0100PA00X+004972Y+066841               S3      
327P12V_PDB         J35   -A82        A10X+005124Y+080787X0300Y1660R180 S1      
327P12V_PDB         J35   -A81        A10X+005518Y+080787X0300Y1660R180 S1      
327P12V_PDB         J35   -B82        A01X+005124Y+080787X0300Y1660R180 S2      
327MATE_R_N         J35   -B81        A01X+005518Y+080590X0300Y1260R180 S2      
317GND              VIA   -     D0100PA00X+005952Y+002592               S3      
317NNAME10014       VIA   -     D0100PA00X+005661Y+002055               S1      
317GND              VIA   -     D0100PA00X+006698Y+005939               S3      
317GND              VIA   -     D0100PA00X+006298Y+005944               S3      
327N54251517        U52   -28         A01X+006472Y+007954X0140Y0590R180 S2      
327N54251539        U52   -27         A01X+006216Y+007954X0140Y0590R180 S2      
327P3V3_NODE1       U52   -26         A01X+005960Y+007954X0140Y0590R180 S2      
327GND              U52   -25         A01X+005704Y+007954X0140Y0590R180 S2      
327N54251519        U52   -24         A01X+005448Y+007954X0140Y0590R180 S2      
327N54251539        C544  -2          A01X+006698Y+006559X0180Y0200R270 S2      
327GND              C544  -1          A01X+006698Y+006244X0180Y0200R270 S2      
327GND              C543  -2          A01X+006298Y+006244X0180Y0200R090 S2      
327P3V3_NODE1       C543  -1          A01X+006298Y+006559X0180Y0200R090 S2      
327N54251519        C546  -2          A01X+005498Y+006559X0180Y0200R270 S2      
327N54251517        C546  -1          A01X+005498Y+006244X0180Y0200R270 S2      
317GND              VIA   -     D0100PA00X+005704Y+007342               S3      
317P3V3_NODE1       VIA   -     D0100PA00X+006032Y+006559               S3      
317N54251539        VIA   -     D0100PA00X+006419Y+007284               S1      
327NNAME10025       U52   -5          A01X+005448Y+010254X0140Y0590R180 S2      
327UART_RX_P2_L     U52   -4          A01X+005704Y+010254X0140Y0590R180 S2      
327N54251541        U52   -3          A01X+005960Y+010254X0140Y0590R180 S2      
327N54251529        U52   -2          A01X+006216Y+010254X0140Y0590R180 S2      
327N54251527        U52   -1          A01X+006472Y+010254X0140Y0590R180 S2      
317N54251529        VIA   -     D0100PA00X+006176Y+010732               S1      
327N54251529        C547  -2          A01X+005865Y+011516X0180Y0200     S2      
327N54251527        C547  -1          A01X+006180Y+011516X0180Y0200     S2      
317N54251541        VIA   -     D0100PA00X+005523Y+011252               S1      
317N54251527        VIA   -     D0100PA00X+006390Y+011208               S1      
327NNAME10026       R195  -2          A01X+006783Y+014503X0180Y0200R270 S2      
327P3V3_SUS_NODE1   R195  -1          A01X+006783Y+014188X0180Y0200R270 S2      
317P3V3_SUS_NODE1   VIA   -     D0100PA00X+006431Y+014188               S3      
327GND              C502  -2          A01X+005992Y+017003X0280Y0320R180 S2      
327NNAME10027       C499  -1          A01X+006544Y+016455X0280Y0320R090 S2      
327GND              C499  -2          A01X+005964Y+016455X0280Y0320R090 S2      
327NNAME10027       L41   -1          A01X+006570Y+017007X0280Y0320     S2      
317GND              VIA   -     D0100PA00X+006876Y+016770               S3      
317GND              VIA   -     D0100PA00X+005619Y+017003               S1      
317GND              VIA   -     D0100PA00X+005964Y+016138               S3      
327GND              C505  -2          A01X+006102Y+018071X0180Y0200R090 S2      
327CRT_DDCDATA      C505  -1          A01X+006102Y+018386X0180Y0200R090 S2      
327CRT_R            C502  -1          A01X+005992Y+017583X0280Y0320R180 S2      
327CRT_R_L          L41   -2          A01X+006570Y+017587X0280Y0320     S2      
327CRT_DDCDATA      R639  -2          A01X+006517Y+018392X0180Y0200R270 S2      
327NNAME10028       R639  -1          A01X+006517Y+018077X0180Y0200R270 S2      
317GND              VIA   -     D0100PA00X+005726Y+018071               S1      
317NNAME10028       VIA   -     D0100PA00X+006785Y+018074               S1      
317CRT_R_L          VIA   -     D0100PA00X+006869Y+017559               S1      
327CRT_G            C503  -1          A01X+005982Y+019377X0280Y0320     S2      
327GND              C503  -2          A01X+005982Y+019957X0280Y0320     S2      
327NNAME10029       L40   -1          A01X+006582Y+019957X0280Y0320R180 S2      
327CRT_G_L          L40   -2          A01X+006582Y+019377X0280Y0320R180 S2      
327CRT_G_L          R641  -1          A01X+006949Y+018895X0180Y0200R180 S2      
327CRT_G            R788  -2          A01X+006066Y+018918X0180Y0200     S2      
327CRT_G_L          R788  -1          A01X+006381Y+018918X0180Y0200     S2      
317GND              VIA   -     D0100PA00X+005596Y+019957               S3      
317NNAME10029       VIA   -     D0100PA00X+006893Y+019719               S3      
317CRT_G_L          VIA   -     D0100PA00X+006657Y+018998               S1      
327GND              C506  -2          A01X+006073Y+020433X0180Y0200R090 S2      
327CRT_HSYNC        C506  -1          A01X+006073Y+020748X0180Y0200R090 S2      
327CRT_B            C504  -1          A01X+006024Y+021274X0280Y0320     S2      
327GND              C504  -2          A01X+006024Y+021854X0280Y0320     S2      
327NNAME10030       L39   -1          A01X+006624Y+021854X0280Y0320R180 S2      
327CRT_B_L          L39   -2          A01X+006624Y+021274X0280Y0320R180 S2      
327CRT_HSYNC        R638  -2          A01X+006491Y+020760X0180Y0200R270 S2      
327VGA_HSYNC        R638  -1          A01X+006491Y+020445X0180Y0200R270 S2      
317GND              VIA   -     D0100PA00X+005775Y+020433               S3      
317GND              VIA   -     D0100PA00X+005638Y+021854               S3      
317CRT_B_L          VIA   -     D0100PA00X+006883Y+021582               S1      
327CRT_VSYNC        U50   -3          A01X+006568Y+023392X0400Y0500R090 S2      
327GND              C507  -2          A01X+006003Y+022868X0180Y0200R090 S2      
327CRT_VSYNC        C507  -1          A01X+006003Y+023183X0180Y0200R090 S2      
327NNAME10030       C501  -1          A01X+006606Y+022394X0280Y0320R090 S2      
327GND              C501  -2          A01X+006026Y+022394X0280Y0320R090 S2      
317GND              VIA   -     D0100PA00X+006372Y+022868               S3      
317GND              VIA   -     D0100PA00X+005694Y+022394               S3      
327NNAME10031       R636  -1          A01X+006018Y+024995X0180Y0200R270 S2      
327NNAME10031       R635  -2          A01X+006018Y+024602X0180Y0200R270 S2      
327P5V_CRT          R635  -1          A01X+006018Y+024287X0180Y0200R270 S2      
327CRT_VSYNC        R637  -2          A01X+006003Y+023588X0180Y0200R090 S2      
327VGA_VSYNC        R637  -1          A01X+006003Y+023903X0180Y0200R090 S2      
327NNAME10031       Q17   -D          A01X+006597Y+024794X0400Y0500R090 S2      
317P5V_CRT          VIA   -     D0100PA00X+005629Y+024287               S1      
317VGA_VSYNC        VIA   -     D0100PA00X+006372Y+023903               S1      
327CRT_DDCCLK       U49   -3          A01X+007080Y+025878X0400Y0500R180 S2      
327P5V_CRT          U49   -2          A01X+006680Y+026758X0400Y0500R180 S2      
327GND              C508  -2          A01X+005703Y+025705X0180Y0200     S2      
327CRT_DDCCLK       C508  -1          A01X+006018Y+025705X0180Y0200     S2      
327CRT_DDCCLK       R636  -2          A01X+006018Y+025310X0180Y0200R270 S2      
327N21581564        FS2   -2          A01X+005799Y+027866X0480Y1300R180 S2      
317P5V_CRT          VIA   -     D0100PA00X+006195Y+026758               S1      
327N21581564        CD1   -2          A01X+005847Y+029317X0320Y0360     S2      
327VCC5_CRTXX       CD1   -1          A01X+006689Y+029317X0320Y0360     S2      
317VCC5_CRTXX       VIA   -     D0100PA00X+006682Y+029748               S1      
317N21581564        VIA   -     D0100PA00X+005799Y+028766               S1      
327N/C                    -1          A01X+007197Y+035785X0390Y0390R270 S2      
327N/C                    -1          A10X+007197Y+035785X0390Y0390R270 S1      
317GND              VIA   -     D0100PA00X+005762Y+036611               S3      
327P1V05_NODE1      PC64  -1          A01X+007249Y+042263X0950Y1110R180 S2      
317P3V3_NODE1       VIA   -     D0100PA00X+005800Y+041264               S3      
327P1V05_NODE1      PC63  -1          A01X+007249Y+044145X0950Y1110R180 S2      
317P1V05_NODE1      VIA   -     D0100PA00X+006457Y+045103               S3      
317P1V05_NODE1      VIA   -     D0100PA00X+006757Y+045103               S3      
317P1V05_NODE1      VIA   -     D0100PA00X+007057Y+045103               S3      
327NNAME10020       PR22  -1          A01X+005682Y+047199X0460Y0620     S2      
317GND              VIA   -     D0100PA00X+006675Y+046636               S3      
317GND              VIA   -     D0100PA00X+006405Y+046569               S3      
317GND              VIA   -     D0100PA00X+006118Y+046531               S3      
327NNAME10020       PC57  -1          A10X+005715Y+048856X0460Y0620R180 S1      
327NNAME10020       PC56  -1          A01X+005715Y+048856X0460Y0620     S2      
327NNAME10020       PC55  -1          A01X+005693Y+048023X0460Y0620     S2      
317NNAME10020       VIA   -     D0100PA00X+006136Y+048339               S3      
317NNAME10020       VIA   -     D0100PA00X+006136Y+048089               S3      
317NNAME10020       VIA   -     D0100PA00X+006136Y+047789               S1      
317NNAME10020       VIA   -     D0100PA00X+006119Y+048712               S3      
327NNAME10020       PQ1   -1_EP       A01X+006764Y+049362X0330Y0990     S2      
327NNAME10020       PQ1   -4          A01X+006409Y+048978X0170Y0220R270 S2      
327NNAME10020       PQ1   -3          A01X+006409Y+049234X0170Y0220R270 S2      
327NNAME10020       PQ1   -2          A01X+006409Y+049490X0170Y0220R270 S2      
327NNAME10032       PQ1   -1          A01X+006409Y+049746X0170Y0220R270 S2      
327P5V_STB_NODE1    PC59  -2          A01X+005720Y+050084X0280Y0320R270 S2      
317P5V_STB_NODE1    VIA   -     D0100PA00X+005633Y+049794               S3      
317P5V_STB_NODE1    VIA   -     D0100PA00X+005883Y+049794               S3      
317NNAME10033       VIA   -     D0100PA00X+006168Y+050266               S3      
317NNAME10033       VIA   -     D0100PA00X+006168Y+050016               S3      
317NNAME10020       VIA   -     D0100PA00X+006119Y+048962               S3      
317NNAME10020       VIA   -     D0100PA00X+006119Y+049212               S3      
317NNAME10020       VIA   -     D0100PA00X+005598Y+049454               S3      
317NNAME10032       VIA   -     D0100PA00X+006448Y+050160               S1      
327GND              PU6   -TH         A01X+006324Y+051288X0650Y0650     S2      
327NNAME10034       PU6   -16         A01X+006934Y+051584X0110Y0360R270 S2      
327NNAME10035       PU6   -15         A01X+006934Y+051387X0110Y0360R270 S2      
327P1V05_NODE1_EN   PU6   -14         A01X+006934Y+051190X0110Y0360R270 S2      
327NNAME10036       PU6   -13         A01X+006934Y+050993X0110Y0360R270 S2      
327GND              PU6   -8          A01X+005714Y+050993X0110Y0360R270 S2      
327GND              PU6   -7          A01X+005714Y+051190X0110Y0360R270 S2      
327NNAME10022       PU6   -6          A01X+005714Y+051387X0110Y0360R270 S2      
327NNAME10023       PU6   -5          A01X+005714Y+051584X0110Y0360R270 S2      
327NNAME10037       PU6   -12         A01X+006619Y+050678X0110Y0360     S2      
327NNAME10032       PU6   -11         A01X+006422Y+050678X0110Y0360     S2      
327NNAME10033       PU6   -10         A01X+006225Y+050678X0110Y0360     S2      
327P5V_STB_NODE1    PU6   -9          A01X+006028Y+050678X0110Y0360     S2      
327NNAME10024       PU6   -4          A01X+006028Y+051899X0110Y0360     S2      
327NNAME10038       PU6   -3          A01X+006225Y+051899X0110Y0360     S2      
327NNAME10039       PU6   -2          A01X+006422Y+051899X0110Y0360     S2      
327NNAME10040       PU6   -1          A01X+006619Y+051899X0110Y0360     S2      
317GND              VIA   -     D0100PA00X+006544Y+051067               S3      
317GND              VIA   -     D0100PA00X+006103Y+051071               S3      
317GND              VIA   -     D0100PA00X+006100Y+051511               S3      
317GND              VIA   -     D0100PA00X+006548Y+051511               S3      
327NNAME10023       PC69  -2          A01X+005535Y+052291X0180Y0200R090 S2      
327NNAME10024       PC69  -1          A01X+005535Y+052606X0180Y0200R090 S2      
327NNAME10040       PC65  -2          A01X+006653Y+052642X0180Y0200R180 S2      
327NNAME10038       PC65  -1          A01X+006338Y+052642X0180Y0200R180 S2      
327GND              PC70  -2          A01X+005930Y+052920X0180Y0200R270 S2      
327NNAME10024       PC70  -1          A01X+005930Y+052605X0180Y0200R270 S2      
327NNAME10038       PR27  -2          A01X+006338Y+053042X0180Y0200     S2      
327GND              PR27  -1          A01X+006653Y+053042X0180Y0200     S2      
327NNAME10039       PR25  -2          A10X+006555Y+052798X0180Y0200     S1      
327P3V3_NODE1       PR25  -1          A10X+006240Y+052798X0180Y0200     S1      
317GND              VIA   -     D0100PA00X+005615Y+053081               S3      
317NNAME10038       VIA   -     D0100PA00X+006225Y+052259               S1      
317NNAME10039       VIA   -     D0100PA00X+006737Y+052299               S1      
317NNAME10040       VIA   -     D0100PA00X+007070Y+052724               S1      
317GND              VIA   -     D0100PA00X+006726Y+054669               S1      
327GND              C414  -2          A01X+007007Y+056082X0440Y0540     S2      
327GND              C393  -2          A01X+007022Y+055297X0440Y0540     S2      
317GND              VIA   -     D0100PA00X+006590Y+056640               S1      
317GND              VIA   -     D0100PA00X+006618Y+056215               S3      
317GND              VIA   -     D0100PA00X+006393Y+056018               S3      
317GND              VIA   -     D0100PA00X+006626Y+055334               S1      
327GND              C413  -2          A01X+007007Y+057682X0440Y0540     S2      
327GND              C415  -2          A01X+007007Y+056882X0440Y0540     S2      
317GND              VIA   -     D0100PA00X+006599Y+057812               S1      
317GND              VIA   -     D0100PA00X+006604Y+057490               S3      
317GND              VIA   -     D0100PA00X+006367Y+057604               S3      
317NNAME10008       VIA   -     D0100PA00X+005771Y+057292               S1      
317NNAME10010       VIA   -     D0100PA00X+005707Y+058007               S1      
317GND              VIA   -     D0100PA00X+006977Y+058253               S1      
317UART_RX_P6_L     VIA   -     D0100PA00X+005744Y+058561               S1      
327LAN1_P1_P        U137  -24         A01X+006849Y+060391X0320Y0610R090 S2      
327LAN1_P1_N        U137  -23         A01X+006849Y+060891X0320Y0610R090 S2      
327LAN1_P1_R        U137  -22         A01X+006849Y+061391X0320Y0610R090 S2      
317TACKOVER_EN      VIA   -     D0100PA00X+006863Y+059995               S1      
327LAN1_P2_P        U137  -20         A01X+006849Y+062391X0320Y0610R090 S2      
327LAN1_P2_N        U137  -19         A01X+006849Y+062891X0320Y0610R090 S2      
327LAN1_P2_R        U137  -21         A01X+006849Y+061891X0320Y0610R090 S2      
327LAN1_P2_R        R1274 -2          A01X+005811Y+061941X0180Y0200R180 S2      
327N54065132        R1274 -1          A01X+005496Y+061941X0180Y0200R180 S2      
327LAN1_P1_R        R1273 -2          A01X+005811Y+061491X0180Y0200R180 S2      
327N54065132        R1273 -1          A01X+005496Y+061491X0180Y0200R180 S2      
317GND              VIA   -     D0100PA00X+006330Y+062176               S3      
317LAN1_P2_P        VIA   -     D0100PA00X+006121Y+062387               S1      
317LAN1_P1_R        VIA   -     D0100PA00X+006357Y+061391               S1      
317LAN1_P2_R        VIA   -     D0100PA00X+006361Y+061892               S1      
317LAN1_P2_N        VIA   -     D0100PA00X+006121Y+062887               S1      
327LAN1_P3_P        U137  -18         A01X+006849Y+063391X0320Y0610R090 S2      
327LAN1_P3_N        U137  -17         A01X+006849Y+063891X0320Y0610R090 S2      
327LAN1_P3_R        U137  -16         A01X+006849Y+064391X0320Y0610R090 S2      
327LAN1_P3_R        R1275 -2          A01X+005690Y+064393X0180Y0200R180 S2      
317GND              VIA   -     D0100PA00X+006349Y+063069               S3      
317UART_RI_P5_L_N   VIA   -     D0100PA00X+006216Y+064409               S3      
317UART_RX_P5_L     VIA   -     D0100PA00X+005939Y+064291               S3      
317NNAME10011       VIA   -     D0100PA00X+005624Y+063008               S1      
317NNAME10013       VIA   -     D0100PA00X+005953Y+063170               S3      
327LAN1_P4_P        U137  -14         A01X+006849Y+065391X0320Y0610R090 S2      
327LAN1_P4_N        U137  -13         A01X+006849Y+065891X0320Y0610R090 S2      
327LAN1_P4_R        U137  -15         A01X+006849Y+064891X0320Y0610R090 S2      
327LAN1_P4_R        R1276 -2          A01X+005690Y+064843X0180Y0200R180 S2      
317LAN1_P3_R        VIA   -     D0100PA00X+006365Y+064696               S1      
317LAN1_P4_R        VIA   -     D0100PA00X+006160Y+065361               S1      
327LAN1_P4_N        VIA   -           A01X+006574Y+071716X0160Y0041R270 S2      
327LAN1_P4_P        VIA   -           A01X+006745Y+072709X0160Y0041R270 S2      
317CM_PWR_CTL_IN    VIA   -     D0100PA00X+006688Y+076163               S3      
317P12V_PDB         VIA   -     D0100PA00X+005926Y+077982               S3      
317P12V_PDB         VIA   -     D0100PA00X+005884Y+078310               S3      
317P12V_PDB         VIA   -     D0100PA00X+006229Y+077963               S3      
317P12V_PDB         VIA   -     D0100PA00X+006766Y+077945               S3      
317P12V_PDB         VIA   -     D0100PA00X+006273Y+078269               S3      
317P12V_PDB         VIA   -     D0100PA00X+006686Y+078272               S3      
317P12V_PDB         VIA   -     D0100PA00X+006037Y+077686               S3      
317P12V_PDB         VIA   -     D0100PA00X+006479Y+077678               S3      
327P12V_PDB         J35   -A80        A10X+005911Y+080787X0300Y1660R180 S1      
327P12V_PDB         J35   -A79        A10X+006305Y+080787X0300Y1660R180 S1      
327P12V_PDB         J35   -A78        A10X+006699Y+080787X0300Y1660R180 S1      
327GND              J35   -A77        A10X+007093Y+080787X0300Y1660R180 S1      
327P12V_PDB         J35   -B80        A01X+005911Y+080787X0300Y1660R180 S2      
327P12V_PDB         J35   -B79        A01X+006305Y+080787X0300Y1660R180 S2      
327CM_PWR_CTL_IN    J35   -B78        A01X+006699Y+080787X0300Y1660R180 S2      
327GND              J35   -B77        A01X+007093Y+080787X0300Y1660R180 S2      
317MATE_R_N         VIA   -     D0100PA00X+005650Y+078967               S3      
317GND              D18   -3    D0400PA00X+008374Y+002071               S0      
317N53608934        D18   -2    D0400PA00X+007874Y+003071               S0      
317NNAME10041       D18   -1    D0400PA00X+007374Y+002071               S0      
327GND              R808  -2          A01X+007936Y+004308X0180Y0200R270 S2      
327N53608934        R808  -1          A01X+007936Y+003993X0180Y0200R270 S2      
317GND              VIA   -     D0100PA00X+007936Y+004604               S3      
317GND              VIA   -     D0100PA00X+008207Y+007322               S3      
317GND              VIA   -     D0100PA00X+008085Y+010686               S3      
317NNAME10026       J34   -1    D0480PA00X+007688Y+014327               S0      
317GND              J34   -2    D0480PA00X+008688Y+014327               S0      
317NNAME10026       VIA   -     D0100PA00X+007688Y+012653               S3      
317GND              VIA   -     D0100PA00X+007289Y+015435               S3      
317NNAME10042       VIA   -     D0100PA00X+007603Y+015615               S1      
327CRT_R            U46   -3          A01X+007621Y+016358X0400Y0500R090 S2      
327P5V_CRT          U46   -2          A01X+008501Y+016758X0400Y0500R090 S2      
327GND              U46   -1          A01X+008501Y+015958X0400Y0500R090 S2      
327CRT_R            R789  -2          A01X+007075Y+017004X0180Y0200R090 S2      
317GND              VIA   -     D0100PA00X+008103Y+017261               S3      
317GND              VIA   -     D0100PA00X+007885Y+015787               S3      
317P5V_CRT          VIA   -     D0100PA00X+008501Y+017168               S3      
317NNAME10027       VIA   -     D0100PA00X+007151Y+016455               S3      
327CRT_DDCDATA      U47   -3          A01X+007794Y+018197X0400Y0500R090 S2      
327P5V_CRT          U47   -2          A01X+008674Y+018597X0400Y0500R090 S2      
327GND              U47   -1          A01X+008674Y+017797X0400Y0500R090 S2      
327GND              R640  -2          A01X+007790Y+017261X0180Y0200R180 S2      
327CRT_R_L          R640  -1          A01X+007475Y+017261X0180Y0200R180 S2      
327NNAME10028       R634  -2          A01X+007173Y+018074X0180Y0200R270 S2      
327P5V_CRT          R634  -1          A01X+007173Y+017759X0180Y0200R270 S2      
327CRT_R_L          R789  -1          A01X+007075Y+017319X0180Y0200R090 S2      
317P5V_CRT          VIA   -     D0100PA00X+007447Y+017567               S3      
317P5V_CRT          VIA   -     D0100PA00X+008255Y+018543               S1      
327CRT_G            U45   -3          A01X+007794Y+019573X0400Y0500R090 S2      
327P5V_CRT          U45   -2          A01X+008674Y+019973X0400Y0500R090 S2      
327GND              U45   -1          A01X+008674Y+019173X0400Y0500R090 S2      
327NNAME10029       C500  -1          A01X+007188Y+019531X0280Y0320     S2      
327GND              C500  -2          A01X+007188Y+020111X0280Y0320     S2      
327GND              R641  -2          A01X+007264Y+018895X0180Y0200R180 S2      
317GND              VIA   -     D0100PA00X+008203Y+019173               S1      
317GND              VIA   -     D0100PA00X+007524Y+018895               S3      
317GND              VIA   -     D0100PA00X+007536Y+020111               S3      
327CRT_HSYNC        U48   -3          A01X+008187Y+020985X0400Y0500R090 S2      
327CRT_B            R659  -2          A01X+007178Y+021203X0180Y0200R090 S2      
327CRT_B_L          R659  -1          A01X+007178Y+021518X0180Y0200R090 S2      
327CRT_B_L          R642  -1          A01X+007176Y+021891X0180Y0200R270 S2      
317GND              VIA   -     D0100PA00X+008588Y+021894               S3      
317GND              VIA   -     D0100PA00X+007819Y+021464               S3      
317P5V_CRT          VIA   -     D0100PA00X+008617Y+021385               S3      
317NNAME10030       VIA   -     D0100PA00X+007556Y+021851               S3      
317VGA_HSYNC        VIA   -     D0100PA00X+007387Y+020576               S1      
327GND              U50   -1          A01X+007448Y+022992X0400Y0500R090 S2      
327CRT_B            U44   -3          A01X+008193Y+022373X0400Y0500R090 S2      
327P5V_CRT          C509  -2          A01X+008546Y+023286X0180Y0200R180 S2      
327GND              C509  -1          A01X+008231Y+023286X0180Y0200R180 S2      
327GND              R642  -2          A01X+007176Y+022206X0180Y0200R270 S2      
317GND              VIA   -     D0100PA00X+007215Y+022515               S3      
317GND              VIA   -     D0100PA00X+007861Y+022992               S3      
317GND              VIA   -     D0100PA00X+007922Y+023286               S3      
317P5V_CRT          VIA   -     D0100PA00X+008339Y+023567               S3      
327P5V_CRT          U50   -2          A01X+007448Y+023792X0400Y0500R090 S2      
327P3V3_NODE1       R633  -1          A01X+008037Y+025068X0180Y0200R270 S2      
327N21581283        R631  -2          A01X+008039Y+024331X0180Y0200R090 S2      
327P3V3_NODE1       R631  -1          A01X+008039Y+024646X0180Y0200R090 S2      
327NNAME10043       Q17   -S          A01X+007477Y+025194X0400Y0500R090 S2      
327N21581283        Q17   -G          A01X+007477Y+024394X0400Y0500R090 S2      
317P5V_CRT          VIA   -     D0100PA00X+007914Y+023792               S3      
317P3V3_NODE1       VIA   -     D0100PA00X+008648Y+024926               S3      
327GND              U49   -1          A01X+007480Y+026758X0400Y0500R180 S2      
327NNAME10043       R633  -2          A01X+008037Y+025383X0180Y0200R270 S2      
317NNAME10031       VIA   -     D0100PA00X+007724Y+026081               S1      
317GND              VIA   -     D0100PA00X+008121Y+026134               S3      
317NNAME10043       VIA   -     D0100PA00X+008117Y+025772               S1      
327N/C              D7    -2          A01X+008348Y+027948X0320Y0360R180 S2      
327P5V_CRT          FS2   -1          A01X+007374Y+027866X0480Y1300R180 S2      
317GND              VIA   -     D0100PA00X+007954Y+026758               S3      
317P5V_CRT          VIA   -     D0100PA00X+007837Y+027603               S1      
317P5V_CRT          VIA   -     D0100PA00X+007822Y+028175               S3      
317P5V_CRT          VIA   -     D0100PA00X+007821Y+027909               S3      
327GND              C498  -2          A01X+007237Y+029058X0180Y0200R090 S2      
327VCC5_CRTXX       C498  -1          A01X+007237Y+029373X0180Y0200R090 S2      
327GND              C497  -2          A01X+008237Y+029373X0180Y0200R270 S2      
327P5V_NODE1        C497  -1          A01X+008237Y+029058X0180Y0200R270 S2      
327VCC5_CRTXX       L38   -1          A01X+007737Y+029506X0280Y0320R180 S2      
327P5V_NODE1        L38   -2          A01X+007737Y+028926X0280Y0320R180 S2      
317VCC5_CRTXX       VIA   -     D0100PA00X+007219Y+029740               S1      
317GND              VIA   -     D0100PA00X+008237Y+029714               S3      
317GND              VIA   -     D0100PA00X+007237Y+028791               S3      
317P5V_NODE1        VIA   -     D0100PA00X+008256Y+028810               S3      
317P5V_NODE1        VIA   -     D0100PA00X+008260Y+028543               S3      
317VCC5_CRTXX       VIA   -     D0100PA00X+007737Y+029921               S1      
327NNAME10006       U134  -5          A01X+008595Y+038357X0220Y0680R180 S2      
327FRU_SYS_A1       R186  -2          A01X+008007Y+038962X0180Y0200R180 S2      
327P3V3_NODE1       R186  -1          A01X+007692Y+038962X0180Y0200R180 S2      
327FRU_SYS_A1       R1153 -2          A01X+008007Y+038572X0180Y0200R180 S2      
327GND              R1153 -1          A01X+007692Y+038572X0180Y0200R180 S2      
317GND              VIA   -     D0100PA00X+007392Y+038572               S3      
317P3V3_NODE1       VIA   -     D0100PA00X+007406Y+038962               S3      
317FRU_SYS_A1       VIA   -     D0100PA00X+008308Y+038962               S1      
327GND              U134  -4          A01X+008595Y+040437X0220Y0680R180 S2      
327FRU_SYS_A2       R1154 -2          A01X+008009Y+039386X0180Y0200R180 S2      
327GND              R1154 -1          A01X+007694Y+039386X0180Y0200R180 S2      
327FRU_SYS_A2       R187  -2          A01X+008009Y+039791X0180Y0200R180 S2      
327P3V3_NODE1       R187  -1          A01X+007694Y+039791X0180Y0200R180 S2      
317GND              VIA   -     D0100PA00X+007403Y+039386               S3      
317P3V3_NODE1       VIA   -     D0100PA00X+007387Y+039791               S3      
317FRU_SYS_A2       VIA   -     D0100PA00X+008325Y+039791               S1      
317GND              VIA   -     D0100PA00X+008595Y+041026               S1      
317P1V05_NODE1      VIA   -     D0100PA00X+008049Y+042069               S3      
317P1V05_NODE1      VIA   -     D0100PA00X+008049Y+042369               S3      
317P1V05_NODE1      VIA   -     D0100PA00X+008605Y+042872               S3      
317P1V05_NODE1      VIA   -     D0100PA00X+008049Y+042669               S3      
317P1V05_NODE1      VIA   -     D0100PA00X+007990Y+043919               S3      
317P1V05_NODE1      VIA   -     D0100PA00X+008605Y+042511               S3      
317P1V05_NODE1      VIA   -     D0100PA00X+008605Y+043747               S3      
317P1V05_NODE1      VIA   -     D0100PA00X+008605Y+043447               S3      
327P1V05_NODE1      PL6   -2          A01X+007750Y+045749X0848Y1300R270 S2      
317P1V05_NODE1      VIA   -     D0100PA00X+007990Y+044519               S3      
317P1V05_NODE1      VIA   -     D0100PA00X+007990Y+044219               S3      
317P1V05_NODE1      VIA   -     D0100PA00X+008562Y+045128               S3      
317P1V05_NODE1      VIA   -     D0100PA00X+008262Y+045128               S3      
317P1V05_NODE1      VIA   -     D0100PA00X+008605Y+044343               S3      
317P1V05_NODE1      VIA   -     D0100PA00X+008605Y+044643               S3      
327NNAME10037       PL6   -1          A01X+007750Y+048052X0848Y1300R270 S2      
317NNAME10037       VIA   -     D0100PA00X+007429Y+048667               S1      
327GND              PQ1   --6-7       A01X+008055Y+049234X0689Y0226R270 S2      
327NNAME10033       PQ1   -8          A01X+008055Y+049746X0170Y0220R270 S2      
327NNAME10037       PQ1   -2_EP       A01X+007462Y+049362X0800Y0990     S2      
317GND              VIA   -     D0100PA00X+008346Y+048949               S3      
317GND              VIA   -     D0100PA00X+008346Y+049199               S3      
317GND              VIA   -     D0100PA00X+008596Y+048949               S3      
317GND              VIA   -     D0100PA00X+008596Y+049199               S3      
317GND              VIA   -     D0100PA00X+008346Y+049449               S3      
317GND              VIA   -     D0100PA00X+008596Y+049449               S3      
317NNAME10033       VIA   -     D0100PA00X+008354Y+049831               S1      
327GND              PC62  -2          A01X+007924Y+051310X0180Y0200R180 S2      
327P1V05_NODE1_EN   PC62  -1          A01X+007609Y+051310X0180Y0200R180 S2      
327NNAME10037       PC60  -2          A01X+007557Y+050399X0180Y0200R090 S2      
327NNAME10036       PC60  -1          A01X+007557Y+050714X0180Y0200R090 S2      
327GND              PR26  -2          A01X+007924Y+051710X0180Y0200R180 S2      
327NNAME10035       PR26  -1          A01X+007609Y+051710X0180Y0200R180 S2      
327P1V05_NODE1_EN   PR23  -2          A01X+008037Y+050917X0180Y0200R270 S2      
327P3V3_NODE1       PR23  -1          A01X+008037Y+050602X0180Y0200R270 S2      
327P1V05_NODE1_EN   PJ6   -2          A01X+008410Y+050916X0180Y0200R270 S2      
327NNAME10044       PJ6   -1          A01X+008410Y+050601X0200Y0400R180 S2      
317GND              VIA   -     D0100PA00X+008164Y+051710               S1      
317GND              VIA   -     D0100PA00X+008164Y+051310               S3      
317P3V3_NODE1       VIA   -     D0100PA00X+008117Y+050359               S3      
317P1V05_NODE1_EN   VIA   -     D0100PA00X+008535Y+051230               S1      
317NNAME10035       VIA   -     D0100PA00X+007306Y+051529               S1      
317NNAME10036       VIA   -     D0100PA00X+007264Y+050899               S1      
327NNAME10034       PR24  -2          A01X+007609Y+052110X0180Y0200     S2      
327P3V3_NODE1       PR24  -1          A01X+007924Y+052110X0180Y0200     S2      
317GND              VIA   -     D0100PA00X+008149Y+053319               S1      
317P3V3_NODE1       VIA   -     D0100PA00X+008164Y+052110               S3      
317NNAME10034       VIA   -     D0100PA00X+008203Y+052393               S3      
327GND              C433  -2          A01X+008583Y+053520X0280Y0320R090 S2      
327GND              C430  -2          A01X+008499Y+054270X0440Y0540     S2      
317GND              VIA   -     D0100PA00X+007222Y+054049               S3      
317GND              VIA   -     D0100PA00X+008032Y+054431               S1      
317GND              VIA   -     D0100PA00X+008159Y+053638               S3      
317GND              VIA   -     D0100PA00X+008032Y+054103               S3      
327P3V3_NODE1       C414  -1          A01X+007755Y+056082X0440Y0540     S2      
327P3V3_NODE1       C393  -1          A01X+007770Y+055297X0440Y0540     S2      
317P3V3_NODE1       VIA   -     D0100PA00X+008499Y+056329               S3      
317P3V3_NODE1       VIA   -     D0100PA00X+008214Y+056076               S3      
317P3V3_NODE1       VIA   -     D0100PA00X+008198Y+055685               S3      
327P3V3_NODE1       C413  -1          A01X+007755Y+057682X0440Y0540     S2      
327P3V3_NODE1       C415  -1          A01X+007755Y+056882X0440Y0540     S2      
327P3V3_NODE1       Q15   -3          A01X+008815Y+057535X0590Y0790R180 S2      
317P3V3_NODE1       VIA   -     D0100PA00X+008152Y+057791               S3      
327P3V3_NODE1       C416  -1          A01X+007918Y+058371X0280Y0320R090 S2      
327GND              C416  -2          A01X+007338Y+058371X0280Y0320R090 S2      
317P3V3_NODE1       VIA   -     D0100PA00X+008303Y+058266               S3      
317P3V3_NODE1       VIA   -     D0100PA00X+008514Y+058521               S3      
317GND              VIA   -     D0100PA00X+007313Y+060160               S3      
317GND              VIA   -     D0100PA00X+007318Y+061118               S3      
317LAN1_P1_N        VIA   -     D0100PA00X+007538Y+060891               S1      
317LAN1_P1_P        VIA   -     D0100PA00X+007538Y+060391               S1      
317GND              VIA   -     D0100PA00X+008063Y+068968               S3      
327LAN1_P3_P        VIA   -           A01X+007217Y+069630X0160Y0041R270 S2      
317GND              VIA   -     D0100PA00X+008285Y+071607               S3      
327LAN1_P3_N        VIA   -           A01X+007046Y+070798X0160Y0041R270 S2      
327LAN1_P2_N        J35   -A76        A10X+007486Y+080787X0300Y1660R180 S1      
327LAN1_P2_P        J35   -A75        A10X+007880Y+080787X0300Y1660R180 S1      
327GND              J35   -A74        A10X+008274Y+080787X0300Y1660R180 S1      
327LAN1_P1_N        J35   -A73        A10X+008667Y+080787X0300Y1660R180 S1      
327LAN1_P4_N        J35   -B76        A01X+007486Y+080787X0300Y1660R180 S2      
327LAN1_P4_P        J35   -B75        A01X+007880Y+080787X0300Y1660R180 S2      
327GND              J35   -B74        A01X+008274Y+080787X0300Y1660R180 S2      
327LAN1_P3_N        J35   -B73        A01X+008667Y+080787X0300Y1660R180 S2      
317GND              VIA   -     D0100PA00X+008274Y+079170               S3      
317GND              VIA   -     D0100PA00X+008274Y+078870               S3      
317GND              VIA   -     D0100PA00X+007093Y+078870               S3      
317GND              VIA   -     D0100PA00X+007093Y+079170               S3      
317GND              VIA   -     D0100PA00X+009783Y+006651               S3      
317GND              H9    -1    D1420UA00X+009843Y+010551               S0      
317GND              VIA   -     D0100PA00X+009853Y+012134               S3      
327N/C                    -1          A01X+010561Y+014753X0390Y0390R270 S2      
327NNAME10028       D8    -3          A01X+009506Y+015981X0320Y0360R180 S2      
327N/C              D8    -2          A01X+009132Y+016769X0320Y0360R180 S2      
327NNAME10042       D8    -1          A01X+009880Y+016769X0320Y0360R180 S2      
317P3V3_NODE1       VIA   -     D0100PA00X+010226Y+016796               S3      
327NNAME10028       Q18   -D          A01X+009745Y+018102X0400Y0500R180 S2      
317GND              VIA   -     D0100PA00X+009088Y+017797               S3      
327NNAME10045       U132  -2          A01X+010140Y+020417X0170Y0520     S2      
327GFX_BUF_EN_N     U132  -1          A01X+009884Y+020417X0170Y0520     S2      
327NNAME10042       Q18   -S          A01X+009345Y+018982X0400Y0500R180 S2      
327N21581283        Q18   -G          A01X+010145Y+018982X0400Y0500R180 S2      
317P5V_CRT          VIA   -     D0100PA00X+009091Y+019973               S3      
317N21581283        VIA   -     D0100PA00X+010145Y+019437               S1      
327P5V_NODE1        U132  -8          A01X+009884Y+021873X0170Y0520     S2      
327GFX_BUF_EN_N     U132  -7          A01X+010140Y+021873X0170Y0520     S2      
327GND              U44   -1          A01X+009073Y+021973X0400Y0500R090 S2      
327P5V_CRT          U48   -2          A01X+009067Y+021385X0400Y0500R090 S2      
327GND              U48   -1          A01X+009067Y+020585X0400Y0500R090 S2      
317GND              VIA   -     D0100PA00X+008656Y+020585               S3      
327P5V_CRT          U44   -2          A01X+009073Y+022773X0400Y0500R090 S2      
327GFX_BUF_EN_N     R658  -2          A01X+009932Y+022584X0180Y0200R180 S2      
327GND              R658  -1          A01X+009617Y+022584X0180Y0200R180 S2      
317GND              VIA   -     D0100PA00X+009617Y+023162               S3      
317N21581283        VIA   -     D0100PA00X+009870Y+023465               S3      
317P5V_NODE1        VIA   -     D0100PA00X+009699Y+022304               S3      
317GFX_BUF_EN_N     VIA   -     D0100PA00X+010102Y+022335               S1      
317N/C              H3    -1    D1180UA00X+010236Y+024724               S0      
317P3V3_NODE1       VIA   -     D0100PA00X+008840Y+024404               S3      
327NNAME10031       D7    -3          A01X+008722Y+027160X0320Y0360R180 S2      
327NNAME10043       D7    -1          A01X+009096Y+027948X0320Y0360R180 S2      
317GND              VIA   -     D0100PA00X+009320Y+030073               S3      
317N/C              H1    -1    D1180UA00X+010236Y+034961               S0      
327GND              C537  -2          A01X+009997Y+037111X0180Y0200R090 S2      
327P3V3_NODE1       C537  -1          A01X+009997Y+037426X0180Y0200R090 S2      
327GND              R1151 -2          A01X+009597Y+037111X0180Y0200R090 S2      
327N43448372        R1151 -1          A01X+009597Y+037426X0180Y0200R090 S2      
317GND              VIA   -     D0100PA00X+009997Y+036771               S3      
317GND              VIA   -     D0100PA00X+009597Y+036781               S3      
317N43448372        VIA   -     D0100PA00X+009595Y+037666               S1      
327P3V3_NODE1       U134  -8          A01X+010095Y+038357X0220Y0680R180 S2      
327N43448372        U134  -7          A01X+009595Y+038357X0220Y0680R180 S2      
327NNAME10004       U134  -6          A01X+009095Y+038357X0220Y0680R180 S2      
327FRU_SYS_A2       U134  -3          A01X+009095Y+040437X0220Y0680R180 S2      
327FRU_SYS_A1       U134  -2          A01X+009595Y+040437X0220Y0680R180 S2      
327FRU_SYS_A0       U134  -1          A01X+010095Y+040437X0220Y0680R180 S2      
327GND              PC61  -2          A01X+009581Y+042007X0180Y0200R180 S2      
327P1V05_NODE1      PC61  -1          A01X+009266Y+042007X0180Y0200R180 S2      
317GND              VIA   -     D0100PA00X+009841Y+042191               S3      
317GND              VIA   -     D0100PA00X+009847Y+041883               S1      
317P1V05_NODE1      VIA   -     D0100PA00X+009003Y+042169               S3      
317P1V05_NODE1      VIA   -     D0100PA00X+009024Y+041862               S3      
327GND              PC68  -2          A01X+009761Y+043594X0440Y0540R180 S2      
327P1V05_NODE1      PC68  -1          A01X+009013Y+043594X0440Y0540R180 S2      
327GND              C55   -2          A10X+009763Y+042694X0440Y0540     S1      
327P1V05_NODE1      C55   -1          A10X+009015Y+042694X0440Y0540     S1      
327GND              C53   -2          A10X+009763Y+043594X0440Y0540     S1      
327P1V05_NODE1      C53   -1          A10X+009015Y+043594X0440Y0540     S1      
327GND              PC66  -2          A01X+009761Y+042694X0440Y0540R180 S2      
327P1V05_NODE1      PC66  -1          A01X+009013Y+042694X0440Y0540R180 S2      
317GND              VIA   -     D0100PA00X+010165Y+042875               S3      
317GND              VIA   -     D0100PA00X+010165Y+042555               S3      
317GND              VIA   -     D0100PA00X+010165Y+043330               S3      
317GND              VIA   -     D0100PA00X+010165Y+043608               S3      
327GND              PC67  -2          A01X+009763Y+044494X0440Y0540R180 S2      
327P1V05_NODE1      PC67  -1          A01X+009015Y+044494X0440Y0540R180 S2      
327GND              C54   -2          A10X+009763Y+044494X0440Y0540     S1      
327P1V05_NODE1      C54   -1          A10X+009015Y+044494X0440Y0540     S1      
317GND              VIA   -     D0100PA00X+010159Y+044620               S3      
317GND              VIA   -     D0100PA00X+010165Y+044304               S3      
317P1V05_NODE1      VIA   -     D0100PA00X+008862Y+045128               S3      
317GND              VIA   -     D0100PA00X+008673Y+050200               S3      
317GND              VIA   -     D0100PA00X+008856Y+049198               S3      
317GND              VIA   -     D0100PA00X+008856Y+048948               S3      
317GND              VIA   -     D0100PA00X+008856Y+049448               S3      
317NNAME10033       VIA   -     D0100PA00X+008670Y+049818               S3      
327GND              R1239 -2          A01X+009146Y+050920X0180Y0200R270 S2      
327NNAME10044       R1239 -1          A01X+009146Y+050605X0180Y0200R270 S2      
317GND              VIA   -     D0100PA00X+009146Y+051185               S1      
317NNAME10044       VIA   -     D0100PA00X+008772Y+050582               S3      
317P1V9_LAN1        VIA   -     D0100PA00X+009242Y+053108               S1      
317P1V9_LAN1        VIA   -     D0100PA00X+009566Y+053136               S3      
317P1V9_LAN1        VIA   -     D0100PA00X+009880Y+053160               S1      
327P1V9_LAN1        C433  -1          A01X+009163Y+053520X0280Y0320R090 S2      
327P1V9_LAN1        C431  -1          A01X+010224Y+054270X0440Y0540R180 S2      
327P1V9_LAN1        C430  -1          A01X+009247Y+054270X0440Y0540     S2      
327P1V9_LAN1        Q15   -4          A01X+009715Y+055305X0790Y1500R270 S2      
317P1V9_LAN1        VIA   -     D0100PA00X+009727Y+053706               S1      
317P1V9_LAN1        VIA   -     D0100PA00X+009737Y+054290               S3      
327P1V9_LAN1        Q15   -2          A01X+009715Y+057535X0590Y0790R180 S2      
317P3V3_NODE1       VIA   -     D0100PA00X+008820Y+056811               S3      
327P3V3_NODE1       R564  -1          A01X+009172Y+058708X0280Y0320R270 S2      
327LAN1_CTRL_P1V9   R564  -2          A01X+009752Y+058708X0280Y0320R270 S2      
327LAN1_MDI0_DP     U137  -1          A01X+010373Y+060391X0320Y0610R090 S2      
327LAN1_MDI0_DN     U137  -2          A01X+010373Y+060891X0320Y0610R090 S2      
327P1V9_LAN1        U137  -3          A01X+010373Y+061391X0320Y0610R090 S2      
327LAN1_MDI1_DP     U137  -5          A01X+010373Y+062391X0320Y0610R090 S2      
327LAN1_MDI1_DN     U137  -6          A01X+010373Y+062891X0320Y0610R090 S2      
327P1V9_LAN1        U137  -4          A01X+010373Y+061891X0320Y0610R090 S2      
317P1V9_LAN1        VIA   -     D0100PA00X+009837Y+061925               S3      
317P1V9_LAN1        VIA   -     D0100PA00X+009407Y+061899               S3      
317P1V9_LAN1        VIA   -     D0100PA00X+009407Y+061384               S3      
317P1V9_LAN1        VIA   -     D0100PA00X+009779Y+061380               S3      
317P1V9_LAN1        VIA   -     D0100PA00X+009620Y+061633               S1      
327LAN1_MDI2_DP     U137  -7          A01X+010373Y+063391X0320Y0610R090 S2      
327LAN1_MDI2_DN     U137  -8          A01X+010373Y+063891X0320Y0610R090 S2      
327P1V9_LAN1        U137  -9          A01X+010373Y+064391X0320Y0610R090 S2      
317P1V9_LAN1        VIA   -     D0100PA00X+009535Y+064409               S3      
327LAN1_MDI3_DP     U137  -11         A01X+010373Y+065391X0320Y0610R090 S2      
327LAN1_MDI3_DN     U137  -12         A01X+010373Y+065891X0320Y0610R090 S2      
327P1V9_LAN1        U137  -10         A01X+010373Y+064891X0320Y0610R090 S2      
317P1V9_LAN1        VIA   -     D0100PA00X+009531Y+064748               S1      
317P1V9_LAN1        VIA   -     D0100PA00X+009848Y+064622               S3      
317P1V9_LAN1        VIA   -     D0100PA00X+009841Y+064888               S3      
317GND              VIA   -     D0100PA00X+009841Y+068054               S3      
317GND              H8    -1    D1420UA00X+009843Y+071969               S0      
317GND              VIA   -     D0100PA00X+010022Y+073321               S3      
317CM_PWR_CTL_IN    VIA   -     D0100PA00X+008981Y+076591               S3      
317NNAME10000       VIA   -     D0100PA00X+009739Y+076644               S3      
317N/C              VIA   -     D0100PA00X+009859Y+078249               S3      
317GND27            VIA   -     D0100PA00X+009718Y+078647               S1      
327LAN1_P1_P        J35   -A72        A10X+009061Y+080787X0300Y1660R180 S1      
327GND              J35   -A71        A10X+009455Y+080787X0300Y1660R180 S1      
327GND27            J35   -A70        A10X+009848Y+080787X0300Y1660R180 S1      
327N/C              J35   -A69        A10X+010242Y+080787X0300Y1660R180 S1      
327LAN1_P3_P        J35   -B72        A01X+009061Y+080787X0300Y1660R180 S2      
327GND              J35   -B71        A01X+009455Y+080787X0300Y1660R180 S2      
327N/C              J35   -B70        A01X+009848Y+080787X0300Y1660R180 S2      
327GND62            J35   -B69        A01X+010242Y+080787X0300Y1660R180 S2      
317GND              VIA   -     D0100PA00X+009455Y+078870               S3      
317GND              VIA   -     D0100PA00X+009455Y+079170               S3      
317GND              VIA   -     D0100PA00X+011239Y+007187               S3      
317GND              VIA   -     D0100PA00X+011563Y+010441               S3      
327P3V3_NODE1       R632  -1          A01X+010226Y+017205X0180Y0200R270 S2      
317NNAME10019       VIA   -     D0100PA00X+011122Y+016092               S1      
317NNAME10017       VIA   -     D0100PA00X+010609Y+016762               S1      
327NNAME10042       R632  -2          A01X+010226Y+017520X0180Y0200R270 S2      
317NNAME10025       VIA   -     D0100PA00X+011253Y+018636               S1      
317UART_TX_P2_L     VIA   -     D0100PA00X+010676Y+017537               S1      
317NNAME10018       VIA   -     D0100PA00X+011492Y+017908               S1      
327GND              U132  -4          A01X+010652Y+020417X0170Y0520     S2      
327VGA_HSYNC        U132  -3          A01X+010396Y+020417X0170Y0520     S2      
317UART_RX_P2_L     VIA   -     D0100PA00X+010891Y+019319               S1      
327NNAME10046       U132  -5          A01X+010652Y+021873X0170Y0520     S2      
327VGA_VSYNC        U132  -6          A01X+010396Y+021873X0170Y0520     S2      
317GND              VIA   -     D0100PA00X+010652Y+021080               S3      
317NNAME10046       VIA   -     D0100PA00X+010455Y+026236               S3      
317NNAME10045       VIA   -     D0100PA00X+010427Y+026566               S3      
317NNAME10038       VIA   -     D0100PA00X+011023Y+036074               S3      
317P3V3_NODE1       VIA   -     D0100PA00X+010315Y+037334               S3      
317NNAME10021       VIA   -     D0100PA00X+011023Y+036324               S3      
327FRU_SYS_A0       R1152 -2          A01X+011062Y+039202X0180Y0200     S2      
327GND              R1152 -1          A01X+011377Y+039202X0180Y0200     S2      
327FRU_SYS_A0       R180  -2          A01X+011062Y+038798X0180Y0200     S2      
327P3V3_NODE1       R180  -1          A01X+011377Y+038798X0180Y0200     S2      
317P3V3_NODE1       VIA   -     D0100PA00X+011703Y+038998               S3      
327P1V8_STB_NODE1   C818  -1          A10X+011876Y+040961X0440Y0540R090 S1      
327GND              C817  -2          A01X+011362Y+039818X0180Y0200R090 S2      
327P5V_STB_NODE1    C817  -1          A01X+011362Y+040133X0180Y0200R090 S2      
327NNAME10047       R1106 -2          A01X+010939Y+040638X0180Y0200R180 S2      
327GND              R1106 -1          A01X+010624Y+040638X0180Y0200R180 S2      
317GND              VIA   -     D0100PA00X+011049Y+039736               S3      
317GND              VIA   -     D0100PA00X+011696Y+039402               S1      
317P5V_STB_NODE1    VIA   -     D0100PA00X+010375Y+040274               S3      
317P5V_STB_NODE1    VIA   -     D0100PA00X+010381Y+040588               S3      
317P5V_STB_NODE1    VIA   -     D0100PA00X+010387Y+039960               S3      
317P5V_STB_NODE1    VIA   -     D0100PA00X+010824Y+040102               S3      
317P5V_STB_NODE1    VIA   -     D0100PA00X+011112Y+040108               S3      
317P1V8_STB_NODE1   VIA   -     D0100PA00X+011573Y+040584               S3      
317P1V8_STB_NODE1   VIA   -     D0100PA00X+011341Y+040483               S3      
327P1V8_STB_NODE1   VIA   -           A10X+011450Y+040126X0260Y0260     S1      
317P1V8_STB_NODE1   VIA   -     D0100PA00X+011350Y+040767               S3      
317FRU_SYS_A0       VIA   -     D0100PA00X+010753Y+039402               S1      
327GND              C818  -2          A10X+011876Y+041709X0440Y0540R090 S1      
327GND              C819  -2          A01X+010934Y+041350X0180Y0200R270 S2      
327NNAME10047       C819  -1          A01X+010934Y+041035X0180Y0200R270 S2      
317GND              VIA   -     D0100PA00X+011421Y+041791               S3      
317GND              VIA   -     D0100PA00X+011421Y+041491               S3      
317GND              VIA   -     D0100PA00X+010567Y+041126               S3      
327GND              C97   -2          A10X+011386Y+045364X0440Y0540     S1      
327P1V05_NODE1      C97   -1          A10X+010638Y+045364X0440Y0540     S1      
317GND              VIA   -     D0100PA00X+011798Y+045198               S3      
317GND              VIA   -     D0100PA00X+011802Y+045508               S3      
327GND              C96   -2          A10X+011698Y+046182X0460Y0620     S1      
327P1V05_NODE1      C96   -1          A10X+010538Y+046182X0460Y0620     S1      
327GND              C829  -2          A01X+011207Y+048376X0180Y0200R090 S2      
327NNAME10048       C829  -1          A01X+011207Y+048691X0180Y0200R090 S2      
327NNAME10048       R1233 -2          A01X+010803Y+048686X0180Y0200R270 S2      
327GND              R1233 -1          A01X+010803Y+048371X0180Y0200R270 S2      
317GND              VIA   -     D0100PA00X+011407Y+048096               S3      
317P1V8_NODE1       VIA   -     D0100PA00X+011552Y+048570               S3      
327NNAME10048       U121  -6          A01X+011670Y+049313X0110Y0360     S2      
327GND              U121  -TH         A01X+012064Y+049923X0690Y1050R270 S2      
317GND              VIA   -     D0100PA00X+011040Y+050222               S3      
317GND              VIA   -     D0100PA00X+011044Y+049968               S3      
317GND              VIA   -     D0100PA00X+011047Y+049689               S3      
317GND              VIA   -     D0100PA00X+011334Y+050208               S3      
317GND              VIA   -     D0100PA00X+011337Y+049689               S3      
317GND              VIA   -     D0100PA00X+011330Y+049957               S3      
317P1V8_NODE1       VIA   -     D0100PA00X+011703Y+048832               S3      
317NNAME10048       VIA   -     D0100PA00X+010803Y+049250               S3      
327NNAME10049       C834  -2          A01X+011437Y+051256X0180Y0200R090 S2      
327GND              C834  -1          A01X+011437Y+051571X0180Y0200R090 S2      
327NNAME10049       R1094 -2          A01X+010997Y+051256X0180Y0200R090 S2      
327P3V3_STB_NODE1   R1094 -1          A01X+010997Y+051571X0180Y0200R090 S2      
327NNAME10049       U121  -5          A01X+011670Y+050533X0110Y0360     S2      
317GND              VIA   -     D0100PA00X+011437Y+051890               S3      
317NNAME10049       VIA   -     D0100PA00X+010997Y+050932               S1      
317GND              VIA   -     D0100PA00X+011258Y+053293               S3      
317P3V3_STB_NODE1   VIA   -     D0100PA00X+010997Y+051951               S3      
327P1V9_LAN1        C432  -1          A01X+010308Y+053520X0280Y0320R270 S2      
327GND              C432  -2          A01X+010888Y+053520X0280Y0320R270 S2      
327GND              C431  -2          A01X+010972Y+054270X0440Y0540R180 S2      
317GND              VIA   -     D0100PA00X+011391Y+054114               S3      
317GND              VIA   -     D0100PA00X+011401Y+054436               S3      
317GND              VIA   -     D0100PA00X+011263Y+053670               S3      
327P1V9_LAN1        C429  -2          A01X+011617Y+056284X0280Y0320R180 S2      
327NNAME10050       C429  -1          A01X+011617Y+056864X0280Y0320R180 S2      
327NNAME10050       R565  -2          A01X+011638Y+057673X0460Y0620R090 S2      
327LAN1_CTRL_P1V9   Q15   -1          A01X+010615Y+057535X0590Y0790R180 S2      
327LAN1_CTRL_P1V9   R565  -1          A01X+011638Y+058833X0460Y0620R090 S2      
327GND              C514  -2          A10X+010564Y+061192X0180Y0200     S1      
327P1V9_LAN1        C514  -1          A10X+010249Y+061192X0180Y0200     S1      
317GND              VIA   -     D0100PA00X+010964Y+061189               S3      
327LAN1_MDI0_DP     VIA   -           A01X+011515Y+060556X0160Y0041     S2      
327GND              C512  -2          A10X+010564Y+061642X0180Y0200     S1      
327P1V9_LAN1        C512  -1          A10X+010249Y+061642X0180Y0200     S1      
327GND              C513  -2          A10X+010564Y+062092X0180Y0200     S1      
327P1V9_LAN1        C513  -1          A10X+010249Y+062092X0180Y0200     S1      
317GND              VIA   -     D0100PA00X+010941Y+062143               S3      
317GND              VIA   -     D0100PA00X+010950Y+061672               S3      
327LAN1_MDI1_DN     VIA   -           A01X+011052Y+062727X0160Y0041     S2      
327GND              C510  -2          A10X+010537Y+064435X0180Y0200     S1      
327P1V9_LAN1        C510  -1          A10X+010222Y+064435X0180Y0200     S1      
327LAN1_MDI2_DP     VIA   -           A01X+011327Y+063556X0160Y0041     S2      
317GND              VIA   -     D0100PA00X+010926Y+064469               S3      
327GND              C511  -2          A10X+010541Y+064862X0180Y0200     S1      
327P1V9_LAN1        C511  -1          A10X+010226Y+064862X0180Y0200     S1      
317GND              VIA   -     D0100PA00X+010926Y+064899               S3      
327LAN1_MDI3_DN     VIA   -           A01X+011112Y+065727X0160Y0041     S2      
317GND              VIA   -     D0100PA00X+011779Y+066724               S3      
317GND              VIA   -     D0100PA00X+011575Y+071628               S3      
317N/C              VIA   -     D0100PA00X+010636Y+078579               S3      
317N/C              VIA   -     D0100PA00X+010242Y+078219               S3      
317N/C              VIA   -     D0100PA00X+011030Y+078573               S3      
317N/C              VIA   -     D0100PA00X+011030Y+078219               S3      
317NNAME10051       VIA   -     D0100PA00X+011637Y+078594               S3      
317MATE_R_N         VIA   -     D0100PA00X+010430Y+077310               S3      
317GND61            VIA   -     D0100PA00X+010665Y+077958               S1      
317GND62            VIA   -     D0100PA00X+010242Y+078594               S1      
327N/C              J35   -A68        A10X+010636Y+080787X0300Y1660R180 S1      
327N/C              J35   -A67        A10X+011030Y+080787X0300Y1660R180 S1      
327GND              J35   -A66        A10X+011423Y+080787X0300Y1660R180 S1      
327NNAME10019       J35   -A65        A10X+011817Y+080787X0300Y1660R180 S1      
327GND61            J35   -B68        A01X+010636Y+080787X0300Y1660R180 S2      
327N/C              J35   -B67        A01X+011030Y+080787X0300Y1660R180 S2      
327GND              J35   -B66        A01X+011423Y+080787X0300Y1660R180 S2      
327NNAME10051       J35   -B65        A01X+011817Y+080787X0300Y1660R180 S2      
317GND              VIA   -     D0100PA00X+011423Y+079170               S3      
317GND              VIA   -     D0100PA00X+011423Y+078870               S3      
317GND              VIA   -     D0100PA00X+012986Y+001457               S3      
317NNAME10052       VIA   -     D0100PA00X+013020Y+001916               S3      
317GND              VIA   -     D0100PA00X+013147Y+004344               S3      
317NNAME10007       VIA   -     D0100PA00X+013107Y+007659               S1      
317P5V_NODE1        VIA   -     D0100PA00X+012622Y+008036               S3      
317P5V_NODE1        VIA   -     D0100PA00X+012622Y+008329               S3      
317UART_DTR_P5_N    VIA   -     D0100PA00X+012548Y+009116               S3      
317UART_RI_P5_N     VIA   -     D0100PA00X+013240Y+008815               S3      
317UART_TX_P5       VIA   -     D0100PA00X+012958Y+008684               S3      
317UART_DSR_P5_N    VIA   -     D0100PA00X+012978Y+009258               S3      
317UART_RTS_P5_N    VIA   -     D0100PA00X+012415Y+009464               S3      
317UART_CTS_P5_N    VIA   -     D0100PA00X+012833Y+009836               S3      
327GND              J2    -G1         A01X+013602Y+014587X1820Y1850     S2      
317GND              VIA   -     D0100PA00X+013035Y+013040               S3      
317GND              VIA   -     D0100PA00X+013035Y+013417               S3      
317GND              VIA   -     D0100PA00X+012646Y+025016               S3      
317NNAME10053       VIA   -     D0100PA00X+012965Y+025041               S1      
317GND              VIA   -     D0100PA00X+012657Y+025619               S3      
317NNAME10054       VIA   -     D0100PA00X+012965Y+025541               S1      
317GND              VIA   -     D0100PA00X+012966Y+027989               S3      
317GND              VIA   -     D0100PA00X+013031Y+026917               S3      
317NNAME10055       VIA   -     D0100PA00X+013032Y+027210               S3      
317NNAME10056       VIA   -     D0100PA00X+013032Y+027710               S3      
317GND              VIA   -     D0100PA00X+012316Y+028706               S3      
317GND              VIA   -     D0100PA00X+012961Y+028712               S3      
317NNAME10057       VIA   -     D0100PA00X+012396Y+028370               S3      
317NNAME10058       VIA   -     D0100PA00X+012896Y+028370               S3      
317NNAME10004       VIA   -     D0100PA00X+012505Y+038455               S3      
317NNAME10006       VIA   -     D0100PA00X+012212Y+038674               S3      
317NNAME10026       VIA   -     D0100PA00X+012630Y+039037               S3      
327P1V5_SUS_NODE1   C820  -1          A10X+013276Y+040915X0440Y0540R090 S1      
327P5V_STB_NODE1    U120  -10         A01X+011904Y+040242X0110Y0360R090 S2      
327P1V5_SUS_NODE1   U120  -1          A01X+013125Y+040242X0110Y0360R090 S2      
327P1V8_STB_NODE1   U120  -9          A01X+011904Y+040439X0110Y0360R090 S2      
327P1V8_STB_NODE1   U120  -8          A01X+011904Y+040636X0110Y0360R090 S2      
327P1V5_SUS_NODE1   U120  -3          A01X+013125Y+040636X0110Y0360R090 S2      
327P1V5_SUS_NODE1   U120  -2          A01X+013125Y+040439X0110Y0360R090 S2      
327GND              U120  -TH         A01X+012514Y+040636X0690Y1050R180 S2      
317GND              VIA   -     D0100PA00X+012273Y+039800               S3      
317GND              VIA   -     D0100PA00X+012773Y+039800               S3      
317GND              VIA   -     D0100PA00X+012523Y+039800               S3      
327P1V8_STB_NODE1   VIA   -           A10X+012014Y+040110X0260Y0260     S1      
327P1V5_SUS_NODE1   VIA   -           A10X+012662Y+040144X0260Y0260     S1      
327P1V5_SUS_NODE1   VIA   -           A10X+013234Y+040128X0260Y0260     S1      
327P1V5_SUS_NODE1   VIA   -           A10X+013290Y+039486X0260Y0260     S1      
327GND              C820  -2          A10X+013276Y+041663X0440Y0540R090 S1      
327NNAME10059       C824  -2          A01X+013216Y+041815X0180Y0200R180 S2      
327GND              C824  -1          A01X+012901Y+041815X0180Y0200R180 S2      
327NNAME10059       R1087 -2          A01X+013218Y+042232X0180Y0200R180 S2      
327P3V3_STB_NODE1   R1087 -1          A01X+012903Y+042232X0180Y0200R180 S2      
327NNAME10047       U120  -6          A01X+011904Y+041030X0110Y0360R270 S2      
327NNAME10059       U120  -5          A01X+013125Y+041030X0110Y0360R270 S2      
327P1V8_STB_NODE1   U120  -7          A01X+011904Y+040833X0110Y0360R090 S2      
327NNAME10060       U120  -4          A01X+013125Y+040833X0110Y0360R090 S2      
317GND              VIA   -     D0100PA00X+012823Y+041393               S3      
317GND              VIA   -     D0100PA00X+012573Y+041393               S3      
317GND              VIA   -     D0100PA00X+012323Y+041393               S3      
317P3V3_STB_NODE1   VIA   -     D0100PA00X+012903Y+042559               S3      
327P1V5_SUS_NODE1   Q39   -5          A01X+013811Y+044942X1264Y0898R090 S2      
327GND              C850  -2          A01X+012970Y+046274X0180Y0200     S2      
327NNAME10061       C850  -1          A01X+013285Y+046274X0180Y0200     S2      
327P3V3_STB_NODE1   R1117 -2          A01X+012970Y+047074X0180Y0200     S2      
327NNAME10062       R1117 -1          A01X+013285Y+047074X0180Y0200     S2      
327P3V3_STB_NODE1   R1116 -2          A01X+012970Y+046674X0180Y0200     S2      
327NNAME10061       R1116 -1          A01X+013285Y+046674X0180Y0200     S2      
327NNAME10061       R1240 -2          A01X+013285Y+045873X0180Y0200R180 S2      
327GND              R1240 -1          A01X+012970Y+045873X0180Y0200R180 S2      
317GND              VIA   -     D0100PA00X+012108Y+046006               S3      
317GND              VIA   -     D0100PA00X+012404Y+045975               S3      
317GND              VIA   -     D0100PA00X+012706Y+046004               S3      
317P3V3_STB_NODE1   VIA   -     D0100PA00X+012638Y+046674               S3      
317P3V3_STB_NODE1   VIA   -     D0100PA00X+012626Y+047027               S3      
327GND              C828  -2          A01X+012007Y+047709X0440Y0540R090 S2      
327P1V8_NODE1       C828  -1          A01X+012007Y+048457X0440Y0540R090 S2      
327GND              C827  -2          A01X+012607Y+048376X0180Y0200R090 S2      
327P5V_STB_NODE1    C827  -1          A01X+012607Y+048691X0180Y0200R090 S2      
317GND              VIA   -     D0100PA00X+012136Y+047203               S3      
317GND              VIA   -     D0100PA00X+011872Y+047199               S3      
317GND              VIA   -     D0100PA00X+012607Y+048086               S3      
327GND              C830  -2          A01X+013215Y+049769X0440Y0540R090 S2      
327GND              C831  -2          A10X+013214Y+049768X0440Y0540R270 S1      
327P5V_STB_NODE1    U121  -10         A01X+012457Y+049313X0110Y0360R180 S2      
327P1V8_NODE1       U121  -9          A01X+012260Y+049313X0110Y0360R180 S2      
327P1V8_NODE1       U121  -8          A01X+012064Y+049313X0110Y0360R180 S2      
327P1V8_NODE1       U121  -7          A01X+011867Y+049313X0110Y0360R180 S2      
317GND              VIA   -     D0100PA00X+013079Y+049391               S3      
317GND              VIA   -     D0100PA00X+013373Y+049391               S3      
317P5V_STB_NODE1    VIA   -     D0100PA00X+012771Y+048943               S3      
317P5V_STB_NODE1    VIA   -     D0100PA00X+012511Y+048943               S3      
317P1V8_NODE1       VIA   -     D0100PA00X+011933Y+048971               S3      
317P1V8_NODE1       VIA   -     D0100PA00X+012197Y+048848               S3      
327NNAME10063       C830  -1          A01X+013215Y+050517X0440Y0540R090 S2      
327NNAME10063       C831  -1          A10X+013214Y+050516X0440Y0540R270 S1      
327NNAME10064       PR17  -2          A01X+011883Y+051383X0180Y0200     S2      
327GND              PR17  -1          A01X+012198Y+051383X0180Y0200     S2      
327NNAME10063       U121  -1          A01X+012457Y+050533X0110Y0360R180 S2      
327NNAME10064       U121  -4          A01X+011867Y+050533X0110Y0360R180 S2      
327NNAME10063       U121  -3          A01X+012064Y+050533X0110Y0360R180 S2      
327NNAME10063       U121  -2          A01X+012260Y+050533X0110Y0360R180 S2      
317GND              VIA   -     D0100PA00X+012202Y+051635               S3      
317NNAME10064       VIA   -     D0100PA00X+011812Y+051081               S1      
317NNAME10063       VIA   -     D0100PA00X+013314Y+051011               S3      
317NNAME10063       VIA   -     D0100PA00X+012164Y+050940               S3      
317NNAME10063       VIA   -     D0100PA00X+013060Y+051004               S3      
317NNAME10063       VIA   -     D0100PA00X+012465Y+050940               S3      
317NNAME10063       VIA   -     D0100PA00X+013070Y+051255               S3      
317NNAME10063       VIA   -     D0100PA00X+013084Y+051513               S3      
317NNAME10063       VIA   -     D0100PA00X+012809Y+051387               S3      
327NNAME10065       C833  -2          A01X+012185Y+052303X0180Y0200R180 S2      
327NNAME10064       C833  -1          A01X+011870Y+052303X0180Y0200R180 S2      
327NNAME10065       R1095 -2          A01X+012188Y+051903X0180Y0200R180 S2      
327NNAME10064       R1095 -1          A01X+011873Y+051903X0180Y0200R180 S2      
327NNAME10063       J22   -2          A01X+013055Y+052290X0180Y0200R180 S2      
327NNAME10065       J22   -1          A01X+012740Y+052290X0200Y0400R090 S2      
317NNAME10065       VIA   -     D0100PA00X+012428Y+052369               S1      
317GND              VIA   -     D0100PA00X+013296Y+055001               S3      
317GND              VIA   -     D0100PA00X+012534Y+055809               S3      
317NNAME10050       VIA   -     D0100PA00X+012030Y+057251               S1      
317LAN1_CTRL_P1V9   VIA   -     D0100PA00X+013359Y+058844               S3      
317LAN1_CTRL_P1V9   VIA   -     D0100PA00X+013079Y+059561               S3      
327GND              C794  -2          A01X+012447Y+067587X0180Y0200     S2      
327NNAME10066       C794  -1          A01X+012762Y+067587X0180Y0200     S2      
327NNAME10066       R1281 -2          A01X+012762Y+067088X0180Y0200R180 S2      
327CM_PWR_CTL_IN    R1281 -1          A01X+012447Y+067088X0180Y0200R180 S2      
327GND              R1251 -2          A01X+012095Y+066564X0180Y0200     S2      
327NNAME10066       R1251 -1          A01X+012410Y+066564X0180Y0200     S2      
327GND              U109  -S          A01X+013345Y+066746X0400Y0500R270 S2      
327NNAME10066       U109  -G          A01X+013345Y+067546X0400Y0500R270 S2      
317GND              VIA   -     D0100PA00X+012824Y+066658               S3      
317GND              VIA   -     D0100PA00X+012091Y+067449               S3      
317CPU_RSV_1        VIA   -     D0100PA00X+013219Y+066262               S3      
317CM_PWR_CTL_IN    VIA   -     D0100PA00X+012107Y+067051               S1      
317NNAME10066       VIA   -     D0100PA00X+013205Y+067182               S1      
327GND              C779  -2          A01X+012961Y+068921X0180Y0200R090 S2      
317GND              VIA   -     D0100PA00X+012961Y+068674               S3      
317NNAME10067       VIA   -     D0100PA00X+013361Y+068670               S1      
317NNAME10068       VIA   -     D0100PA00X+013026Y+067984               S1      
327AGND_HSC_NODE1   U100  -8          A01X+013244Y+069986X0110Y0570R180 S2      
327NNAME10069       U100  -7          A01X+013047Y+069986X0110Y0570R180 S2      
327NNAME10068       U100  -6          A01X+012850Y+069986X0110Y0570R180 S2      
327NNAME10070       C779  -1          A01X+012961Y+069236X0180Y0200R090 S2      
317AGND_HSC_NODE1   VIA   -     D0100PA00X+013244Y+070473               S1      
317NNAME10070       VIA   -     D0100PA00X+013349Y+069547               S1      
327NNAME10071       U100  -5          A01X+012850Y+071738X0110Y0570R180 S2      
327AGND_HSC_NODE1   U100  -4          A01X+013047Y+071738X0110Y0570R180 S2      
327P12V_AUX_EN      U100  -3          A01X+013244Y+071738X0110Y0570R180 S2      
327NNAME10071       VIA   -           A10X+013196Y+072094X0260Y0260     S1      
317NNAME10071       VIA   -     D0100PA00X+012622Y+072095               S3      
327AGND_HSC_NODE1   C778  -2          A01X+012918Y+072975X0180Y0200     S2      
327P12V_AUX_EN      C778  -1          A01X+013233Y+072975X0180Y0200     S2      
327NNAME10071       C780  -1          A01X+012463Y+072698X0280Y0320     S2      
327AGND_HSC_NODE1   C780  -2          A01X+012463Y+073278X0280Y0320     S2      
327AGND_HSC_NODE1   R1022 -2          A01X+012918Y+072525X0180Y0200     S2      
327P12V_AUX_EN      R1022 -1          A01X+013233Y+072525X0180Y0200     S2      
327UART_RI_P6_L_N   R1331 -2          A10X+012693Y+073910X0180Y0200R180 S1      
327NNAME10072       R1331 -1          A10X+013008Y+073910X0180Y0200R180 S1      
327AGND_HSC_NODE1   R1025 -1          A01X+013010Y+073807X0280Y0320R090 S2      
327GND              R1025 -2          A01X+012430Y+073807X0280Y0320R090 S2      
317GND              VIA   -     D0100PA00X+012036Y+073889               S3      
317P12V_AUX_EN      VIA   -     D0100PA00X+013233Y+073298               S3      
327NNAME10073       R1332 -2          A10X+013008Y+074320X0180Y0200     S1      
327UART_RI_P5_L_N   R1332 -1          A10X+012693Y+074320X0180Y0200     S1      
317GND              VIA   -     D0100PA00X+012032Y+074219               S3      
317GND              VIA   -     D0100PA00X+012352Y+074203               S3      
317UART_RI_P6_L_N   VIA   -     D0100PA00X+011990Y+075402               S1      
317UART_RI_P5_L_N   VIA   -     D0100PA00X+012560Y+075900               S1      
327NNAME10072       VIA   -           A10X+013190Y+076090X0260Y0260     S1      
317UART_TX_P1_L     VIA   -     D0100PA00X+012596Y+078570               S1      
317NNAME10074       VIA   -     D0100PA00X+012009Y+078062               S1      
317UART_RX_P1_L     VIA   -     D0100PA00X+013085Y+078246               S3      
317NNAME10019       VIA   -     D0100PA00X+011817Y+078386               S3      
317UART_RX_P2_L     VIA   -     D0100PA00X+013066Y+078560               S3      
317UART_TX_P2_L     VIA   -     D0100PA00X+012729Y+078198               S3      
317NNAME10017       VIA   -     D0100PA00X+012272Y+078505               S3      
327NNAME10017       J35   -A64        A10X+012211Y+080787X0300Y1660R180 S1      
327UART_TX_P2_L     J35   -A63        A10X+012604Y+080787X0300Y1660R180 S1      
327UART_RX_P2_L     J35   -A62        A10X+012998Y+080787X0300Y1660R180 S1      
327NNAME10025       J35   -A61        A10X+013392Y+080787X0300Y1660R180 S1      
327NNAME10074       J35   -B64        A01X+012211Y+080787X0300Y1660R180 S2      
327UART_TX_P1_L     J35   -B63        A01X+012604Y+080787X0300Y1660R180 S2      
327UART_RX_P1_L     J35   -B62        A01X+012998Y+080787X0300Y1660R180 S2      
327NNAME10075       J35   -B61        A01X+013392Y+080787X0300Y1660R180 S2      
327NNAME10076       Q43   -3          A01X+014420Y+001516X0400Y0500R270 S2      
327GND              Q43   -2          A01X+013540Y+001116X0400Y0500R270 S2      
327NNAME10052       Q43   -1          A01X+013540Y+001916X0400Y0500R270 S2      
327GND              PC86  -1          A01X+014170Y+002549X0280Y0320     S2      
327NNAME10077       PR31  -2          A01X+014638Y+002737X0180Y0200R270 S2      
327P3V3_STB_NODE1   PR31  -1          A01X+014638Y+002422X0180Y0200R270 S2      
317GND              VIA   -     D0100PA00X+013750Y+002549               S3      
317NNAME10076       VIA   -     D0100PA00X+014149Y+001927               S1      
317NNAME10078       VIA   -     D0100PA00X+013787Y+002955               S1      
317NNAME10077       VIA   -     D0100PA00X+014743Y+003037               S3      
317P3V3_STB_NODE1   VIA   -     D0100PA00X+014638Y+002035               S3      
327NNAME10079       PU7   -5          A01X+014378Y+003741X0070Y0360R270 S2      
327NNAME10080       PU7   -4          A01X+014378Y+003898X0070Y0360R270 S2      
327NNAME10080       PU7   -3          A01X+014378Y+004056X0070Y0360R270 S2      
327NNAME10080       PU7   -2          A01X+014378Y+004213X0070Y0360R270 S2      
327NNAME10081       PU7   -1          A01X+014378Y+004371X0070Y0360R270 S2      
327NNAME10077       PU7   -7          A01X+014836Y+003440X0070Y0360     S2      
327NNAME10078       PU7   -6          A01X+014678Y+003440X0070Y0360     S2      
327NNAME10082       PU7   -20         A01X+014678Y+004671X0070Y0360     S2      
327NNAME10083       PU7   -19         A01X+014836Y+004671X0070Y0360     S2      
327GND              PU7   -TH         A01X+014993Y+004056X0710Y0710R090 S2      
327NNAME10078       PC86  -2          A01X+014170Y+003129X0280Y0320     S2      
327NNAME10080       PR36  -2          A01X+013723Y+004344X0180Y0200R180 S2      
327GND              PR36  -1          A01X+013408Y+004344X0180Y0200R180 S2      
327NNAME10079       PR38  -2          A01X+013409Y+003919X0180Y0200     S2      
327NNAME10080       PR38  -1          A01X+013724Y+003919X0180Y0200     S2      
327NNAME10078       PR40  -2          A01X+013701Y+003216X0180Y0200R090 S2      
327NNAME10079       PR40  -1          A01X+013701Y+003531X0180Y0200R090 S2      
317GND              VIA   -     D0100PA00X+014746Y+003808               S3      
317GND              VIA   -     D0100PA00X+014750Y+004298               S3      
317NNAME10080       VIA   -     D0100PA00X+013993Y+004084               S1      
317NNAME10079       VIA   -     D0100PA00X+013993Y+003531               S1      
327NNAME10083       PC85  -2          A01X+014521Y+005451X0180Y0200R090 S2      
327GND              PC85  -1          A01X+014521Y+005766X0180Y0200R090 S2      
327GND              PR103 -2          A01X+014916Y+005758X0180Y0200R270 S2      
327NNAME10084       PR103 -1          A01X+014916Y+005443X0180Y0200R270 S2      
327PV_VDDR_NODE1    PR35  -2          A01X+014116Y+005763X0180Y0200R270 S2      
327NNAME10082       PR35  -1          A01X+014116Y+005448X0180Y0200R270 S2      
327GND              PR34  -2          A01X+013415Y+004737X0180Y0200     S2      
327NNAME10081       PR34  -1          A01X+013730Y+004737X0180Y0200     S2      
317GND              VIA   -     D0100PA00X+014521Y+006015               S3      
317GND              VIA   -     D0100PA00X+014916Y+006001               S3      
317NNAME10081       VIA   -     D0100PA00X+013505Y+005349               S1      
317NNAME10082       VIA   -     D0100PA00X+013754Y+005826               S3      
317NNAME10083       VIA   -     D0100PA00X+014386Y+005194               S1      
317NNAME10084       VIA   -     D0100PA00X+014903Y+005172               S1      
327GND              C143  -2          A01X+014368Y+007659X0180Y0200R180 S2      
327NNAME10085       C143  -1          A01X+014053Y+007659X0180Y0200R180 S2      
327NNAME10007       R217  -2          A01X+013354Y+007659X0180Y0200     S2      
327NNAME10085       R217  -1          A01X+013669Y+007659X0180Y0200     S2      
317GND              VIA   -     D0100PA00X+014656Y+007486               S3      
317UART_RX_P5       VIA   -     D0100PA00X+013529Y+008766               S1      
317UART_RTS_P6_N    VIA   -     D0100PA00X+014035Y+008135               S3      
317N/C              J2    -H1   D0650UA00X+015197Y+009862               S0      
317GND              VIA   -     D0100PA00X+013564Y+013417               S3      
317GND              VIA   -     D0100PA00X+013559Y+013045               S3      
327NNAME10053       C20   -2          A10X+013965Y+025091X0180Y0200R180 S1      
327NNAME10086       C20   -1          A10X+014280Y+025091X0180Y0200R180 S1      
317GND              VIA   -     D0100PA00X+014757Y+024903               S3      
317GND              VIA   -     D0100PA00X+014716Y+024222               S3      
317NNAME10087       VIA   -     D0100PA00X+014440Y+024406               S3      
317NNAME10088       VIA   -     D0100PA00X+014440Y+024756               S3      
327NNAME10058       C17   -2          A10X+013956Y+026605X0180Y0200R180 S1      
327NNAME10089       C17   -1          A10X+014271Y+026605X0180Y0200R180 S1      
327NNAME10057       C18   -2          A10X+013956Y+026155X0180Y0200R180 S1      
327NNAME10090       C18   -1          A10X+014271Y+026155X0180Y0200R180 S1      
327NNAME10054       C19   -2          A10X+013965Y+025491X0180Y0200R180 S1      
327NNAME10091       C19   -1          A10X+014280Y+025491X0180Y0200R180 S1      
317NNAME10092       VIA   -     D0100PA00X+014833Y+025881               S1      
317GND              VIA   -     D0100PA00X+014168Y+026983               S3      
317GND              VIA   -     D0100PA00X+014315Y+028112               S3      
317NNAME10093       VIA   -     D0100PA00X+014520Y+027647               S1      
317NNAME10094       VIA   -     D0100PA00X+013893Y+027897               S1      
317NNAME10095       VIA   -     D0100PA00X+014835Y+028177               S1      
317NNAME10096       VIA   -     D0100PA00X+013454Y+026779               S1      
327NNAME10097       L9    -2          A01X+014470Y+029674X0180Y0200R180 S2      
327P1V8_NODE1       L9    -1          A01X+014155Y+029674X0180Y0200R180 S2      
327GND              R46   -2          A01X+014294Y+028499X0180Y0200     S2      
327NNAME10098       R46   -1          A01X+014609Y+028499X0180Y0200     S2      
327GND              R45   -2          A01X+014294Y+028899X0180Y0200     S2      
327NNAME10099       R45   -1          A01X+014609Y+028899X0180Y0200     S2      
327NNAME10100       R150  -2          A01X+014609Y+029299X0180Y0200R180 S2      
327P1V5_NODE1       R150  -1          A01X+014294Y+029299X0180Y0200R180 S2      
317GND              VIA   -     D0100PA00X+013793Y+029099               S3      
317P1V8_NODE1       VIA   -     D0100PA00X+013799Y+029674               S3      
317P1V5_NODE1       VIA   -     D0100PA00X+013995Y+029384               S3      
327GND              C112  -2          A01X+014126Y+030063X0180Y0200     S2      
327NNAME10097       C112  -1          A01X+014441Y+030063X0180Y0200     S2      
327NNAME10097       C111  -1          A01X+014538Y+030564X0280Y0320R090 S2      
327GND              C111  -2          A01X+013958Y+030564X0280Y0320R090 S2      
327GND              R43   -2          A01X+013886Y+031054X0180Y0200     S2      
327NNAME10101       R43   -1          A01X+014201Y+031054X0180Y0200     S2      
317GND              VIA   -     D0100PA00X+013613Y+030564               S3      
317GND              VIA   -     D0100PA00X+013709Y+030180               S3      
317NNAME10097       VIA   -     D0100PA00X+014902Y+030350               S3      
317NNAME10101       VIA   -     D0100PA00X+014572Y+031134               S1      
327GND              R107  -2          A01X+013924Y+032793X0180Y0200     S2      
327NNAME10102       R107  -1          A01X+014239Y+032793X0180Y0200     S2      
327GND              R44   -2          A01X+013886Y+032354X0180Y0200     S2      
327NNAME10103       R44   -1          A01X+014201Y+032354X0180Y0200     S2      
327GND              R41   -2          A01X+013886Y+031904X0180Y0200     S2      
327NNAME10104       R41   -1          A01X+014201Y+031904X0180Y0200     S2      
327GND              R40   -2          A01X+013886Y+031454X0180Y0200     S2      
327NNAME10105       R40   -1          A01X+014201Y+031454X0180Y0200     S2      
317GND              VIA   -     D0100PA00X+013573Y+031454               S3      
317GND              VIA   -     D0100PA00X+013477Y+031904               S3      
317GND              VIA   -     D0100PA00X+013522Y+032354               S1      
317NNAME10103       VIA   -     D0100PA00X+014610Y+032354               S1      
317NNAME10105       VIA   -     D0100PA00X+014558Y+031684               S1      
327GND              R108  -2          A01X+013938Y+033205X0180Y0200     S2      
327NNAME10106       R108  -1          A01X+014253Y+033205X0180Y0200     S2      
317GND              VIA   -     D0100PA00X+013651Y+033219               S1      
327NNAME10107       C28   -2          A10X+014406Y+037008X0180Y0200R270 S1      
327GND              C28   -1          A10X+014406Y+037323X0180Y0200R270 S1      
327NNAME10004       R125  -2          A10X+014806Y+037323X0180Y0200R090 S1      
327NNAME10107       R125  -1          A10X+014806Y+037008X0180Y0200R090 S1      
317GND              VIA   -     D0100PA00X+014406Y+037603               S3      
327NNAME10004       R126  -2          A10X+014800Y+038058X0180Y0200R270 S1      
327P3V3_NODE1       R126  -1          A10X+014800Y+038373X0180Y0200R270 S1      
327P1V5_SUS_NODE1   C821  -1          A10X+014060Y+040897X0440Y0540R090 S1      
327P1V5_SUS_NODE1   C823  -2          A01X+014466Y+040743X0180Y0200R180 S2      
327NNAME10060       C823  -1          A01X+014151Y+040743X0180Y0200R180 S2      
317P1V5_SUS_NODE1   VIA   -     D0100PA00X+013789Y+040335               S3      
317P1V5_SUS_NODE1   VIA   -     D0100PA00X+014180Y+040448               S3      
317P1V5_SUS_NODE1   VIA   -     D0100PA00X+014185Y+040182               S3      
327P1V5_SUS_NODE1   VIA   -           A10X+013915Y+040080X0260Y0260     S1      
317P1V5_SUS_NODE1   VIA   -     D0100PA00X+013509Y+040506               S3      
317P1V5_SUS_NODE1   VIA   -     D0100PA00X+013518Y+040212               S3      
317P1V5_SUS_NODE1   VIA   -     D0100PA00X+014530Y+040439               S3      
317P1V5_SUS_NODE1   VIA   -     D0100PA00X+014528Y+040151               S1      
327GND              C821  -2          A10X+014060Y+041645X0440Y0540R090 S1      
327GND              C822  -2          A10X+014668Y+041360X0180Y0200R090 S1      
327P1V5_SUS_NODE1   C822  -1          A10X+014668Y+041045X0180Y0200R090 S1      
327NNAME10060       R1089 -2          A01X+013770Y+040885X0180Y0200R090 S2      
327GND              R1089 -1          A01X+013770Y+041200X0180Y0200R090 S2      
327P1V5_SUS_NODE1   R1088 -2          A01X+014466Y+041143X0180Y0200R180 S2      
327NNAME10060       R1088 -1          A01X+014151Y+041143X0180Y0200R180 S2      
317GND              VIA   -     D0100PA00X+013551Y+042137               S3      
317NNAME10060       VIA   -     D0100PA00X+014224Y+042235               S1      
317NNAME10059       VIA   -     D0100PA00X+013940Y+042509               S3      
317P1V5_SUS_NODE1   VIA   -     D0100PA00X+013844Y+043593               S3      
317P1V5_SUS_NODE1   VIA   -     D0100PA00X+013844Y+043843               S3      
327NNAME10108       Q39   -4          A01X+014362Y+045326X0140Y0200R090 S2      
327P1V5_NODE1       Q39   -3          A01X+014362Y+045070X0140Y0200R090 S2      
327P1V5_NODE1       Q39   -2          A01X+014362Y+044814X0140Y0200R090 S2      
327P1V5_NODE1       Q39   -1          A01X+014362Y+044558X0140Y0200R090 S2      
317GND              VIA   -     D0100PA00X+014782Y+044193               S3      
317P1V5_NODE1       VIA   -     D0100PA00X+014758Y+044528               S3      
317P1V5_NODE1       VIA   -     D0100PA00X+014758Y+044778               S3      
317P1V5_NODE1       VIA   -     D0100PA00X+014758Y+045028               S3      
317P1V5_SUS_NODE1   VIA   -     D0100PA00X+013844Y+044093               S3      
327NNAME10108       Q40   -D          A01X+014250Y+046041X0320Y0360R180 S2      
327NNAME10061       Q40   -S          A01X+013876Y+046828X0320Y0360R180 S2      
327NNAME10062       Q40   -G          A01X+014624Y+046828X0320Y0360R180 S2      
317NNAME10061       VIA   -     D0100PA00X+013530Y+046844               S1      
317NNAME10062       VIA   -     D0100PA00X+014624Y+047211               S1      
317P3V3_STB_NODE1   VIA   -     D0100PA00X+013931Y+047810               S3      
317P3V3_STB_NODE1   VIA   -     D0100PA00X+013647Y+048199               S3      
327GND              C832  -2          A01X+013685Y+051380X0180Y0200R180 S2      
327NNAME10063       C832  -1          A01X+013370Y+051380X0180Y0200R180 S2      
317GND              VIA   -     D0100PA00X+013937Y+051664               S3      
317GND              VIA   -     D0100PA00X+013940Y+051371               S3      
327NNAME10109       R261  -2          A10X+014553Y+052698X0180Y0200R090 S1      
327NNAME10063       R261  -1          A10X+014553Y+052383X0180Y0200R090 S1      
317NNAME10109       VIA   -     D0100PA00X+014948Y+053273               S3      
327NNAME10109       VIA   -           A10X+014354Y+053202X0260Y0260     S1      
327NNAME10109       C227  -2          A10X+014654Y+054095X0180Y0200R180 S1      
327NNAME10109       C228  -1          A10X+014664Y+053701X0180Y0200     S1      
327NNAME10109       C224  -1          A10X+014663Y+055035X0180Y0200     S1      
327NNAME10109       R262  -1          A10X+014663Y+054485X0180Y0200     S1      
317NNAME10109       VIA   -     D0100PA00X+014412Y+054758               S3      
317NNAME10109       VIA   -     D0100PA00X+014692Y+054768               S3      
327NNAME10109       VIA   -           A10X+014189Y+054480X0260Y0260     S1      
327NNAME10109       VIA   -           A10X+014209Y+053815X0260Y0260     S1      
327NNAME10109       VIA   -           A10X+014636Y+055539X0260Y0260     S1      
327GND              R554  -1          A10X+014774Y+058101X0180Y0200     S1      
327P3V3_NODE1       R551  -1          A10X+014774Y+057311X0180Y0200     S1      
327GND              R552  -1          A10X+014774Y+057711X0180Y0200     S1      
317GND              VIA   -     D0100PA00X+014502Y+057600               S3      
317P3V3_NODE1       VIA   -     D0100PA00X+014325Y+057311               S3      
327GND              C426  -2          A10X+014769Y+059414X0180Y0200R180 S1      
317LAN1_CTRL_P1V9   VIA   -     D0100PA00X+014555Y+058809               S3      
317LAN1_CTRL_P1V9   VIA   -     D0100PA00X+014905Y+058804               S1      
317LAN1_CTRL_P1V9   VIA   -     D0100PA00X+014126Y+058818               S3      
317GND              VIA   -     D0100PA00X+014119Y+059769               S3      
317GND              VIA   -     D0100PA00X+014588Y+058413               S3      
327GND              C427  -2          A10X+014775Y+061070X0180Y0200R180 S1      
327GND              C406  -2          A10X+014766Y+059814X0180Y0200R180 S1      
317GND              VIA   -     D0100PA00X+014471Y+059814               S3      
327LAN1_MDI0_DN     VIA   -           A01X+013341Y+060727X0160Y0041     S2      
327LAN1_MDI1_DP     VIA   -           A01X+014311Y+061253X0160Y0041     S2      
317P3V3_SUS_NODE1   VIA   -     D0100PA00X+013642Y+059935               S3      
327GND              C407  -2          A10X+014775Y+061904X0180Y0200R180 S1      
327GND              C401  -2          A10X+014775Y+061474X0180Y0200R180 S1      
317GND              VIA   -     D0100PA00X+014775Y+062756               S3      
327LAN1_MDI2_DN     VIA   -           A01X+013723Y+062373X0160Y0041     S2      
327N/C                    -1          A10X+014759Y+064788X0390Y0390R270 S1      
327N/C                    -1          A01X+014759Y+064788X0390Y0390R270 S2      
317GND              VIA   -     D0100PA00X+014575Y+063025               S3      
317P12V_AUX         VIA   -     D0100PA00X+014814Y+066011               S3      
327P12V_AUX_EN      U109  -D          A01X+014225Y+067146X0400Y0500R270 S2      
317P12V_AUX         VIA   -     D0100PA00X+014849Y+067604               S3      
317P12V_AUX_EN      VIA   -     D0100PA00X+014820Y+066921               S1      
317P3V3_SUS_NODE1   VIA   -     D0100PA00X+014011Y+067591               S1      
327GND              C771  -2          A01X+014382Y+068754X0460Y0620     S2      
327NNAME10110       R106  -2          A01X+013776Y+068918X0180Y0200R090 S2      
327P3V3_SUS_NODE1   R1023 -2          A01X+013776Y+068118X0180Y0200R090 S2      
327NNAME10110       R1023 -1          A01X+013776Y+068433X0180Y0200R090 S2      
327NNAME10067       R1021 -2          A01X+013361Y+068921X0180Y0200R090 S2      
317GND              VIA   -     D0100PA00X+014775Y+068754               S3      
317GND              VIA   -     D0100PA00X+014382Y+068291               S3      
317GND              VIA   -     D0100PA00X+013445Y+068298               S3      
317NNAME10110       VIA   -     D0100PA00X+013916Y+068673               S1      
317NNAME10069       VIA   -     D0100PA00X+013528Y+067921               S1      
327NNAME10111       Q22   -5          A01X+014954Y+070304X1850Y1811R090 S2      
327NNAME10112       U100  -10         A01X+013638Y+069986X0110Y0570R180 S2      
327NNAME10070       U100  -9          A01X+013441Y+069986X0110Y0570R180 S2      
327NNAME10112       R106  -1          A01X+013776Y+069233X0180Y0200R090 S2      
327NNAME10070       R1021 -1          A01X+013361Y+069236X0180Y0200R090 S2      
317NNAME10112       VIA   -     D0100PA00X+013873Y+069671               S1      
327NNAME10111       U100  -2          A01X+013441Y+071738X0110Y0570R180 S2      
327P12V_PDB         U100  -1          A01X+013638Y+071738X0110Y0570R180 S2      
317NNAME10111       VIA   -     D0100PA00X+013820Y+071263               S1      
327GND              D20   -1          A01X+014636Y+072671X0320Y0360     S2      
327GND              C770  -2          A01X+013718Y+073873X0180Y0200     S2      
327P12V_PDB         C770  -1          A01X+014033Y+073873X0180Y0200     S2      
327GND              C777  -2          A01X+013728Y+072517X0180Y0200     S2      
327P12V_PDB         C777  -1          A01X+014043Y+072517X0180Y0200     S2      
327GND              C767  -2          A01X+013718Y+073073X0180Y0200     S2      
327P12V_PDB         C767  -1          A01X+014033Y+073073X0180Y0200     S2      
327GND              C768  -2          A01X+013718Y+073473X0180Y0200     S2      
327P12V_PDB         C768  -1          A01X+014033Y+073473X0180Y0200     S2      
317GND              VIA   -     D0100PA00X+013478Y+073873               S3      
317GND              VIA   -     D0100PA00X+013478Y+073473               S3      
317GND              VIA   -     D0100PA00X+013475Y+072616               S3      
317GND              VIA   -     D0100PA00X+013707Y+072801               S3      
317P12V_PDB         VIA   -     D0100PA00X+014463Y+073596               S1      
327GND              C769  -2          A01X+013718Y+074273X0180Y0200     S2      
327P12V_PDB         C769  -1          A01X+014033Y+074273X0180Y0200     S2      
317GND              VIA   -     D0100PA00X+013472Y+074238               S3      
317P12V_PDB         VIA   -     D0100PA00X+014729Y+074411               S3      
317P12V_PDB         VIA   -     D0100PA00X+014504Y+074074               S3      
317NNAME10113       VIA   -     D0100PA00X+013960Y+078128               S3      
317NNAME10075       VIA   -     D0100PA00X+013547Y+078170               S1      
317NNAME10025       VIA   -     D0100PA00X+013561Y+078452               S3      
317NNAME10018       VIA   -     D0100PA00X+013968Y+078460               S3      
317NNAME10012       VIA   -     D0100PA00X+014945Y+078043               S3      
317NNAME10072       VIA   -     D0100PA00X+014615Y+078382               S3      
317NNAME10073       VIA   -     D0100PA00X+014557Y+078058               S1      
327NNAME10018       J35   -A60        A10X+013785Y+080787X0300Y1660R180 S1      
327GND              J35   -A59        A10X+014179Y+080787X0300Y1660R180 S1      
327NNAME10072       J35   -A58        A10X+014573Y+080787X0300Y1660R180 S1      
327NNAME10009       J35   -A57        A10X+014967Y+080787X0300Y1660R180 S1      
327NNAME10113       J35   -B60        A01X+013785Y+080787X0300Y1660R180 S2      
327GND              J35   -B59        A01X+014179Y+080787X0300Y1660R180 S2      
327NNAME10073       J35   -B58        A01X+014573Y+080787X0300Y1660R180 S2      
327NNAME10012       J35   -B57        A01X+014967Y+080787X0300Y1660R180 S2      
317GND              VIA   -     D0100PA00X+014179Y+078870               S3      
317GND              VIA   -     D0100PA00X+014179Y+079170               S3      
327GND              PC31  -2          A01X+015818Y+001445X0180Y0200R090 S2      
327GND              PC74  -2          A01X+016495Y+000862X0460Y0620R090 S2      
327NNAME10114       R1241 -2          A01X+015394Y+001215X0180Y0200R180 S2      
327GND              R1241 -1          A01X+015079Y+001215X0180Y0200R180 S2      
317GND              VIA   -     D0100PA00X+015079Y+000925               S3      
317GND              VIA   -     D0100PA00X+015818Y+001198               S3      
317GND              VIA   -     D0100PA00X+015386Y+001518               S3      
317GND              VIA   -     D0100PA00X+016414Y+001303               S3      
327NNAME10114       PC31  -1          A01X+015818Y+001760X0180Y0200R090 S2      
327P3V3_STB_NODE1   C853  -2          A01X+015071Y+001772X0180Y0200     S2      
327GND              C853  -1          A01X+015386Y+001772X0180Y0200     S2      
327NNAME10115       PC74  -1          A01X+016495Y+002022X0460Y0620R090 S2      
327GND              PR37  -2          A01X+015459Y+002422X0180Y0200R090 S2      
327NNAME10116       PR37  -1          A01X+015459Y+002737X0180Y0200R090 S2      
327NNAME10076       R1123 -2          A01X+015059Y+002737X0180Y0200R270 S2      
327P3V3_STB_NODE1   R1123 -1          A01X+015059Y+002422X0180Y0200R270 S2      
327NNAME10117       PJ10  -2          A01X+015817Y+002752X0180Y0200R270 S2      
327NNAME10114       PJ10  -1          A01X+015817Y+002437X0200Y0400R180 S2      
317GND              VIA   -     D0100PA00X+015459Y+002117               S3      
317NNAME10117       VIA   -     D0100PA00X+015788Y+003067               S1      
317NNAME10116       VIA   -     D0100PA00X+015281Y+002992               S1      
317NNAME10114       VIA   -     D0100PA00X+015817Y+002130               S1      
317P3V3_STB_NODE1   VIA   -     D0100PA00X+015059Y+002097               S3      
327P5V_STB_NODE1    PU7   -15         A01X+015609Y+004371X0070Y0360R270 S2      
327NNAME10118       PU7   -14         A01X+015609Y+004213X0070Y0360R270 S2      
327NNAME10119       PU7   -13         A01X+015609Y+004056X0070Y0360R270 S2      
327NNAME10120       PU7   -12         A01X+015609Y+003898X0070Y0360R270 S2      
327NNAME10121       PU7   -11         A01X+015609Y+003741X0070Y0360R270 S2      
327NNAME10117       PU7   -10         A01X+015308Y+003440X0070Y0360     S2      
327NNAME10116       PU7   -9          A01X+015151Y+003440X0070Y0360     S2      
327NNAME10076       PU7   -8          A01X+014993Y+003440X0070Y0360     S2      
327NNAME10122       PU7   -16         A01X+015308Y+004671X0070Y0360     S2      
327GND              PU7   -17         A01X+015151Y+004671X0070Y0360     S2      
327NNAME10084       PU7   -18         A01X+014993Y+004671X0070Y0360     S2      
327NNAME10120       PC77  -2          A01X+016393Y+003748X0180Y0200R270 S2      
327NNAME10121       PC77  -1          A01X+016393Y+003433X0180Y0200R270 S2      
317GND              VIA   -     D0100PA00X+015241Y+003811               S3      
317GND              VIA   -     D0100PA00X+015237Y+004298               S3      
317P5V_STB_NODE1    VIA   -     D0100PA00X+015626Y+004574               S3      
317NNAME10121       VIA   -     D0100PA00X+015986Y+003613               S1      
317NNAME10119       VIA   -     D0100PA00X+016073Y+004104               S3      
317NNAME10119       VIA   -     D0100PA00X+016235Y+004298               S3      
327GND              PC76  -1          A01X+016551Y+005097X0280Y0320R090 S2      
327P5V_STB_NODE1    PC76  -2          A01X+015971Y+005097X0280Y0320R090 S2      
327GND              PR33  -2          A01X+015314Y+005591X0180Y0200     S2      
327NNAME10122       PR33  -1          A01X+015629Y+005591X0180Y0200     S2      
327P5V_STB_NODE1    PJ9   -2          A01X+016011Y+005672X0180Y0200R090 S2      
327NNAME10122       PJ9   -1          A01X+016011Y+005987X0200Y0400     S2      
317GND              VIA   -     D0100PA00X+015279Y+005312               S3      
317P5V_STB_NODE1    VIA   -     D0100PA00X+015766Y+004789               S3      
317NNAME10122       VIA   -     D0100PA00X+015701Y+005896               S1      
317NNAME10077       VIA   -     D0100PA00X+016455Y+006124               S1      
327PD_NODE1_DM0     R212  -2          A01X+015255Y+007486X0180Y0200R180 S2      
327GND              R212  -1          A01X+014940Y+007486X0180Y0200R180 S2      
317PD_NODE1_DM0     VIA   -     D0100PA00X+015644Y+007486               S1      
327NNAME10123       J2    -5          A01X+016358Y+008248X0150Y0810     S2      
327GND              J2    -3          A01X+016122Y+008248X0150Y0810     S2      
327NNAME10085       J2    -1          A01X+015886Y+008248X0150Y0810     S2      
317GND              VIA   -     D0100PA00X+016122Y+008945               S3      
317NNAME10085       VIA   -     D0100PA00X+015162Y+008334               S1      
317GND              VIA   -     D0100PA00X+016004Y+010884               S3      
317NNAME10123       VIA   -     D0100PA00X+016428Y+010181               S1      
327NNAME10124       J2    -4          A01X+016240Y+011476X0150Y0810     S2      
327GND              J2    -2          A01X+016004Y+011476X0150Y0810     S2      
317GND              VIA   -     D0100PA00X+016213Y+012934               S3      
317NNAME10125       VIA   -     D0100PA00X+016449Y+012711               S1      
317NNAME10124       VIA   -     D0100PA00X+015919Y+012778               S1      
317GND              VIA   -     D0100PA00X+016352Y+024399               S3      
317GND              VIA   -     D0100PA00X+016232Y+024988               S3      
317NNAME10126       VIA   -     D0100PA00X+015299Y+024810               S1      
317NNAME10127       VIA   -     D0100PA00X+015769Y+024992               S1      
327NNAME10092       U2    -BF1        A01X+016438Y+026256X0100Y0135R270 S2      
317GND              VIA   -     D0100PA00X+016192Y+025429               S3      
317GND              VIA   -     D0100PA00X+016045Y+025961               S3      
327NNAME10090       VIA   -           A10X+016087Y+026303X0160Y0042     S1      
317NNAME10128       VIA   -     D0100PA00X+015455Y+025699               S1      
327NNAME10129       C16   -2          A10X+015244Y+027149X0180Y0200R180 S1      
327NNAME10130       C16   -1          A10X+015559Y+027149X0180Y0200R180 S1      
327NNAME10131       C15   -2          A10X+015244Y+026749X0180Y0200R180 S1      
327NNAME10132       C15   -1          A10X+015559Y+026749X0180Y0200R180 S1      
327NNAME10098       U2    -AU1        A01X+016438Y+028029X0100Y0135R270 S2      
327GND              U2    -AY1        A01X+016438Y+027462X0100Y0135R270 S2      
327GND              U2    -BC1        A01X+016438Y+026822X0100Y0135R270 S2      
317GND              VIA   -     D0100PA00X+016248Y+027660               S3      
327NNAME10132       VIA   -           A10X+015989Y+026904X0160Y0042     S1      
317NNAME10133       VIA   -     D0100PA00X+015263Y+027681               S1      
327GND              C36   -2          A10X+015625Y+029721X0280Y0320R180 S1      
327GND              U2    -AP1        A01X+016438Y+028595X0100Y0135R270 S2      
327GND              U2    -AL1        A01X+016438Y+029235X0100Y0135R270 S2      
317GND              VIA   -     D0100PA00X+015858Y+028555               S3      
317GND              VIA   -     D0100PA00X+016192Y+029387               S3      
317GND              VIA   -     D0100PA00X+016177Y+028724               S3      
317NNAME10100       VIA   -     D0100PA00X+014972Y+029299               S1      
317NNAME10098       VIA   -     D0100PA00X+015273Y+028852               S1      
317NNAME10099       VIA   -     D0100PA00X+015808Y+029064               S1      
327P1V05_NODE1      C36   -1          A10X+015625Y+030301X0280Y0320R180 S1      
327GND              U2    -AB1        A01X+016438Y+031008X0100Y0135R270 S2      
327NNAME10098       U2    -AH1        A01X+016438Y+029802X0100Y0135R270 S2      
327GND              U2    -AE1        A01X+016438Y+030368X0100Y0135R270 S2      
317GND              VIA   -     D0100PA00X+016218Y+030308               S3      
317GND              VIA   -     D0100PA00X+016169Y+031036               S3      
317NNAME10097       VIA   -     D0100PA00X+015458Y+030877               S1      
327GND              U2    -N1         A01X+016438Y+032781X0100Y0135R270 S2      
327GND              U2    -T1         A01X+016438Y+032141X0100Y0135R270 S2      
327NNAME10104       U2    -W1         A01X+016438Y+031574X0100Y0135R270 S2      
317GND              VIA   -     D0100PA00X+016206Y+032794               S3      
317GND              VIA   -     D0100PA00X+016202Y+032439               S3      
317GND              VIA   -     D0100PA00X+015956Y+032801               S3      
317GND              VIA   -     D0100PA00X+016151Y+031714               S3      
317NNAME10102       VIA   -     D0100PA00X+015123Y+033016               S1      
317NNAME10104       VIA   -     D0100PA00X+015092Y+031813               S1      
327GND              U2    -K1         A01X+016438Y+033347X0100Y0135R270 S2      
317GND              VIA   -     D0100PA00X+015929Y+033622               S3      
317NNAME10106       VIA   -     D0100PA00X+015051Y+033631               S1      
317NNAME10134       VIA   -     D0100PA00X+015645Y+033663               S1      
317NNAME10135       VIA   -     D0100PA00X+016207Y+033695               S1      
317GND              VIA   -     D0100PA00X+016442Y+034819               S3      
327NNAME10136       C30   -2          A10X+015206Y+037008X0180Y0200R270 S1      
327GND              C30   -1          A10X+015206Y+037323X0180Y0200R270 S1      
327NNAME10137       C26   -2          A10X+016006Y+037008X0180Y0200R270 S1      
327GND              C26   -1          A10X+016006Y+037323X0180Y0200R270 S1      
327NNAME10068       R130  -2          A10X+015606Y+037323X0180Y0200R090 S1      
327NNAME10136       R130  -1          A10X+015606Y+037008X0180Y0200R090 S1      
327NNAME10138       R121  -2          A10X+016406Y+037323X0180Y0200R090 S1      
327NNAME10137       R121  -1          A10X+016406Y+037008X0180Y0200R090 S1      
317GND              VIA   -     D0100PA00X+015206Y+037602               S3      
317GND              VIA   -     D0100PA00X+016006Y+037582               S3      
327NNAME10136       VIA   -           A10X+015861Y+036457X0260Y0260     S1      
327NNAME10068       R131  -2          A10X+015610Y+038058X0180Y0200R270 S1      
327P3V3_NODE1       R131  -1          A10X+015610Y+038373X0180Y0200R270 S1      
327NNAME10138       R122  -2          A10X+016374Y+038029X0180Y0200R270 S1      
327P3V3_NODE1       R122  -1          A10X+016374Y+038344X0180Y0200R270 S1      
317GND              VIA   -     D0100PA00X+015052Y+038281               S3      
317P3V3_NODE1       VIA   -     D0100PA00X+016529Y+038595               S3      
317P3V3_NODE1       VIA   -     D0100PA00X+015182Y+038555               S3      
317NNAME10004       VIA   -     D0100PA00X+015090Y+037971               S3      
317NNAME10138       VIA   -     D0100PA00X+016089Y+038029               S3      
317NNAME10068       VIA   -     D0100PA00X+016071Y+038404               S3      
317GND              VIA   -     D0100PA00X+016164Y+040329               S3      
317NNAME10110       VIA   -     D0100PA00X+016294Y+040619               S3      
327GND              PC19  -2          A01X+016445Y+043252X0180Y0200     S2      
327GND              PR8   -2          A01X+016425Y+043683X0180Y0200     S2      
317GND              VIA   -     D0100PA00X+016158Y+043683               S3      
317GND              VIA   -     D0100PA00X+016156Y+043252               S1      
327NNAME10139       PC21  -1          A01X+016477Y+044108X0180Y0200R180 S2      
327NNAME10108       C849  -1          A01X+015110Y+045529X0280Y0320R180 S2      
327P1V5_NODE1       C849  -2          A01X+015110Y+044949X0280Y0320R180 S2      
327P1V5_NODE1       R1118 -2          A01X+015110Y+044508X0180Y0200R270 S2      
327GND              R1118 -1          A01X+015110Y+044193X0180Y0200R270 S2      
327NNAME10139       PR7   -1          A01X+016477Y+044503X0180Y0200R180 S2      
317P1V5_NODE1       VIA   -     D0100PA00X+015437Y+044993               S1      
327NNAME10108       R1115 -2          A01X+015115Y+046343X0180Y0200R090 S2      
327P5V_STB_NODE1    R1115 -1          A01X+015115Y+046658X0180Y0200R090 S2      
317P5V_STB_NODE1    VIA   -     D0100PA00X+015115Y+046946               S3      
327P1V8_NODE1       VIA   -           A10X+015969Y+046529X0260Y0260     S1      
317NNAME10108       VIA   -     D0100PA00X+015055Y+045936               S1      
317NNAME10063       VIA   -     D0100PA00X+016338Y+048454               S3      
317NNAME10063       VIA   -     D0100PA00X+015255Y+049403               S3      
317NNAME10063       VIA   -     D0100PA00X+015841Y+050002               S3      
327NNAME10140       U15   -T3         A01X+016391Y+050773X0145Y0145     S2      
327NNAME10141       U15   -T2         A01X+016076Y+050773X0145Y0145     S2      
327GND              U15   -T1         A01X+015761Y+050773X0145Y0145     S2      
327NNAME10142       U15   -R3         A01X+016391Y+051088X0145Y0145     S2      
327NNAME10143       U15   -R2         A01X+016076Y+051088X0145Y0145     S2      
327NNAME10063       U15   -R1         A01X+015761Y+051088X0145Y0145     S2      
327NNAME10144       U15   -P3         A01X+016391Y+051403X0145Y0145     S2      
327NNAME10145       U15   -P2         A01X+016076Y+051403X0145Y0145     S2      
327GND              U15   -P1         A01X+015761Y+051403X0145Y0145     S2      
327NNAME10146       U15   -N3         A01X+016391Y+051718X0145Y0145     S2      
327NNAME10147       U15   -N2         A01X+016076Y+051718X0145Y0145     S2      
327NNAME10063       U15   -N1         A01X+015761Y+051718X0145Y0145     S2      
327GND              C230  -2          A10X+015071Y+050678X0180Y0200R270 S1      
327NNAME10063       C230  -1          A10X+015071Y+050993X0180Y0200R270 S1      
317GND              VIA   -     D0100PA00X+015431Y+050751               S3      
317GND              VIA   -     D0100PA00X+015452Y+051393               S3      
317NNAME10145       VIA   -     D0100PA00X+016234Y+051246               S1      
317NNAME10147       VIA   -     D0100PA00X+015920Y+051561               S1      
317NNAME10063       VIA   -     D0100PA00X+015404Y+051139               S3      
317NNAME10063       VIA   -     D0100PA00X+015397Y+051719               S3      
327NNAME10148       U15   -M3         A01X+016391Y+052033X0145Y0145     S2      
327NNAME10149       U15   -M2         A01X+016076Y+052033X0145Y0145     S2      
327GND              U15   -M1         A01X+015761Y+052033X0145Y0145     S2      
327NNAME10150       U15   -L3         A01X+016391Y+052348X0145Y0145     S2      
327NNAME10151       U15   -L2         A01X+016076Y+052348X0145Y0145     S2      
327NNAME10152       U15   -L1         A01X+015761Y+052348X0145Y0145     S2      
327NNAME10153       U15   -K3         A01X+016391Y+052663X0145Y0145     S2      
327NNAME10063       U15   -K2         A01X+016076Y+052663X0145Y0145     S2      
327NNAME10154       U15   -K1         A01X+015761Y+052663X0145Y0145     S2      
327NNAME10155       U15   -J3         A01X+016391Y+052978X0145Y0145     S2      
327GND              U15   -J2         A01X+016076Y+052978X0145Y0145     S2      
327NNAME10156       U15   -J1         A01X+015761Y+052978X0145Y0145     S2      
327NNAME10157       U15   -H3         A01X+016391Y+053293X0145Y0145     S2      
327NNAME10063       U15   -H2         A01X+016076Y+053293X0145Y0145     S2      
327NNAME10109       U15   -H1         A01X+015761Y+053293X0145Y0145     S2      
327NNAME10109       C226  -2          A10X+014948Y+052693X0180Y0200R090 S1      
327NNAME10063       C226  -1          A10X+014948Y+052378X0180Y0200R090 S1      
317GND              VIA   -     D0100PA00X+015919Y+053136               S3      
317GND              VIA   -     D0100PA00X+015373Y+052073               S3      
317NNAME10144       VIA   -     D0100PA00X+015918Y+052189               S1      
317NNAME10152       VIA   -     D0100PA00X+015413Y+052441               S1      
317NNAME10151       VIA   -     D0100PA00X+016234Y+052191               S3      
317NNAME10156       VIA   -     D0100PA00X+015448Y+053042               S1      
317NNAME10154       VIA   -     D0100PA00X+015918Y+052823               S1      
317NNAME10109       VIA   -     D0100PA00X+015540Y+053344               S3      
317NNAME10109       VIA   -     D0100PA00X+015425Y+052747               S3      
317NNAME10063       VIA   -     D0100PA00X+016234Y+052821               S3      
317NNAME10063       VIA   -     D0100PA00X+015919Y+053450               S3      
327NNAME10158       U15   -G3         A01X+016391Y+053608X0145Y0145     S2      
327NNAME10159       U15   -G2         A01X+016076Y+053608X0145Y0145     S2      
327GND              U15   -G1         A01X+015761Y+053608X0145Y0145     S2      
327NNAME10160       U15   -F3         A01X+016391Y+053923X0145Y0145     S2      
327NNAME10161       U15   -F2         A01X+016076Y+053923X0145Y0145     S2      
327NNAME10063       U15   -F1         A01X+015761Y+053923X0145Y0145     S2      
327NNAME10162       U15   -E3         A01X+016391Y+054238X0145Y0145     S2      
327GND              U15   -E2         A01X+016076Y+054238X0145Y0145     S2      
327GND              U15   -E1         A01X+015761Y+054238X0145Y0145     S2      
327NNAME10163       U15   -D3         A01X+016391Y+054553X0145Y0145     S2      
327NNAME10063       U15   -D2         A01X+016076Y+054553X0145Y0145     S2      
327GND              U15   -D1         A01X+015761Y+054553X0145Y0145     S2      
327NNAME10164       U15   -C3         A01X+016391Y+054868X0145Y0145     S2      
327NNAME10165       U15   -C2         A01X+016076Y+054868X0145Y0145     S2      
327NNAME10063       U15   -C1         A01X+015761Y+054868X0145Y0145     S2      
327GND              C227  -1          A10X+014969Y+054095X0180Y0200R180 S1      
327GND              C228  -2          A10X+014979Y+053701X0180Y0200     S1      
327GND              C224  -2          A10X+014978Y+055035X0180Y0200     S1      
327GND              R262  -2          A10X+014978Y+054485X0180Y0200     S1      
317GND              VIA   -     D0100PA00X+015919Y+054395               S3      
317GND              VIA   -     D0100PA00X+015506Y+054553               S3      
317GND              VIA   -     D0100PA00X+015495Y+054238               S3      
317GND              VIA   -     D0100PA00X+015495Y+053608               S3      
317NNAME10162       VIA   -     D0100PA00X+016234Y+054395               S1      
317NNAME10159       VIA   -     D0100PA00X+015919Y+053765               S1      
317NNAME10165       VIA   -     D0100PA00X+016234Y+055025               S1      
317NNAME10063       VIA   -     D0100PA00X+015495Y+053923               S3      
317NNAME10063       VIA   -     D0100PA00X+015919Y+054710               S3      
317NNAME10063       VIA   -     D0100PA00X+015490Y+054868               S3      
327GND              U15   -B3         A01X+016391Y+055183X0145Y0145     S2      
327NNAME10063       U15   -B2         A01X+016076Y+055183X0145Y0145     S2      
327GND              U15   -B1         A01X+015761Y+055183X0145Y0145     S2      
327NNAME10166       U15   -A3         A01X+016391Y+055498X0145Y0145     S2      
327NNAME10167       U15   -A2         A01X+016076Y+055498X0145Y0145     S2      
327NNAME10063       U15   -A1         A01X+015761Y+055498X0145Y0145     S2      
327GND              C234  -2          A10X+015223Y+055525X0180Y0200R180 S1      
327NNAME10063       C234  -1          A10X+015538Y+055525X0180Y0200R180 S1      
327NNAME10063       C229  -1          A10X+016111Y+056485X0280Y0320R090 S1      
327GND              C229  -2          A10X+015531Y+056485X0280Y0320R090 S1      
317GND              VIA   -     D0100PA00X+016232Y+055339               S3      
317GND              VIA   -     D0100PA00X+015511Y+056115               S3      
317GND              VIA   -     D0100PA00X+015490Y+055183               S3      
317NNAME10167       VIA   -     D0100PA00X+016426Y+055727               S1      
317NNAME10063       VIA   -     D0100PA00X+015919Y+055340               S3      
317NNAME10063       VIA   -     D0100PA00X+015761Y+055747               S3      
317NNAME10063       VIA   -     D0100PA00X+015441Y+055799               S3      
327NNAME10168       R554  -2          A10X+015089Y+058101X0180Y0200     S1      
327LAN1_DIS_REG10   R551  -2          A10X+015089Y+057311X0180Y0200     S1      
327LAN1_DIS_REG10   R552  -2          A10X+015089Y+057711X0180Y0200     S1      
327NNAME10169       R550  -2          A01X+016266Y+057561X0180Y0200R270 S2      
327P3V3_NODE1       R550  -1          A01X+016266Y+057246X0180Y0200R270 S2      
327NNAME10170       R557  -2          A01X+015843Y+057571X0180Y0200R270 S2      
327GND              R557  -1          A01X+015843Y+057256X0180Y0200R270 S2      
317LAN1_DIS_REG10   VIA   -     D0100PA00X+015414Y+057782               S3      
317GND              VIA   -     D0100PA00X+015843Y+056844               S3      
317NNAME10170       VIA   -     D0100PA00X+016128Y+058159               S1      
317P3V3_NODE1       VIA   -     D0100PA00X+016279Y+056860               S3      
327LAN1_CTRL_P1V9   U35   -64         A01X+015755Y+059517X0100Y0360R090 S2      
327P1V9_LAN1        U35   -63         A01X+015755Y+059714X0100Y0360R090 S2      
327NNAME10168       U35   -2          A01X+016267Y+059202X0100Y0360     S2      
327P3V3_NODE1       U35   -1          A01X+016070Y+059202X0100Y0360     S2      
327P1V9_LAN1        C426  -1          A10X+015084Y+059414X0180Y0200R180 S1      
327GND              C395  -2          A10X+016333Y+059301X0180Y0200R090 S1      
327P3V3_NODE1       C395  -1          A10X+016333Y+058986X0180Y0200R090 S1      
327GND              C428  -2          A10X+016054Y+059693X0180Y0200     S1      
327P1V9_LAN1        C428  -1          A10X+015739Y+059693X0180Y0200     S1      
327GND              C397  -2          A10X+015476Y+058824X0180Y0200R180 S1      
327P3V3_NODE1       C397  -1          A10X+015791Y+058824X0180Y0200R180 S1      
317GND              VIA   -     D0100PA00X+015190Y+059045               S3      
317NNAME10168       VIA   -     D0100PA00X+015648Y+058332               S1      
317P1V9_LAN1        VIA   -     D0100PA00X+015353Y+059714               S3      
317P3V3_NODE1       VIA   -     D0100PA00X+016070Y+058790               S3      
327N/C              U35   -62         A01X+015755Y+059911X0100Y0360R090 S2      
327P1V9_LAN1        U35   -61         A01X+015755Y+060108X0100Y0360R090 S2      
327P1V05_LAN1       U35   -60         A01X+015755Y+060304X0100Y0360R090 S2      
327LAN1_DIS_REG10   U35   -59         A01X+015755Y+060501X0100Y0360R090 S2      
327LAN1_MDI0_DP     U35   -58         A01X+015755Y+060698X0100Y0360R090 S2      
327LAN1_MDI0_DN     U35   -57         A01X+015755Y+060895X0100Y0360R090 S2      
327P1V9_LAN1        U35   -56         A01X+015755Y+061092X0100Y0360R090 S2      
327LAN1_MDI1_DP     U35   -55         A01X+015755Y+061289X0100Y0360R090 S2      
327P1V9_LAN1        C427  -1          A10X+015090Y+061070X0180Y0200R180 S1      
327P1V9_LAN1        C406  -1          A10X+015081Y+059814X0180Y0200R180 S1      
327GND              C403  -2          A10X+016054Y+061093X0180Y0200     S1      
327P1V9_LAN1        C403  -1          A10X+015739Y+061093X0180Y0200     S1      
327GND              C417  -2          A10X+016051Y+060514X0180Y0200     S1      
327P1V05_LAN1       C417  -1          A10X+015736Y+060514X0180Y0200     S1      
327GND              C402  -2          A10X+016054Y+060093X0180Y0200     S1      
327P1V9_LAN1        C402  -1          A10X+015739Y+060093X0180Y0200     S1      
317LAN1_DIS_REG10   VIA   -     D0100PA00X+015038Y+060289               S1      
317P1V9_LAN1        VIA   -     D0100PA00X+015371Y+061092               S3      
317P1V9_LAN1        VIA   -     D0100PA00X+015333Y+059994               S3      
317P1V05_LAN1       VIA   -     D0100PA00X+015342Y+060304               S3      
327LAN1_MDI1_DN     U35   -54         A01X+015755Y+061485X0100Y0360R090 S2      
327LAN1_MDI2_DP     U35   -53         A01X+015755Y+061682X0100Y0360R090 S2      
327LAN1_MDI2_DN     U35   -52         A01X+015755Y+061879X0100Y0360R090 S2      
327P1V9_LAN1        U35   -51         A01X+015755Y+062076X0100Y0360R090 S2      
327LAN1_MDI3_DP     U35   -50         A01X+015755Y+062273X0100Y0360R090 S2      
327LAN1_MDI3_DN     U35   -49         A01X+015755Y+062470X0100Y0360R090 S2      
327LAN1_RST         U35   -48         A01X+016070Y+062785X0100Y0360R180 S2      
327P1V9_LAN1        U35   -47         A01X+016267Y+062785X0100Y0360R180 S2      
327P1V9_LAN1        C407  -1          A10X+015090Y+061904X0180Y0200R180 S1      
327P1V9_LAN1        C401  -1          A10X+015090Y+061474X0180Y0200R180 S1      
327GND              C408  -2          A10X+016416Y+062506X0180Y0200R270 S1      
327P1V9_LAN1        C408  -1          A10X+016416Y+062821X0180Y0200R270 S1      
327GND              C404  -2          A10X+016054Y+062093X0180Y0200     S1      
327P1V9_LAN1        C404  -1          A10X+015739Y+062093X0180Y0200     S1      
327GND              C411  -2          A10X+016061Y+061674X0180Y0200     S1      
327P1V9_LAN1        C411  -1          A10X+015746Y+061674X0180Y0200     S1      
327P1V9_LAN1        VIA   -           A10X+015244Y+062788X0260Y0260R090 S1      
317P1V9_LAN1        VIA   -     D0100PA00X+015396Y+062076               S3      
327LAN1_MDI3_DP     VIA   -           A01X+015036Y+062288X0160Y0041     S2      
327LAN1_RST         R559  -2          A01X+015796Y+063696X0180Y0200R090 S2      
327GND              R559  -1          A01X+015796Y+064011X0180Y0200R090 S2      
327N21311592        TP2   -1          A10X+016018Y+063904X0300Y0300R090 S1      
317GND              VIA   -     D0100PA00X+015796Y+064329               S3      
317LAN1_RST         VIA   -     D0100PA00X+015796Y+063374               S1      
317P1V9_LAN1        VIA   -     D0100PA00X+016267Y+063190               S3      
317N21311590        VIA   -     D0100PA00X+016253Y+064324               S3      
317N21311592        VIA   -     D0100PA00X+016253Y+063644               S3      
327LAN1_XTAL_IN     Y4    -1          A01X+016320Y+065343X0870Y0870     S2      
327P12V_DBG         R1070 -2          A01X+016481Y+066637X0180Y0200R090 S2      
327N53103066        R1070 -1          A01X+016481Y+066952X0180Y0200R090 S2      
317P12V_AUX         VIA   -     D0100PA00X+015192Y+067507               S3      
317P12V_AUX         VIA   -     D0100PA00X+015596Y+067481               S3      
317P12V_AUX         VIA   -     D0100PA00X+016011Y+067499               S3      
317P12V_AUX         VIA   -     D0100PA00X+016501Y+067589               S3      
317P12V_DBG         VIA   -     D0100PA00X+016481Y+066258               S3      
327P12V_AUX         C771  -1          A01X+015542Y+068754X0460Y0620     S2      
317P12V_AUX         VIA   -     D0100PA00X+015157Y+068758               S3      
317P12V_AUX         VIA   -     D0100PA00X+015565Y+068152               S3      
317P12V_AUX         VIA   -     D0100PA00X+016199Y+067845               S3      
317P12V_AUX         VIA   -     D0100PA00X+015959Y+068305               S3      
317P12V_AUX         VIA   -     D0100PA00X+015729Y+067814               S3      
317P12V_AUX         VIA   -     D0100PA00X+016517Y+068131               S3      
317P12V_AUX         VIA   -     D0100PA00X+015222Y+067839               S3      
317P12V_AUX         VIA   -     D0100PA00X+016010Y+068796               S3      
317P12V_AUX         VIA   -     D0100PA00X+016302Y+068438               S3      
317P12V_AUX         VIA   -     D0100PA00X+016409Y+068801               S3      
317P12V_AUX         VIA   -     D0100PA00X+015084Y+068244               S3      
327P12V_AUX         Q22   -3          A01X+016499Y+070554X0280Y0460R090 S2      
327P12V_AUX         Q22   -2          A01X+016499Y+070054X0280Y0460R090 S2      
327P12V_AUX         Q22   -1          A01X+016499Y+069554X0280Y0460R090 S2      
327NNAME10067       Q22   -4          A01X+016499Y+071054X0280Y0460R090 S2      
327NNAME10111       R1019 -2          A01X+016236Y+072044X0560Y0950R270 S2      
327P12V_PDB         D20   -3          A01X+015010Y+073458X0320Y0360     S2      
327N/C              D20   -2          A01X+015384Y+072671X0320Y0360     S2      
327P12V_PDB         R1019 -1          A01X+016236Y+073894X0560Y0950R270 S2      
317GND              VIA   -     D0100PA00X+014986Y+072663               S3      
317P12V_PDB         VIA   -     D0100PA00X+015497Y+073697               S3      
317P12V_PDB         VIA   -     D0100PA00X+016198Y+073078               S1      
317P12V_PDB         VIA   -     D0100PA00X+015888Y+073078               S3      
317P12V_PDB         VIA   -     D0100PA00X+016264Y+074393               S3      
317P12V_PDB         VIA   -     D0100PA00X+015897Y+074393               S3      
317P12V_PDB         VIA   -     D0100PA00X+015440Y+074434               S3      
317P12V_PDB         VIA   -     D0100PA00X+015523Y+074026               S3      
317UART_TX_P6_L     VIA   -     D0100PA00X+016314Y+077857               S1      
317NNAME10001       VIA   -     D0100PA00X+016048Y+077758               S3      
317UART_TX_P5_L     VIA   -     D0100PA00X+015517Y+078066               S1      
317UART_RX_P6_L     VIA   -     D0100PA00X+016463Y+078122               S3      
317NNAME10003       VIA   -     D0100PA00X+015332Y+078350               S3      
317UART_RX_P5_L     VIA   -     D0100PA00X+016032Y+078635               S1      
317NNAME10009       VIA   -     D0100PA00X+014981Y+078386               S3      
327NNAME10001       J35   -A56        A10X+015360Y+080787X0300Y1660R180 S1      
327UART_TX_P6_L     J35   -A55        A10X+015754Y+080787X0300Y1660R180 S1      
327UART_RX_P6_L     J35   -A54        A10X+016148Y+080787X0300Y1660R180 S1      
327NNAME10010       J35   -A53        A10X+016541Y+080787X0300Y1660R180 S1      
327NNAME10003       J35   -B56        A01X+015360Y+080787X0300Y1660R180 S2      
327UART_TX_P5_L     J35   -B55        A01X+015754Y+080787X0300Y1660R180 S2      
327UART_RX_P5_L     J35   -B54        A01X+016148Y+080787X0300Y1660R180 S2      
327NNAME10013       J35   -B53        A01X+016541Y+080787X0300Y1660R180 S2      
327GND              PC73  -2          A01X+018158Y+001135X0460Y0620R090 S2      
317GND              VIA   -     D0100PA00X+017924Y+000737               S3      
317GND              VIA   -     D0100PA00X+017131Y+001245               S3      
317GND              VIA   -     D0100PA00X+017167Y+000745               S3      
317GND              VIA   -     D0100PA00X+017528Y+001240               S3      
317GND              VIA   -     D0100PA00X+017417Y+000745               S3      
317GND              VIA   -     D0100PA00X+016664Y+001303               S3      
327NNAME10115       PQ2   -4          A01X+017694Y+002982X0170Y0220     S2      
327NNAME10115       PQ2   -3          A01X+017438Y+002982X0170Y0220     S2      
327NNAME10115       PQ2   -2          A01X+017182Y+002982X0170Y0220     S2      
327NNAME10119       PQ2   -1          A01X+016926Y+002982X0170Y0220     S2      
327GND              PC71  -2          A01X+017534Y+001491X0180Y0200R090 S2      
327NNAME10115       PC71  -1          A01X+017534Y+001806X0180Y0200R090 S2      
327GND              PC75  -2          A01X+017125Y+001487X0180Y0200R090 S2      
327NNAME10115       PC75  -1          A01X+017125Y+001802X0180Y0200R090 S2      
327NNAME10115       PC73  -1          A01X+018158Y+002295X0460Y0620R090 S2      
317NNAME10119       VIA   -     D0100PA00X+016896Y+002707               S1      
317NNAME10119       VIA   -     D0100PA00X+016596Y+002713               S3      
317NNAME10115       VIA   -     D0100PA00X+017311Y+002688               S3      
317NNAME10115       VIA   -     D0100PA00X+018091Y+002754               S3      
317NNAME10115       VIA   -     D0100PA00X+017609Y+002691               S3      
327GND              PQ2   --6-7       A01X+017438Y+004628X0689Y0226     S2      
327NNAME10118       PQ2   -8          A01X+016926Y+004628X0170Y0220     S2      
327NNAME10120       PQ2   -2_EP       A01X+017310Y+004035X0800Y0990R090 S2      
327NNAME10115       PQ2   -1_EP       A01X+017310Y+003337X0330Y0990R090 S2      
317NNAME10120       VIA   -     D0100PA00X+018016Y+004066               S1      
317NNAME10118       VIA   -     D0100PA00X+016534Y+004613               S1      
317GND              VIA   -     D0100PA00X+017722Y+004910               S3      
317GND              VIA   -     D0100PA00X+017472Y+004910               S3      
317GND              VIA   -     D0100PA00X+017722Y+005160               S3      
317GND              VIA   -     D0100PA00X+017472Y+005160               S3      
317GND              VIA   -     D0100PA00X+017222Y+004910               S3      
317GND              VIA   -     D0100PA00X+017222Y+005410               S3      
317GND              VIA   -     D0100PA00X+017722Y+005410               S3      
317GND              VIA   -     D0100PA00X+017472Y+005410               S3      
317GND              VIA   -     D0100PA00X+017222Y+005160               S3      
317GND              VIA   -     D0100PA00X+016915Y+005097               S3      
317NNAME10114       VIA   -     D0100PA00X+016804Y+006146               S3      
327NNAME10171       J2    -19         A01X+018012Y+008248X0150Y0810     S2      
327GND              J2    -17         A01X+017776Y+008248X0150Y0810     S2      
327NNAME10172       J2    -15         A01X+017539Y+008248X0150Y0810     S2      
327NNAME10173       J2    -13         A01X+017303Y+008248X0150Y0810     S2      
327PD_NODE1_DM0     J2    -11         A01X+017067Y+008248X0150Y0810     S2      
327GND              J2    -9          A01X+016831Y+008248X0150Y0810     S2      
327NNAME10174       J2    -7          A01X+016595Y+008248X0150Y0810     S2      
317GND              VIA   -     D0100PA00X+017776Y+008827               S3      
317GND              VIA   -     D0100PA00X+016831Y+008841               S3      
317NNAME10171       VIA   -     D0100PA00X+017773Y+009197               S3      
317NNAME10174       VIA   -     D0100PA00X+016738Y+009315               S1      
317GND              VIA   -     D0100PA00X+018099Y+010877               S3      
317GND              VIA   -     D0100PA00X+017721Y+009766               S3      
317GND              VIA   -     D0100PA00X+016569Y+009884               S3      
317GND              VIA   -     D0100PA00X+017195Y+010511               S3      
317NNAME10173       VIA   -     D0100PA00X+016885Y+009925               S1      
317NNAME10175       VIA   -     D0100PA00X+016951Y+010658               S1      
317NNAME10172       VIA   -     D0100PA00X+017390Y+009766               S3      
317NNAME10176       VIA   -     D0100PA00X+017768Y+010176               S3      
317NNAME10177       VIA   -     D0100PA00X+017471Y+010570               S1      
327NNAME10177       J2    -18         A01X+017894Y+011476X0150Y0810     S2      
327NNAME10175       J2    -16         A01X+017658Y+011476X0150Y0810     S2      
327GND              J2    -14         A01X+017421Y+011476X0150Y0810     S2      
327NNAME10178       J2    -12         A01X+017185Y+011476X0150Y0810     S2      
327NNAME10179       J2    -10         A01X+016949Y+011476X0150Y0810     S2      
327GND              J2    -8          A01X+016713Y+011476X0150Y0810     S2      
327NNAME10125       J2    -6          A01X+016477Y+011476X0150Y0810     S2      
317GND              VIA   -     D0100PA00X+016713Y+012060               S3      
317GND              VIA   -     D0100PA00X+017421Y+012057               S3      
317NNAME10180       VIA   -     D0100PA00X+017776Y+012106               S1      
317NNAME10179       VIA   -     D0100PA00X+016817Y+012337               S1      
317NNAME10178       VIA   -     D0100PA00X+017317Y+012337               S1      
317GND              VIA   -     D0100PA00X+018051Y+023331               S3      
317NNAME10181       VIA   -     D0100PA00X+017804Y+022898               S1      
327NNAME10182       C21   -2          A10X+017963Y+023640X0180Y0200R270 S1      
327NNAME10183       C21   -1          A10X+017963Y+023955X0180Y0200R270 S1      
327NNAME10184       C22   -2          A10X+017563Y+023640X0180Y0200R270 S1      
327NNAME10185       C22   -1          A10X+017563Y+023955X0180Y0200R270 S1      
327GND              U2    -BP1        A01X+016492Y+024681X0160Y0160     S2      
327GND              U2    -BM1        A01X+016492Y+025001X0160Y0160     S2      
327GND              U2    -BP3        A01X+016812Y+024681X0160Y0160     S2      
327GND              U2    -BP5        A01X+017132Y+024681X0160Y0160     S2      
327NNAME10126       U2    -BM3        A01X+016812Y+025001X0160Y0160     S2      
327NNAME10186       U2    -BM5        A01X+017132Y+025001X0160Y0160     S2      
327GND              U2    -BP6        A01X+017452Y+024681X0160Y0160     S2      
327GND              U2    -BP8        A01X+017772Y+024681X0110Y0135     S2      
327NNAME10187       U2    -BM7        A01X+017557Y+024998X0120Y0120     S2      
317GND              VIA   -     D0100PA00X+017414Y+024387               S3      
317GND              VIA   -     D0100PA00X+017132Y+024360               S3      
317GND              VIA   -     D0100PA00X+016747Y+024324               S3      
317NNAME10186       VIA   -     D0100PA00X+016748Y+023991               S1      
317NNAME10187       VIA   -     D0100PA00X+017789Y+024932               S1      
327GND              U2    -BG1        A01X+016492Y+025961X0135Y0110     S2      
327GND              U2    -BJ1        A01X+016492Y+025641X0160Y0160     S2      
327GND              U2    -BK1        A01X+016492Y+025321X0160Y0160     S2      
327NNAME10091       U2    -BH8        A01X+017881Y+025770X0120Y0120     S2      
327GND              U2    -BK5        A01X+017132Y+025321X0160Y0160     S2      
327GND              U2    -BK3        A01X+016812Y+025321X0160Y0160     S2      
327NNAME10188       U2    -BJ4        A01X+016968Y+025550X0120Y0120     S2      
327NNAME10189       U2    -BH3        A01X+016812Y+025780X0120Y0120     S2      
327GND              U2    -BG4        A01X+017027Y+025988X0120Y0120     S2      
327GND              U2    -BG5        A01X+017298Y+026055X0120Y0120     S2      
327GND              U2    -BH5        A01X+017318Y+025778X0120Y0120     S2      
327NNAME10190       U2    -BG8        A01X+017731Y+026023X0120Y0120     S2      
327GND              U2    -BD7        A01X+017581Y+026529X0120Y0120     S2      
327NNAME10090       U2    -BD8        A01X+017881Y+026529X0120Y0120     S2      
327NNAME10191       U2    -BF4        A01X+017110Y+026256X0120Y0120     S2      
327NNAME10128       U2    -BF3        A01X+016810Y+026276X0120Y0120     S2      
327NNAME10056       U2    -BD2        A01X+016633Y+026540X0120Y0120     S2      
327NNAME10055       U2    -BD4        A01X+017010Y+026519X0120Y0120     S2      
327NNAME10192       U2    -BE5        A01X+017298Y+026457X0120Y0120     S2      
327NNAME10127       U2    -BL7        A01X+017557Y+025298X0120Y0120     S2      
327GND              U2    -BK8        A01X+017758Y+025487X0120Y0120     S2      
327GND              U2    -BL8        A01X+017825Y+025216X0120Y0120     S2      
327GND              U2    -BK6        A01X+017356Y+025487X0120Y0120     S2      
317GND              VIA   -     D0100PA00X+017167Y+025629               S3      
317NNAME10091       VIA   -     D0100PA00X+017576Y+025767               S1      
327NNAME10089       VIA   -           A10X+017520Y+026568X0160Y0042     S1      
317NNAME10191       VIA   -     D0100PA00X+017326Y+026259               S3      
317NNAME10192       VIA   -     D0100PA00X+017630Y+026262               S3      
317NNAME10188       VIA   -     D0100PA00X+016732Y+025586               S3      
317NNAME10189       VIA   -     D0100PA00X+016770Y+026062               S3      
317NNAME10096       VIA   -     D0100PA00X+017893Y+026224               S3      
327NNAME10190       VIA   -           A10X+017050Y+025916X0260Y0260     S1      
317NNAME10190       VIA   -     D0100PA00X+017511Y+026041               S3      
327GND              U2    -AY8        A01X+017731Y+027311X0120Y0120     S2      
327GND              U2    -AW8        A01X+017731Y+027587X0120Y0120     S2      
327GND              U2    -BC7        A01X+017581Y+026805X0120Y0120     S2      
327NNAME10193       U2    -BC8        A01X+017881Y+026805X0120Y0120     S2      
327NNAME10094       U2    -BB2        A01X+016678Y+026960X0120Y0120     S2      
327NNAME10093       U2    -BB4        A01X+016968Y+026972X0120Y0120     S2      
327GND              U2    -BC3        A01X+016834Y+026732X0120Y0120     S2      
327NNAME10194       U2    -BB5        A01X+017243Y+027009X0120Y0120     S2      
327GND              U2    -BC5        A01X+017291Y+026736X0120Y0120     S2      
327NNAME10195       U2    -AY5        A01X+017243Y+027284X0120Y0120     S2      
327GND              U2    -AW5        A01X+017318Y+027551X0120Y0120     S2      
327NNAME10133       U2    -AY4        A01X+016968Y+027322X0120Y0120     S2      
327GND              U2    -AW3        A01X+016832Y+027563X0120Y0120     S2      
327NNAME10095       U2    -AY2        A01X+016677Y+027325X0120Y0120     S2      
327GND              U2    -AV5        A01X+017298Y+027828X0120Y0120     S2      
327GND              U2    -AV4        A01X+017027Y+027761X0120Y0120     S2      
327NNAME10099       U2    -AV2        A01X+016612Y+027730X0120Y0120     S2      
327NNAME10099       U2    -AU3        A01X+016810Y+028049X0120Y0120     S2      
327GND              U2    -AU4        A01X+017110Y+028029X0120Y0120     S2      
327N/C              U2    -AT8        A01X+017881Y+028093X0120Y0120     S2      
327GND              U2    -AT7        A01X+017581Y+028093X0120Y0120     S2      
317GND              VIA   -     D0100PA00X+017512Y+027429               S3      
317GND              VIA   -     D0100PA00X+017062Y+026733               S3      
317GND              VIA   -     D0100PA00X+017532Y+027869               S3      
317GND              VIA   -     D0100PA00X+017051Y+027552               S3      
317NNAME10196       VIA   -     D0100PA00X+017803Y+027902               S1      
317NNAME10195       VIA   -     D0100PA00X+017408Y+027144               S3      
317NNAME10194       VIA   -     D0100PA00X+017083Y+027145               S3      
327NNAME10130       VIA   -           A10X+016785Y+027024X0160Y0042     S1      
317NNAME10130       VIA   -     D0100PA00X+017882Y+027454               S3      
317NNAME10193       VIA   -     D0100PA00X+017894Y+027016               S3      
327GND              C39   -2          A10X+016630Y+029750X0280Y0320R180 S1      
327GND              R37   -2          A10X+016595Y+028535X0180Y0200R180 S1      
327NNAME10197       R37   -1          A10X+016910Y+028535X0180Y0200R180 S1      
327GND              R38   -2          A10X+016595Y+028935X0180Y0200R180 S1      
327NNAME10198       R38   -1          A10X+016910Y+028935X0180Y0200R180 S1      
327GND              U2    -AM8        A01X+017731Y+028875X0120Y0120     S2      
327GND              U2    -AP5        A01X+017291Y+028508X0120Y0120     S2      
327GND              U2    -AP3        A01X+016834Y+028504X0120Y0120     S2      
327NNAME10098       U2    -AR2        A01X+016633Y+028313X0120Y0120     S2      
327N/C              U2    -AR8        A01X+017881Y+028369X0120Y0120     S2      
327GND              U2    -AR7        A01X+017581Y+028369X0120Y0120     S2      
327NNAME10098       U2    -AT5        A01X+017298Y+028230X0120Y0120     S2      
327NNAME10099       U2    -AR4        A01X+017010Y+028292X0120Y0120     S2      
327NNAME10197       U2    -AN5        A01X+017243Y+028781X0120Y0120     S2      
327NNAME10099       U2    -AN4        A01X+016968Y+028745X0120Y0120     S2      
327NNAME10098       U2    -AN2        A01X+016678Y+028733X0120Y0120     S2      
327NNAME10099       U2    -AL2        A01X+016677Y+029098X0120Y0120     S2      
327NNAME10198       U2    -AL5        A01X+017243Y+029057X0120Y0120     S2      
327GND              U2    -AK5        A01X+017318Y+029324X0120Y0120     S2      
327GND              U2    -AK3        A01X+016832Y+029336X0120Y0120     S2      
327NNAME10098       U2    -AL4        A01X+016968Y+029095X0120Y0120     S2      
327GND              U2    -AL8        A01X+017731Y+029151X0120Y0120     S2      
327GND              U2    -AJ4        A01X+017027Y+029534X0120Y0120     S2      
327GND              U2    -AJ2        A01X+016612Y+029503X0120Y0120     S2      
327GND              U2    -AJ5        A01X+017298Y+029600X0120Y0120     S2      
327GND              U2    -AH7        A01X+017581Y+029657X0120Y0120     S2      
327N/C              U2    -AH8        A01X+017881Y+029657X0120Y0120     S2      
317GND              VIA   -     D0100PA00X+017747Y+029493               S3      
317GND              VIA   -     D0100PA00X+018025Y+029502               S3      
317GND              VIA   -     D0100PA00X+017516Y+029393               S3      
317GND              VIA   -     D0100PA00X+017566Y+028698               S3      
317NNAME10197       VIA   -     D0100PA00X+017881Y+028726               S1      
317NNAME10198       VIA   -     D0100PA00X+017415Y+028929               S1      
327P1V05_NODE1      C39   -1          A10X+016630Y+030330X0280Y0320R180 S1      
327NNAME10099       U2    -AH3        A01X+016810Y+029822X0120Y0120     S2      
327NNAME10098       U2    -AH4        A01X+017110Y+029802X0120Y0120     S2      
327NNAME10099       U2    -AG5        A01X+017298Y+030003X0120Y0120     S2      
327GND              U2    -AG7        A01X+017581Y+029933X0120Y0120     S2      
327N/C              U2    -AG8        A01X+017881Y+029933X0120Y0120     S2      
327GND              U2    -AD8        A01X+017731Y+030439X0120Y0120     S2      
327GND              U2    -AC8        A01X+017731Y+030715X0120Y0120     S2      
327GND              U2    -AE3        A01X+016834Y+030277X0120Y0120     S2      
327NNAME10099       U2    -AF4        A01X+017010Y+030065X0120Y0120     S2      
327NNAME10098       U2    -AF2        A01X+016633Y+030086X0120Y0120     S2      
327GND              U2    -AE5        A01X+017291Y+030281X0120Y0120     S2      
327NNAME10101       U2    -AB2        A01X+016677Y+030870X0120Y0120     S2      
327NNAME10101       U2    -AB5        A01X+017243Y+030830X0120Y0120     S2      
327NNAME10103       U2    -AD5        A01X+017243Y+030554X0120Y0120     S2      
327GND              U2    -AA5        A01X+017318Y+031097X0120Y0120     S2      
327GND              U2    -AA3        A01X+016832Y+031109X0120Y0120     S2      
327NNAME10103       U2    -AB4        A01X+016968Y+030868X0120Y0120     S2      
327NNAME10103       U2    -AD4        A01X+016968Y+030518X0120Y0120     S2      
327NNAME10101       U2    -AD2        A01X+016678Y+030506X0120Y0120     S2      
327N/C              U2    -Y8         A01X+017881Y+031221X0120Y0120     S2      
327GND              U2    -Y7         A01X+017581Y+031221X0120Y0120     S2      
327GND              U2    -Y4         A01X+017027Y+031307X0120Y0120     S2      
327NNAME10105       U2    -Y2         A01X+016612Y+031275X0120Y0120     S2      
317GND              VIA   -     D0100PA00X+017604Y+030985               S3      
317GND              VIA   -     D0100PA00X+018025Y+031066               S3      
327P1V05_NODE1      VIA   -           A10X+018041Y+030487X0260Y0260     S1      
327P1V05_NODE1      VIA   -           A10X+017299Y+030572X0260Y0260     S1      
317P1V05_NODE1      VIA   -     D0100PA00X+017592Y+030192               S3      
317P1V05_NODE1      VIA   -     D0100PA00X+017892Y+030192               S3      
327N/C              U2    -W8         A01X+017881Y+031497X0120Y0120     S2      
327GND              U2    -W7         A01X+017581Y+031497X0120Y0120     S2      
327GND              U2    -Y5         A01X+017298Y+031373X0120Y0120     S2      
327GND              U2    -U8         A01X+017731Y+032003X0120Y0120     S2      
327GND              U2    -R8         A01X+017731Y+032279X0120Y0120     S2      
327GND              U2    -N7         A01X+017581Y+032785X0120Y0120     S2      
327N/C              U2    -N8         A01X+017881Y+032785X0120Y0120     S2      
327GND              U2    -T5         A01X+017291Y+032054X0120Y0120     S2      
327NNAME10101       U2    -V5         A01X+017298Y+031775X0120Y0120     S2      
327GND              U2    -T3         A01X+016834Y+032050X0120Y0120     S2      
327NNAME10101       U2    -U4         A01X+017010Y+031838X0120Y0120     S2      
327NNAME10103       U2    -U2         A01X+016633Y+031858X0120Y0120     S2      
327GND              U2    -W3         A01X+016810Y+031594X0120Y0120     S2      
327NNAME10103       U2    -W4         A01X+017110Y+031574X0120Y0120     S2      
327NNAME10103       U2    -N2         A01X+016677Y+032643X0120Y0120     S2      
327NNAME10103       U2    -R5         A01X+017243Y+032327X0120Y0120     S2      
327NNAME10101       U2    -R4         A01X+016968Y+032291X0120Y0120     S2      
327NNAME10103       U2    -R2         A01X+016678Y+032278X0120Y0120     S2      
327NNAME10101       U2    -N4         A01X+016968Y+032641X0120Y0120     S2      
327GND              U2    -M3         A01X+016832Y+032881X0120Y0120     S2      
327GND              U2    -M5         A01X+017318Y+032870X0120Y0120     S2      
327NNAME10101       U2    -N5         A01X+017243Y+032603X0120Y0120     S2      
317GND              VIA   -     D0100PA00X+017881Y+032426               S3      
317GND              VIA   -     D0100PA00X+018034Y+031647               S3      
317GND              VIA   -     D0100PA00X+017533Y+031855               S3      
327NNAME10135       U2    -H1         A01X+016492Y+033724X0135Y0110     S2      
327NNAME10134       U2    -F1         A01X+016492Y+034044X0160Y0160     S2      
327GND              U2    -G7         A01X+017581Y+033843X0120Y0120     S2      
327GND              U2    -L7         A01X+017581Y+033061X0120Y0120     S2      
327GND              U2    -L8         A01X+017881Y+033061X0120Y0120     S2      
327NNAME10106       U2    -L2         A01X+016612Y+033048X0120Y0120     S2      
327NNAME10102       U2    -L4         A01X+017027Y+033080X0120Y0120     S2      
327GND              U2    -L5         A01X+017298Y+033146X0120Y0120     S2      
327NNAME10102       U2    -K4         A01X+017110Y+033347X0120Y0120     S2      
327NNAME10106       U2    -K3         A01X+016810Y+033367X0120Y0120     S2      
327GND              U2    -H4         A01X+017027Y+033615X0120Y0120     S2      
327GND              U2    -G3         A01X+016812Y+033823X0120Y0120     S2      
327GND              U2    -J5         A01X+017298Y+033548X0120Y0120     S2      
327NNAME10102       U2    -G5         A01X+017291Y+033827X0120Y0120     S2      
327NNAME10106       U2    -F5         A01X+017243Y+034100X0120Y0120     S2      
327GND              U2    -F4         A01X+016968Y+034054X0120Y0120     S2      
327GND              U2    -E9         A01X+017955Y+034205X0120Y0120     S2      
327GND              U2    -E7         A01X+017677Y+034198X0120Y0120     S2      
327NNAME10102       U2    -H9         A01X+017958Y+033615X0120Y0120     S2      
327NNAME10106       U2    -G9         A01X+017958Y+033915X0120Y0120     S2      
327GND              U2    -E1         A01X+016492Y+034364X0160Y0160     S2      
327GND              U2    -E5         A01X+017132Y+034364X0160Y0160     S2      
327GND              U2    -E3         A01X+016812Y+034364X0160Y0160     S2      
327GND              U2    -D6         A01X+017476Y+034387X0120Y0120     S2      
327GND              U2    -D8         A01X+017743Y+034469X0120Y0120     S2      
317GND              VIA   -     D0100PA00X+016619Y+033529               S3      
317GND              VIA   -     D0100PA00X+016738Y+034131               S3      
317GND              VIA   -     D0100PA00X+017736Y+033255               S3      
317GND              VIA   -     D0100PA00X+017488Y+033655               S3      
327GND              U2    -A8         A01X+017772Y+035004X0110Y0135     S2      
327GND              U2    -A6         A01X+017452Y+035004X0160Y0160     S2      
327GND              U2    -A5         A01X+017132Y+035004X0160Y0160     S2      
327GND              U2    -C3         A01X+016812Y+034684X0160Y0160     S2      
327GND              U2    -C5         A01X+017132Y+034684X0160Y0160     S2      
327GND              U2    -C9         A01X+017952Y+034662X0120Y0120     S2      
327GND              U2    -C6         A01X+017476Y+034687X0120Y0120     S2      
317GND              VIA   -     D0100PA00X+016811Y+035064               S1      
317GND              VIA   -     D0100PA00X+017760Y+035516               S3      
317GND              VIA   -     D0100PA00X+017772Y+035252               S3      
317GND              VIA   -     D0100PA00X+017703Y+034781               S3      
317GND              VIA   -     D0100PA00X+017767Y+035810               S3      
327NNAME10199       C31   -2          A10X+017606Y+037008X0180Y0200R270 S1      
327GND              C31   -1          A10X+017606Y+037323X0180Y0200R270 S1      
327NNAME10200       C29   -2          A10X+016806Y+037008X0180Y0200R270 S1      
327GND              C29   -1          A10X+016806Y+037323X0180Y0200R270 S1      
327NNAME10069       R132  -2          A10X+018006Y+037323X0180Y0200R090 S1      
327NNAME10199       R132  -1          A10X+018006Y+037008X0180Y0200R090 S1      
327NNAME10006       R128  -2          A10X+017206Y+037323X0180Y0200R090 S1      
327NNAME10200       R128  -1          A10X+017206Y+037008X0180Y0200R090 S1      
317GND              VIA   -     D0100PA00X+017606Y+037657               S3      
317GND              VIA   -     D0100PA00X+016806Y+037604               S3      
327NNAME10200       VIA   -           A10X+017486Y+036242X0260Y0260     S1      
327NNAME10069       R133  -2          A10X+017980Y+038062X0180Y0200R270 S1      
327P3V3_NODE1       R133  -1          A10X+017980Y+038377X0180Y0200R270 S1      
327NNAME10006       R129  -2          A10X+017193Y+038073X0180Y0200R270 S1      
327P3V3_NODE1       R129  -1          A10X+017193Y+038388X0180Y0200R270 S1      
317GND              VIA   -     D0100PA00X+016795Y+038055               S3      
317GND              VIA   -     D0100PA00X+017529Y+038958               S3      
317GND              VIA   -     D0100PA00X+017450Y+038338               S3      
317P3V3_NODE1       VIA   -     D0100PA00X+017866Y+038842               S3      
317P3V3_NODE1       VIA   -     D0100PA00X+017193Y+038636               S3      
317NNAME10006       VIA   -     D0100PA00X+017516Y+038073               S3      
317NNAME10201       VIA   -     D0100PA00X+018043Y+039297               S1      
317NNAME10069       VIA   -     D0100PA00X+017566Y+038642               S3      
327NNAME10202       R198  -2          A01X+017936Y+040157X0180Y0200R090 S2      
327P3V3_NODE1       R198  -1          A01X+017936Y+040472X0180Y0200R090 S2      
317P3V3_NODE1       VIA   -     D0100PA00X+017637Y+040472               S3      
317NNAME10203       VIA   -     D0100PA00X+018044Y+039806               S1      
317CPU_RSV_1        VIA   -     D0100PA00X+017276Y+040654               S3      
327GND              PC20  -1          A01X+016786Y+042415X0180Y0200R270 S2      
327NNAME10204       PR5   -2          A01X+017199Y+042077X0180Y0200R270 S2      
327NNAME10205       PR5   -1          A01X+017199Y+041762X0180Y0200R270 S2      
327GND              PR6   -2          A01X+017599Y+041762X0180Y0200R090 S2      
327NNAME10204       PR6   -1          A01X+017599Y+042077X0180Y0200R090 S2      
327NNAME10206       PJ2   -2          A01X+017954Y+042148X0180Y0200R270 S2      
327NNAME10207       PJ2   -1          A01X+017954Y+041833X0200Y0400R180 S2      
317GND              VIA   -     D0100PA00X+017051Y+042413               S3      
317GND              VIA   -     D0100PA00X+017599Y+041492               S3      
317NNAME10205       VIA   -     D0100PA00X+016753Y+042027               S1      
317NNAME10206       VIA   -     D0100PA00X+017956Y+042400               S1      
317NNAME10204       VIA   -     D0100PA00X+017338Y+042401               S3      
327GND              PU2   -TH         A01X+018055Y+043298X0670Y0670R090 S2      
327P3V3_STB_NODE1   PU2   -16         A01X+017759Y+043879X0100Y0330     S2      
327P5V_STB_NODE1    PU2   -15         A01X+017956Y+043879X0100Y0330     S2      
327NNAME10206       PU2   -6          A01X+017956Y+042718X0100Y0330     S2      
327NNAME10204       PU2   -5          A01X+017759Y+042718X0100Y0330     S2      
327GND              PU2   -4          A01X+017474Y+043003X0100Y0330R090 S2      
327NNAME10208       PU2   -3          A01X+017474Y+043200X0100Y0330R090 S2      
327NNAME10205       PU2   -2          A01X+017474Y+043397X0100Y0330R090 S2      
327NNAME10139       PU2   -1          A01X+017474Y+043594X0100Y0330R090 S2      
327NNAME10205       PC19  -1          A01X+016760Y+043252X0180Y0200     S2      
327NNAME10208       PC20  -2          A01X+016786Y+042730X0180Y0200R270 S2      
327NNAME10139       PR8   -1          A01X+016740Y+043683X0180Y0200     S2      
317GND              VIA   -     D0100PA00X+017823Y+043064               S3      
317GND              VIA   -     D0100PA00X+017822Y+043532               S3      
317GND              VIA   -     D0100PA00X+017315Y+042755               S3      
317NNAME10139       VIA   -     D0100PA00X+017068Y+043683               S1      
317NNAME10208       VIA   -     D0100PA00X+017036Y+042860               S1      
327P3V3_STB_NODE1   PC21  -2          A01X+016792Y+044108X0180Y0200R180 S2      
327GND              PC14  -2          A01X+017310Y+044474X0180Y0200     S2      
327P5V_STB_NODE1    PC14  -1          A01X+017625Y+044474X0180Y0200     S2      
327P3V3_STB_NODE1   PR7   -2          A01X+016792Y+044503X0180Y0200R180 S2      
317GND              VIA   -     D0100PA00X+017294Y+044839               S3      
317GND              VIA   -     D0100PA00X+017044Y+044839               S3      
317P12V_AUX         VIA   -     D0100PA00X+017753Y+045195               S3      
317P12V_AUX         VIA   -     D0100PA00X+018013Y+045195               S3      
317P5V_STB_NODE1    VIA   -     D0100PA00X+017896Y+044814               S3      
317P5V_STB_NODE1    VIA   -     D0100PA00X+017622Y+044825               S3      
317NNAME10059       VIA   -     D0100PA00X+017162Y+046780               S3      
327P3V3_NODE1       U16   -5          A01X+017389Y+048255X0130Y0460R090 S2      
327NNAME10209       U16   -2          A01X+018147Y+048511X0130Y0460R090 S2      
327N/C              U16   -1          A01X+018147Y+048255X0130Y0460R090 S2      
327P3V3_NODE1       C225  -2          A01X+017265Y+047779X0180Y0200     S2      
327GND              C225  -1          A01X+017580Y+047779X0180Y0200     S2      
327NNAME10063       R259  -2          A01X+016665Y+048454X0180Y0200R090 S2      
317GND              VIA   -     D0100PA00X+017986Y+047779               S3      
317P3V3_NODE1       VIA   -     D0100PA00X+016837Y+047779               S3      
317NNAME10141       VIA   -     D0100PA00X+016973Y+048766               S1      
327NNAME10141       U16   -4          A01X+017389Y+048766X0130Y0460R090 S2      
327GND              U16   -3          A01X+018147Y+048766X0130Y0460R090 S2      
327NNAME10141       R259  -1          A01X+016665Y+048769X0180Y0200R090 S2      
327NNAME10063       VIA   -           A10X+016597Y+049763X0260Y0260R090 S1      
327NNAME10063       VIA   -           A10X+017691Y+050115X0260Y0260R090 S1      
327NNAME10210       U15   -T8         A01X+017966Y+050773X0145Y0145     S2      
327NNAME10211       U15   -T7         A01X+017651Y+050773X0145Y0145     S2      
327NNAME10212       U15   -R8         A01X+017966Y+051088X0145Y0145     S2      
327NNAME10213       U15   -R7         A01X+017651Y+051088X0145Y0145     S2      
327NNAME10214       U15   -P8         A01X+017966Y+051403X0145Y0145     S2      
327NNAME10215       U15   -P7         A01X+017651Y+051403X0145Y0145     S2      
327NNAME10216       U15   -N8         A01X+017966Y+051718X0145Y0145     S2      
327NNAME10217       U15   -N7         A01X+017651Y+051718X0145Y0145     S2      
317NNAME10149       VIA   -     D0100PA00X+016819Y+051433               S1      
317NNAME10109       VIA   -     D0100PA00X+017809Y+051876               S3      
317NNAME10215       VIA   -     D0100PA00X+017809Y+051246               S1      
317NNAME10218       VIA   -     D0100PA00X+017325Y+051569               S1      
317NNAME10140       VIA   -     D0100PA00X+016571Y+050616               S1      
317NNAME10217       VIA   -     D0100PA00X+017209Y+051054               S1      
317NNAME10148       VIA   -     D0100PA00X+016962Y+051922               S1      
327NNAME10109       U15   -M8         A01X+017966Y+052033X0145Y0145     S2      
327NNAME10219       U15   -M7         A01X+017651Y+052033X0145Y0145     S2      
327NNAME10220       U15   -L8         A01X+017966Y+052348X0145Y0145     S2      
327NNAME10218       U15   -L7         A01X+017651Y+052348X0145Y0145     S2      
327NNAME10063       U15   -K8         A01X+017966Y+052663X0145Y0145     S2      
327NNAME10221       U15   -K7         A01X+017651Y+052663X0145Y0145     S2      
327GND              U15   -J8         A01X+017966Y+052978X0145Y0145     S2      
327NNAME10222       U15   -J7         A01X+017651Y+052978X0145Y0145     S2      
327NNAME10223       U15   -H8         A01X+017966Y+053293X0145Y0145     S2      
327NNAME10224       U15   -H7         A01X+017651Y+053293X0145Y0145     S2      
327NNAME10109       C223  -2          A10X+018063Y+052005X0180Y0200R180 S1      
327NNAME10220       R260  -1          A10X+017840Y+052414X0180Y0200     S1      
317NNAME10224       VIA   -     D0100PA00X+017809Y+053137               S1      
317NNAME10157       VIA   -     D0100PA00X+016630Y+053242               S1      
317NNAME10155       VIA   -     D0100PA00X+016949Y+052970               S1      
317NNAME10153       VIA   -     D0100PA00X+016862Y+052576               S3      
317NNAME10150       VIA   -     D0100PA00X+016684Y+052349               S1      
317NNAME10146       VIA   -     D0100PA00X+017237Y+051978               S3      
317NNAME10222       VIA   -     D0100PA00X+017472Y+053136               S3      
317NNAME10221       VIA   -     D0100PA00X+017440Y+052798               S1      
317NNAME10220       VIA   -     D0100PA00X+017161Y+052751               S3      
327NNAME10220       VIA   -           A10X+017351Y+052285X0260Y0260R090 S1      
317NNAME10063       VIA   -     D0100PA00X+017812Y+052819               S3      
327GND              U15   -G8         A01X+017966Y+053608X0145Y0145     S2      
327NNAME10063       U15   -G7         A01X+017651Y+053608X0145Y0145     S2      
327NNAME10225       U15   -F8         A01X+017966Y+053923X0145Y0145     S2      
327NNAME10226       U15   -F7         A01X+017651Y+053923X0145Y0145     S2      
327GND              U15   -E8         A01X+017966Y+054238X0145Y0145     S2      
327NNAME10227       U15   -E7         A01X+017651Y+054238X0145Y0145     S2      
327GND              U15   -D8         A01X+017966Y+054553X0145Y0145     S2      
327NNAME10228       U15   -D7         A01X+017651Y+054553X0145Y0145     S2      
327NNAME10229       U15   -C8         A01X+017966Y+054868X0145Y0145     S2      
327NNAME10230       U15   -C7         A01X+017651Y+054868X0145Y0145     S2      
327GND              C231  -2          A10X+017595Y+053965X0180Y0200     S1      
327NNAME10063       C231  -1          A10X+017280Y+053965X0180Y0200     S1      
317GND              VIA   -     D0100PA00X+017808Y+053765               S3      
317NNAME10230       VIA   -     D0100PA00X+017810Y+055027               S3      
317NNAME10226       VIA   -     D0100PA00X+017411Y+054229               S3      
317NNAME10161       VIA   -     D0100PA00X+016824Y+054271               S1      
317NNAME10228       VIA   -     D0100PA00X+017493Y+054711               S1      
317NNAME10160       VIA   -     D0100PA00X+016703Y+053953               S3      
317NNAME10158       VIA   -     D0100PA00X+016703Y+053638               S3      
317NNAME10227       VIA   -     D0100PA00X+016916Y+054868               S1      
317NNAME10063       VIA   -     D0100PA00X+017322Y+053656               S3      
327NNAME10231       U15   -B8         A01X+017966Y+055183X0145Y0145     S2      
327NNAME10232       U15   -B7         A01X+017651Y+055183X0145Y0145     S2      
327NNAME10063       U15   -A8         A01X+017966Y+055498X0145Y0145     S2      
327NNAME10233       U15   -A7         A01X+017651Y+055498X0145Y0145     S2      
317GND              VIA   -     D0100PA00X+016929Y+056236               S3      
317NNAME10233       VIA   -     D0100PA00X+017316Y+055190               S1      
317NNAME10166       VIA   -     D0100PA00X+016944Y+055876               S1      
317NNAME10164       VIA   -     D0100PA00X+016711Y+055288               S1      
317NNAME10232       VIA   -     D0100PA00X+017808Y+055340               S1      
317NNAME10163       VIA   -     D0100PA00X+017289Y+056271               S1      
327NNAME10234       R544  -2          A01X+017926Y+057571X0180Y0200R270 S2      
327P3V3_NODE1       R544  -1          A01X+017926Y+057256X0180Y0200R270 S2      
327NNAME10235       R556  -2          A01X+017093Y+057571X0180Y0200R270 S2      
327GND              R556  -1          A01X+017093Y+057256X0180Y0200R270 S2      
327NNAME10236       R548  -2          A01X+016666Y+057561X0180Y0200R270 S2      
327P3V3_NODE1       R548  -1          A01X+016666Y+057246X0180Y0200R270 S2      
327NNAME10237       R546  -2          A01X+017526Y+057571X0180Y0200R270 S2      
327P3V3_NODE1       R546  -1          A01X+017526Y+057256X0180Y0200R270 S2      
317GND              VIA   -     D0100PA00X+017105Y+056941               S3      
317NNAME10237       VIA   -     D0100PA00X+017533Y+057854               S1      
317NNAME10236       VIA   -     D0100PA00X+016693Y+057844               S1      
317P3V3_NODE1       VIA   -     D0100PA00X+016679Y+056906               S1      
317P3V3_NODE1       VIA   -     D0100PA00X+017539Y+056959               S3      
317P3V3_NODE1       VIA   -     D0100PA00X+017974Y+056895               S3      
327P3V3_NODE1       U35   -10         A01X+017842Y+059202X0100Y0360     S2      
327NNAME10234       U35   -9          A01X+017645Y+059202X0100Y0360     S2      
327NNAME10237       U35   -8          A01X+017448Y+059202X0100Y0360     S2      
327NNAME10235       U35   -7          A01X+017251Y+059202X0100Y0360     S2      
327NNAME10236       U35   -6          A01X+017054Y+059202X0100Y0360     S2      
327NNAME10169       U35   -5          A01X+016857Y+059202X0100Y0360     S2      
327P1V05_LAN1       U35   -4          A01X+016661Y+059202X0100Y0360     S2      
327NNAME10170       U35   -3          A01X+016464Y+059202X0100Y0360     S2      
327GND              C419  -2          A10X+016933Y+059301X0180Y0200R090 S1      
327P1V05_LAN1       C419  -1          A10X+016933Y+058986X0180Y0200R090 S1      
327GND              C396  -2          A10X+017626Y+059311X0180Y0200R090 S1      
327P3V3_NODE1       C396  -1          A10X+017626Y+058996X0180Y0200R090 S1      
317NNAME10235       VIA   -     D0100PA00X+017243Y+058404               S1      
317NNAME10234       VIA   -     D0100PA00X+017783Y+058354               S1      
317NNAME10169       VIA   -     D0100PA00X+016657Y+058387               S1      
317P1V05_LAN1       VIA   -     D0100PA00X+016661Y+058786               S3      
317P3V3_NODE1       VIA   -     D0100PA00X+017842Y+058785               S3      
327GND              U35   -TH         A01X+017546Y+060993X2130Y2130R090 S2      
317GND              VIA   -     D0100PA00X+017953Y+060044               S3      
317GND              VIA   -     D0100PA00X+017343Y+060044               S3      
317GND              VIA   -     D0100PA00X+016583Y+060034               S3      
317GND              VIA   -     D0100PA00X+016583Y+060604               S3      
317GND              VIA   -     D0100PA00X+016583Y+061314               S3      
327N21311592        U35   -46         A01X+016464Y+062785X0100Y0360R180 S2      
327N21311590        U35   -45         A01X+016661Y+062785X0100Y0360R180 S2      
327P1V9_LAN1        U35   -44         A01X+016857Y+062785X0100Y0360R180 S2      
327LAN1_XTAL_IN     U35   -43         A01X+017054Y+062785X0100Y0360R180 S2      
327LAN1_XTAL_OUT    U35   -42         A01X+017251Y+062785X0100Y0360R180 S2      
327P1V05_LAN1       U35   -41         A01X+017448Y+062785X0100Y0360R180 S2      
327PU_LAN1_TDI      U35   -40         A01X+017645Y+062785X0100Y0360R180 S2      
327LAN1_AUX_PWR     U35   -39         A01X+017842Y+062785X0100Y0360R180 S2      
327GND              C418  -2          A10X+017683Y+062506X0180Y0200R270 S1      
327P1V05_LAN1       C418  -1          A10X+017683Y+062821X0180Y0200R270 S1      
327GND              C425  -2          A10X+017253Y+062506X0180Y0200R270 S1      
327P1V9_LAN1        C425  -1          A10X+017253Y+062821X0180Y0200R270 S1      
327GND              C409  -2          A10X+016843Y+062496X0180Y0200R270 S1      
327P1V9_LAN1        C409  -1          A10X+016843Y+062811X0180Y0200R270 S1      
317GND              VIA   -     D0100PA00X+017253Y+061954               S3      
317GND              VIA   -     D0100PA00X+017863Y+061944               S3      
317GND              VIA   -     D0100PA00X+016583Y+061944               S3      
327GND              C400  -2          A01X+017704Y+064393X0180Y0200R180 S2      
327LAN1_XTAL_OUT    C400  -1          A01X+017389Y+064393X0180Y0200R180 S2      
327GND              C399  -2          A01X+016639Y+064393X0180Y0200     S2      
327LAN1_XTAL_IN     C399  -1          A01X+016954Y+064393X0180Y0200     S2      
327N21311590        TP1   -1          A10X+016580Y+064381X0300Y0300R090 S1      
317PU_LAN1_TDI      VIA   -     D0100PA00X+017912Y+063962               S1      
317LAN1_XTAL_IN     VIA   -     D0100PA00X+016993Y+063533               S1      
317LAN1_XTAL_OUT    VIA   -     D0100PA00X+017251Y+063977               S1      
317P1V9_LAN1        VIA   -     D0100PA00X+016753Y+063194               S3      
317P1V05_LAN1       VIA   -     D0100PA00X+017448Y+063199               S3      
327LAN1_XTAL_OUT    Y4    -2          A01X+017973Y+065343X0870Y0870     S2      
317GND              VIA   -     D0100PA00X+017704Y+064714               S3      
317GND              VIA   -     D0100PA00X+016639Y+064744               S3      
317GND              VIA   -     D0100PA00X+017118Y+065201               S3      
317GND              VIA   -     D0100PA00X+017127Y+065565               S3      
327PSU_DC_OK_N      U114  -D          A01X+017942Y+066782X0400Y0500R270 S2      
327GND              U114  -S          A01X+017062Y+066382X0400Y0500R270 S2      
327N53103066        U114  -G          A01X+017062Y+067182X0400Y0500R270 S2      
317GND              VIA   -     D0100PA00X+017918Y+067521               S3      
317GND              VIA   -     D0100PA00X+017476Y+066382               S3      
317N53103066        VIA   -     D0100PA00X+016781Y+066813               S1      
327P12V_AUX_EN      U92   -D          A01X+017518Y+068833X0400Y0500     S2      
327GND              U92   -S          A01X+017918Y+067953X0400Y0500     S2      
327PSU_DC_OK_N      U92   -G          A01X+017118Y+067953X0400Y0500     S2      
317P12V_AUX         VIA   -     D0100PA00X+016865Y+068806               S3      
317P12V_AUX         VIA   -     D0100PA00X+016563Y+069129               S3      
317P12V_AUX         VIA   -     D0100PA00X+016732Y+068494               S3      
317P12V_AUX_EN      VIA   -     D0100PA00X+017898Y+068863               S3      
317PSU_DC_OK_N      VIA   -     D0100PA00X+017118Y+068382               S1      
327GND              C774  -2          A01X+017562Y+070598X0180Y0200R180 S2      
327P12V_AUX         C774  -1          A01X+017247Y+070598X0180Y0200R180 S2      
327GND              C772  -2          A01X+017562Y+070198X0180Y0200R180 S2      
327P12V_AUX         C772  -1          A01X+017247Y+070198X0180Y0200R180 S2      
327GND              C773  -2          A01X+017562Y+069798X0180Y0200R180 S2      
327P12V_AUX         C773  -1          A01X+017247Y+069798X0180Y0200R180 S2      
327P12V_PDB         R1006 -2          A01X+017829Y+069404X0180Y0200R180 S2      
327P12V_AUX_EN      R1006 -1          A01X+017514Y+069404X0180Y0200R180 S2      
317GND              VIA   -     D0100PA00X+017828Y+070598               S3      
317GND              VIA   -     D0100PA00X+017828Y+070198               S3      
317GND              VIA   -     D0100PA00X+017828Y+069798               S3      
317P12V_AUX         VIA   -     D0100PA00X+016927Y+070530               S3      
317P12V_AUX         VIA   -     D0100PA00X+016940Y+070101               S3      
317P12V_AUX         VIA   -     D0100PA00X+016927Y+069740               S3      
317P12V_AUX         VIA   -     D0100PA00X+016962Y+069334               S3      
327GND              C775  -2          A01X+017562Y+070998X0180Y0200R180 S2      
327P12V_AUX         C775  -1          A01X+017247Y+070998X0180Y0200R180 S2      
327P12V_AUX_EN      U93   -D          A01X+017569Y+071567X0400Y0500R180 S2      
327GND              U93   -S          A01X+017169Y+072447X0400Y0500R180 S2      
327MATE_N           U93   -G          A01X+017969Y+072447X0400Y0500R180 S2      
317GND              VIA   -     D0100PA00X+017828Y+070998               S3      
317MATE_N           VIA   -     D0100PA00X+018082Y+071791               S1      
317P12V_AUX_EN      VIA   -     D0100PA00X+017115Y+071567               S3      
317NNAME10067       VIA   -     D0100PA00X+016953Y+071054               S3      
317NNAME10238       VIA   -     D0100PA00X+017546Y+072025               S1      
327GND              C604  -2          A01X+018008Y+073052X0180Y0200R180 S2      
327MATE_N           C604  -1          A01X+017693Y+073052X0180Y0200R180 S2      
327MATE_N           R1007 -2          A01X+017246Y+073278X0180Y0200R090 S2      
327P12V_PDB         R1007 -1          A01X+017246Y+073593X0180Y0200R090 S2      
327MATE_N           R835  -2          A10X+017969Y+072647X0180Y0200R270 S1      
327MATE_R_N         R835  -1          A10X+017969Y+072962X0180Y0200R270 S1      
317GND              VIA   -     D0100PA00X+017169Y+072892               S3      
317P12V_PDB         VIA   -     D0100PA00X+016560Y+073048               S3      
317MATE_R_N         VIA   -     D0100PA00X+017495Y+072840               S1      
317NNAME10000       VIA   -     D0100PA00X+017792Y+073930               S3      
317P12V_PDB         VIA   -     D0100PA00X+016757Y+074334               S1      
327PSU6_DC_OK_R     VIA   -           A10X+017707Y+078574X0260Y0260     S1      
317PSU6_AC_OK_R     VIA   -     D0100PA00X+017722Y+077777               S1      
317NNAME10011       VIA   -     D0100PA00X+016935Y+078547               S3      
317NNAME10008       VIA   -     D0100PA00X+017260Y+078015               S3      
317NNAME10013       VIA   -     D0100PA00X+016986Y+078209               S1      
317NNAME10010       VIA   -     D0100PA00X+016735Y+077807               S3      
327NNAME10008       J35   -A52        A10X+016935Y+080787X0300Y1660R180 S1      
327GND              J35   -A51        A10X+017329Y+080787X0300Y1660R180 S1      
327PSU6_DC_OK_R     J35   -A50        A10X+017722Y+080787X0300Y1660R180 S1      
327PSU5_DC_OK_R     J35   -A49        A10X+018116Y+080787X0300Y1660R180 S1      
327NNAME10011       J35   -B52        A01X+016935Y+080787X0300Y1660R180 S2      
327GND              J35   -B51        A01X+017329Y+080787X0300Y1660R180 S2      
327PSU6_AC_OK_R     J35   -B50        A01X+017722Y+080787X0300Y1660R180 S2      
327PSU5_AC_OK_R     J35   -B49        A01X+018116Y+080787X0300Y1660R180 S2      
317GND              VIA   -     D0100PA00X+017329Y+079170               S3      
317GND              VIA   -     D0100PA00X+017329Y+078870               S3      
327GND              PC72  -2          A01X+019001Y+001154X0460Y0620R090 S2      
317GND              VIA   -     D0100PA00X+018924Y+000737               S3      
317GND              VIA   -     D0100PA00X+019174Y+000737               S3      
317GND              VIA   -     D0100PA00X+018174Y+000737               S3      
317P12V_AUX         VIA   -     D0100PA00X+019483Y+001020               S3      
317P12V_AUX         VIA   -     D0100PA00X+019486Y+001295               S3      
327NNAME10115       PC72  -1          A01X+019001Y+002314X0460Y0620R090 S2      
317NNAME10115       VIA   -     D0100PA00X+018341Y+002754               S3      
317NNAME10115       VIA   -     D0100PA00X+018863Y+002786               S3      
317NNAME10115       VIA   -     D0100PA00X+019160Y+002762               S1      
327NNAME10120       PL7   -1          A01X+018666Y+004316X0848Y1300     S2      
327NNAME10181       J2    -31         A01X+019429Y+008248X0150Y0810     S2      
327GND              J2    -29         A01X+019193Y+008248X0150Y0810     S2      
327NNAME10239       J2    -27         A01X+018957Y+008248X0150Y0810     S2      
327NNAME10240       J2    -25         A01X+018721Y+008248X0150Y0810     S2      
327GND              J2    -23         A01X+018484Y+008248X0150Y0810     S2      
327NNAME10241       J2    -21         A01X+018248Y+008248X0150Y0810     S2      
317GND              VIA   -     D0100PA00X+018484Y+008847               S3      
317GND              VIA   -     D0100PA00X+019193Y+008851               S3      
317NNAME10240       VIA   -     D0100PA00X+018493Y+009185               S1      
317NNAME10239       VIA   -     D0100PA00X+018993Y+009185               S1      
317NNAME10242       VIA   -     D0100PA00X+019665Y+009184               S1      
317GND              VIA   -     D0100PA00X+019600Y+009557               S3      
317GND              VIA   -     D0100PA00X+019547Y+010877               S3      
317GND              VIA   -     D0100PA00X+018417Y+009521               S3      
317GND              VIA   -     D0100PA00X+018606Y+010010               S3      
317NNAME10243       VIA   -     D0100PA00X+019649Y+010564               S1      
317NNAME10241       VIA   -     D0100PA00X+018301Y+009881               S3      
317NNAME10181       VIA   -     D0100PA00X+019010Y+009970               S3      
317PD_NODE1_DM1     VIA   -     D0100PA00X+018820Y+010457               S1      
327PD_NODE1_DM1     R211  -2          A10X+019000Y+011298X0180Y0200R180 S1      
327GND              R211  -1          A10X+019315Y+011298X0180Y0200R180 S1      
327GND              J2    -32         A01X+019547Y+011476X0150Y0810     S2      
327NNAME10244       J2    -30         A01X+019311Y+011476X0150Y0810     S2      
327PD_NODE1_DM1     J2    -28         A01X+019075Y+011476X0150Y0810     S2      
327GND              J2    -26         A01X+018839Y+011476X0150Y0810     S2      
327NNAME10176       J2    -24         A01X+018602Y+011476X0150Y0810     S2      
327NNAME10180       J2    -22         A01X+018366Y+011476X0150Y0810     S2      
327GND              J2    -20         A01X+018130Y+011476X0150Y0810     S2      
317GND              VIA   -     D0100PA00X+019601Y+012519               S3      
317GND              VIA   -     D0100PA00X+018673Y+012120               S3      
317NNAME10245       VIA   -     D0100PA00X+019446Y+012263               S1      
317GND              VIA   -     D0100PA00X+018882Y+023278               S3      
317NNAME10241       VIA   -     D0100PA00X+018405Y+023014               S1      
317NNAME10180       VIA   -     D0100PA00X+018355Y+023506               S3      
327NNAME10240       U2    -BM16       A01X+019310Y+024998X0120Y0120     S2      
327GND              U2    -BP16       A01X+019330Y+024626X0100Y0135     S2      
327NNAME10088       U2    -BM9        A01X+018023Y+025021X0120Y0120     S2      
327NNAME10171       U2    -BM13       A01X+018854Y+025022X0120Y0120     S2      
327NNAME10180       U2    -BP13       A01X+018764Y+024626X0100Y0135     S2      
327GND              U2    -BP10       A01X+018124Y+024626X0100Y0135     S2      
327NNAME10087       U2    -BN10       A01X+018261Y+024866X0120Y0120     S2      
327GND              U2    -BN12       A01X+018626Y+024866X0120Y0120     S2      
327NNAME10181       U2    -BN14       A01X+019046Y+024822X0120Y0120     S2      
317GND              VIA   -     D0100PA00X+019368Y+024386               S3      
317GND              VIA   -     D0100PA00X+018919Y+024306               S3      
317GND              VIA   -     D0100PA00X+018432Y+024761               S3      
317NNAME10240       VIA   -     D0100PA00X+018890Y+024021               S3      
317NNAME10243       VIA   -     D0100PA00X+019513Y+024996               S3      
317NNAME10171       VIA   -     D0100PA00X+018430Y+024110               S1      
317NNAME10239       VIA   -     D0100PA00X+018890Y+023681               S3      
327GND              U2    -BL10       A01X+018264Y+025157X0120Y0120     S2      
327GND              U2    -BL12       A01X+018614Y+025157X0120Y0120     S2      
327NNAME10243       U2    -BL14       A01X+019067Y+025199X0120Y0120     S2      
327NNAME10096       U2    -BG9        A01X+018031Y+026023X0120Y0120     S2      
327NNAME10089       U2    -BD10       A01X+018181Y+026529X0120Y0120     S2      
327GND              U2    -BL16       A01X+019330Y+025298X0120Y0120     S2      
327GND              U2    -BK17       A01X+019531Y+025487X0120Y0120     S2      
327GND              U2    -BK15       A01X+019129Y+025487X0120Y0120     S2      
327GND              U2    -BG11       A01X+018328Y+026070X0120Y0120     S2      
327GND              U2    -BH11       A01X+018328Y+025770X0120Y0120     S2      
327NNAME10173       U2    -BG15       A01X+019110Y+025920X0120Y0120     S2      
327GND              U2    -BD15       A01X+019110Y+026520X0120Y0120     S2      
327GND              U2    -BF15       A01X+019110Y+026220X0120Y0120     S2      
327NNAME10123       U2    -BG13       A01X+018834Y+025920X0120Y0120     S2      
327NNAME10175       U2    -BD13       A01X+018834Y+026520X0120Y0120     S2      
327NNAME10177       U2    -BF13       A01X+018834Y+026220X0120Y0120     S2      
327NNAME10086       U2    -BK9        A01X+018035Y+025506X0120Y0120     S2      
327GND              U2    -BK10       A01X+018302Y+025431X0120Y0120     S2      
327GND              U2    -BK12       A01X+018577Y+025431X0120Y0120     S2      
327GND              U2    -BK13       A01X+018850Y+025483X0120Y0120     S2      
317GND              VIA   -     D0100PA00X+019406Y+025670               S3      
317GND              VIA   -     D0100PA00X+019374Y+026586               S3      
317GND              VIA   -     D0100PA00X+018844Y+025264               S3      
317GND              VIA   -     D0100PA00X+018483Y+025914               S3      
317NNAME10086       VIA   -     D0100PA00X+018118Y+025764               S1      
317NNAME10173       VIA   -     D0100PA00X+018866Y+025687               S3      
317NNAME10089       VIA   -     D0100PA00X+018412Y+026485               S3      
317NNAME10090       VIA   -     D0100PA00X+018160Y+026266               S3      
317NNAME10175       VIA   -     D0100PA00X+018687Y+026370               S3      
317NNAME10123       VIA   -     D0100PA00X+018580Y+025676               S3      
317NNAME10177       VIA   -     D0100PA00X+018687Y+026070               S3      
317NNAME10179       VIA   -     D0100PA00X+019469Y+025920               S3      
317NNAME10178       VIA   -     D0100PA00X+019469Y+026220               S3      
327NNAME10183       VIA   -           A10X+019386Y+025234X0160Y0042R045 S1      
327GND              U2    -AY14       A01X+018931Y+027311X0120Y0120     S2      
327N/C              U2    -AW14       A01X+018931Y+027587X0120Y0120     S2      
327GND              U2    -AW12       A01X+018631Y+027587X0120Y0120     S2      
327NNAME10246       U2    -AW11       A01X+018331Y+027587X0120Y0120     S2      
327GND              U2    -AY12       A01X+018631Y+027311X0120Y0120     S2      
327NNAME10132       U2    -AY11       A01X+018331Y+027311X0120Y0120     S2      
327N/C              U2    -AW15       A01X+019231Y+027587X0120Y0120     S2      
327GND              U2    -AY15       A01X+019231Y+027311X0120Y0120     S2      
327GND              U2    -BC13       A01X+018781Y+026805X0120Y0120     S2      
327GND              U2    -BC11       A01X+018481Y+026805X0120Y0120     S2      
327NNAME10196       U2    -AW9        A01X+018031Y+027587X0120Y0120     S2      
327NNAME10130       U2    -AY9        A01X+018031Y+027311X0120Y0120     S2      
327NNAME10247       U2    -BC10       A01X+018181Y+026805X0120Y0120     S2      
327N/C              U2    -AT10       A01X+018181Y+028093X0120Y0120     S2      
327GND              U2    -AT11       A01X+018481Y+028093X0120Y0120     S2      
327N/C              U2    -AT13       A01X+018781Y+028093X0120Y0120     S2      
327N/C              U2    -AT14       A01X+019081Y+028093X0120Y0120     S2      
327GND              U2    -AT16       A01X+019381Y+028093X0120Y0120     S2      
327GND              U2    -BC15       A01X+019110Y+026820X0120Y0120     S2      
317GND              VIA   -     D0100PA00X+019092Y+027769               S3      
317GND              VIA   -     D0100PA00X+018599Y+027904               S3      
317GND              VIA   -     D0100PA00X+018612Y+027079               S3      
317P1V05_NODE1      VIA   -     D0100PA00X+018842Y+027889               S3      
317NNAME10247       VIA   -     D0100PA00X+018344Y+026982               S1      
317NNAME10132       VIA   -     D0100PA00X+018182Y+027454               S3      
327NNAME10248       VIA   -           A10X+019325Y+028029X0260Y0260     S1      
317NNAME10248       VIA   -     D0100PA00X+019421Y+027103               S3      
327NNAME10249       VIA   -           A10X+018969Y+026824X0260Y0260     S1      
317NNAME10249       VIA   -     D0100PA00X+019186Y+027015               S3      
317NNAME10246       VIA   -     D0100PA00X+018320Y+027803               S1      
327NNAME10193       VIA   -           A10X+018898Y+027344X0260Y0260     S1      
327GND              U2    -AL17       A01X+019531Y+029151X0120Y0120     S2      
327GND              U2    -AM17       A01X+019531Y+028875X0120Y0120     S2      
327N/C              U2    -AM9        A01X+018031Y+028875X0120Y0120     S2      
327N/C              U2    -AL9        A01X+018031Y+029151X0120Y0120     S2      
327N/C              U2    -AM11       A01X+018331Y+028875X0120Y0120     S2      
327GND              U2    -AM12       A01X+018631Y+028875X0120Y0120     S2      
327N/C              U2    -AL11       A01X+018331Y+029151X0120Y0120     S2      
327GND              U2    -AL12       A01X+018631Y+029151X0120Y0120     S2      
327N/C              U2    -AL14       A01X+018931Y+029151X0120Y0120     S2      
327N/C              U2    -AM14       A01X+018931Y+028875X0120Y0120     S2      
327N/C              U2    -AM15       A01X+019231Y+028875X0120Y0120     S2      
327N/C              U2    -AL15       A01X+019231Y+029151X0120Y0120     S2      
327N/C              U2    -AR10       A01X+018181Y+028369X0120Y0120     S2      
327GND              U2    -AR11       A01X+018481Y+028369X0120Y0120     S2      
327GND              U2    -AR13       A01X+018781Y+028369X0120Y0120     S2      
327N/C              U2    -AR14       A01X+019081Y+028369X0120Y0120     S2      
327N/C              U2    -AR16       A01X+019381Y+028369X0120Y0120     S2      
327N/C              U2    -AH10       A01X+018181Y+029657X0120Y0120     S2      
327N/C              U2    -AH14       A01X+019081Y+029657X0120Y0120     S2      
327N/C              U2    -AH13       A01X+018781Y+029657X0120Y0120     S2      
327GND              U2    -AH11       A01X+018481Y+029657X0120Y0120     S2      
327GND              U2    -AH16       A01X+019381Y+029657X0120Y0120     S2      
317GND              VIA   -     D0100PA00X+018370Y+028569               S3      
317GND              VIA   -     D0100PA00X+019356Y+029443               S3      
317GND              VIA   -     D0100PA00X+018781Y+028635               S3      
317GND              VIA   -     D0100PA00X+018481Y+029298               S3      
317GND              VIA   -     D0100PA00X+018625Y+029502               S3      
317P1V05_NODE1      VIA   -     D0100PA00X+019105Y+029442               S3      
317P1V05_NODE1      VIA   -     D0100PA00X+018325Y+029502               S3      
327NNAME10250       VIA   -           A10X+019197Y+029773X0260Y0260     S1      
317NNAME10251       VIA   -     D0100PA00X+019230Y+028618               S1      
327GND              C56   -2          A10X+019221Y+031160X0180Y0200     S1      
327P1V05_NODE1      C56   -1          A10X+018906Y+031160X0180Y0200     S1      
327P1V05_NODE1      C35   -2          A10X+018918Y+030582X0180Y0200R180 S1      
327GND              C35   -1          A10X+019233Y+030582X0180Y0200R180 S1      
327GND              C99   -2          A10X+019637Y+031362X0180Y0200R180 S1      
327N/C              U2    -AG10       A01X+018181Y+029933X0120Y0120     S2      
327N/C              U2    -AG14       A01X+019081Y+029933X0120Y0120     S2      
327N/C              U2    -AG13       A01X+018781Y+029933X0120Y0120     S2      
327GND              U2    -AG11       A01X+018481Y+029933X0120Y0120     S2      
327GND              U2    -AG16       A01X+019381Y+029933X0120Y0120     S2      
327GND              U2    -AD17       A01X+019531Y+030439X0120Y0120     S2      
327GND              U2    -AC17       A01X+019531Y+030715X0120Y0120     S2      
327N/C              U2    -AC9        A01X+018031Y+030715X0120Y0120     S2      
327N/C              U2    -AD9        A01X+018031Y+030439X0120Y0120     S2      
327N/C              U2    -AD14       A01X+018931Y+030439X0120Y0120     S2      
327N/C              U2    -AC14       A01X+018931Y+030715X0120Y0120     S2      
327GND              U2    -AC12       A01X+018631Y+030715X0120Y0120     S2      
327N/C              U2    -AC11       A01X+018331Y+030715X0120Y0120     S2      
327GND              U2    -AD12       A01X+018631Y+030439X0120Y0120     S2      
327N/C              U2    -AD11       A01X+018331Y+030439X0120Y0120     S2      
327N/C              U2    -AC15       A01X+019231Y+030715X0120Y0120     S2      
327N/C              U2    -AD15       A01X+019231Y+030439X0120Y0120     S2      
327GND              U2    -Y10        A01X+018181Y+031221X0120Y0120     S2      
327NNAME10107       U2    -Y11        A01X+018481Y+031221X0120Y0120     S2      
327NNAME10136       U2    -Y13        A01X+018781Y+031221X0120Y0120     S2      
327GND              U2    -Y14        A01X+019081Y+031221X0120Y0120     S2      
327GND              U2    -Y16        A01X+019381Y+031221X0120Y0120     S2      
317GND              VIA   -     D0100PA00X+019477Y+030218               S3      
317GND              VIA   -     D0100PA00X+019381Y+030862               S3      
317GND              VIA   -     D0100PA00X+019525Y+031066               S3      
317GND              VIA   -     D0100PA00X+018475Y+030284               S3      
317P1V05_NODE1      VIA   -     D0100PA00X+018192Y+030192               S3      
317P1V05_NODE1      VIA   -     D0100PA00X+019195Y+030199               S3      
317P1V05_NODE1      VIA   -     D0100PA00X+018881Y+030200               S3      
317P1V05_NODE1      VIA   -     D0100PA00X+018791Y+030878               S3      
317NNAME10136       VIA   -     D0100PA00X+018625Y+031066               S3      
317NNAME10107       VIA   -     D0100PA00X+018325Y+031066               S1      
327GND              U2    -W10        A01X+018181Y+031497X0120Y0120     S2      
327NNAME10137       U2    -W11        A01X+018481Y+031497X0120Y0120     S2      
327NNAME10200       U2    -W13        A01X+018781Y+031497X0120Y0120     S2      
327GND              U2    -W14        A01X+019081Y+031497X0120Y0120     S2      
327NNAME10199       U2    -W16        A01X+019381Y+031497X0120Y0120     S2      
327N/C              U2    -U11        A01X+018331Y+032003X0120Y0120     S2      
327GND              U2    -U12        A01X+018631Y+032003X0120Y0120     S2      
327N/C              U2    -U14        A01X+018931Y+032003X0120Y0120     S2      
327N/C              U2    -N10        A01X+018181Y+032785X0120Y0120     S2      
327N/C              U2    -R11        A01X+018331Y+032279X0120Y0120     S2      
327GND              U2    -R12        A01X+018631Y+032279X0120Y0120     S2      
327N/C              U2    -R14        A01X+018931Y+032279X0120Y0120     S2      
327GND              U2    -N11        A01X+018481Y+032785X0120Y0120     S2      
327N/C              U2    -N13        A01X+018781Y+032785X0120Y0120     S2      
327N/C              U2    -N14        A01X+019081Y+032785X0120Y0120     S2      
327N/C              U2    -U15        A01X+019231Y+032003X0120Y0120     S2      
327N/C              U2    -R15        A01X+019231Y+032279X0120Y0120     S2      
327N/C              U2    -U9         A01X+018031Y+032003X0120Y0120     S2      
327N/C              U2    -R9         A01X+018031Y+032279X0120Y0120     S2      
327GND              U2    -T17        A01X+019522Y+032115X0120Y0120     S2      
327GND              U2    -P17        A01X+019522Y+032415X0120Y0120     S2      
327N/C              U2    -N17        A01X+019522Y+032715X0120Y0120     S2      
317GND              VIA   -     D0100PA00X+019331Y+032549               S3      
317GND              VIA   -     D0100PA00X+018630Y+032637               S3      
317NNAME10200       VIA   -     D0100PA00X+018635Y+031712               S3      
317NNAME10252       VIA   -     D0100PA00X+019648Y+031704               S3      
317NNAME10137       VIA   -     D0100PA00X+018323Y+031702               S1      
317NNAME10199       VIA   -     D0100PA00X+019396Y+031706               S3      
317NNAME10253       VIA   -     D0100PA00X+019116Y+031717               S1      
317NNAME10254       VIA   -     D0100PA00X+019056Y+032570               S1      
327NNAME10254       R148  -2          A10X+019635Y+033101X0180Y0200R180 S1      
327GND              U2    -E14        A01X+019048Y+034198X0120Y0120     S2      
327GND              U2    -E13        A01X+018771Y+034178X0120Y0120     S2      
327N/C              U2    -J13        A01X+018740Y+033465X0120Y0120     S2      
327GND              U2    -L13        A01X+018740Y+033165X0120Y0120     S2      
327NNAME10255       U2    -J14        A01X+019016Y+033465X0120Y0120     S2      
327GND              U2    -L14        A01X+019016Y+033165X0120Y0120     S2      
327NNAME10256       U2    -H14        A01X+019016Y+033765X0120Y0120     S2      
327N/C              U2    -H13        A01X+018740Y+033765X0120Y0120     S2      
327NNAME10102       U2    -K10        A01X+018234Y+033315X0120Y0120     S2      
327NNAME10106       U2    -H10        A01X+018234Y+033615X0120Y0120     S2      
327GND              U2    -G10        A01X+018234Y+033915X0120Y0120     S2      
327GND              U2    -D14        A01X+018981Y+034469X0120Y0120     S2      
327GND              U2    -E16        A01X+019450Y+034198X0120Y0120     S2      
327NNAME10106       U2    -D15        A01X+019249Y+034387X0120Y0120     S2      
327NNAME10102       U2    -E10        A01X+018228Y+034254X0120Y0120     S2      
327NNAME10102       U2    -E12        A01X+018504Y+034254X0120Y0120     S2      
327N/C              U2    -L17        A01X+019522Y+033015X0120Y0120     S2      
327GND              U2    -K17        A01X+019522Y+033315X0120Y0120     S2      
327N/C              U2    -H17        A01X+019522Y+033615X0120Y0120     S2      
327N/C              U2    -G17        A01X+019522Y+033915X0120Y0120     S2      
327NNAME10106       U2    -D17        A01X+019512Y+034486X0120Y0120     S2      
317GND              VIA   -     D0100PA00X+018740Y+034400               S3      
317GND              VIA   -     D0100PA00X+019229Y+034079               S3      
317GND              VIA   -     D0100PA00X+018520Y+033285               S3      
317GND              VIA   -     D0100PA00X+018437Y+033779               S3      
317NNAME10256       VIA   -     D0100PA00X+019223Y+033732               S3      
327NNAME10256       VIA   -           A10X+019553Y+034095X0260Y0260     S1      
317NNAME10255       VIA   -     D0100PA00X+019204Y+033361               S1      
327GND              R97   -2          A10X+019006Y+034989X0180Y0200R090 S1      
327NNAME10255       R97   -1          A10X+019006Y+034674X0180Y0200R090 S1      
327GND              R99   -2          A10X+019419Y+034998X0180Y0200R090 S1      
327NNAME10256       R99   -1          A10X+019419Y+034683X0180Y0200R090 S1      
327GND              U2    -A9         A01X+018042Y+035059X0100Y0135     S2      
327GND              U2    -A12        A01X+018682Y+035059X0100Y0135     S2      
327GND              U2    -A15        A01X+019249Y+035059X0100Y0135     S2      
327GND              U2    -B14        A01X+018950Y+034884X0120Y0120     S2      
327NNAME10102       U2    -C15        A01X+019269Y+034687X0120Y0120     S2      
327NNAME10106       U2    -B12        A01X+018545Y+034819X0120Y0120     S2      
327NNAME10106       U2    -D10        A01X+018192Y+034528X0120Y0120     S2      
327NNAME10106       U2    -D12        A01X+018542Y+034528X0120Y0120     S2      
327GND              U2    -C13        A01X+018783Y+034664X0120Y0120     S2      
327NNAME10102       U2    -B10        A01X+018180Y+034818X0120Y0120     S2      
327NNAME10102       U2    -B17        A01X+019533Y+034863X0120Y0120     S2      
317GND              VIA   -     D0100PA00X+018693Y+035581               S3      
317GND              VIA   -     D0100PA00X+019252Y+035276               S3      
317GND              VIA   -     D0100PA00X+018691Y+035276               S3      
327NNAME10252       VIA   -           A10X+018495Y+036156X0260Y0260     S1      
327NNAME10199       VIA   -           A10X+018279Y+035211X0260Y0260     S1      
327NNAME10252       C27   -2          A10X+018406Y+037008X0180Y0200R270 S1      
327GND              C27   -1          A10X+018406Y+037323X0180Y0200R270 S1      
327NNAME10257       R123  -2          A10X+018806Y+037323X0180Y0200R090 S1      
327NNAME10252       R123  -1          A10X+018806Y+037008X0180Y0200R090 S1      
317GND              VIA   -     D0100PA00X+018406Y+037648               S3      
317NNAME10258       VIA   -     D0100PA00X+019542Y+037241               S1      
327NNAME10257       R124  -2          A10X+018797Y+038073X0180Y0200R270 S1      
327P3V3_NODE1       R124  -1          A10X+018797Y+038388X0180Y0200R270 S1      
327GND              U9    -TH         A01X+019743Y+039333X0830Y0830R180 S2      
327NNAME10259       U9    -14         A01X+019615Y+038640X0150Y0280R180 S2      
327NNAME10260       U9    -13         A01X+019359Y+038640X0150Y0280R180 S2      
327NNAME10004       U9    -12         A01X+019050Y+038949X0150Y0280R270 S2      
327NNAME10006       U9    -11         A01X+019050Y+039205X0150Y0280R270 S2      
317GND              VIA   -     D0100PA00X+019423Y+039027               S3      
317P3V3_NODE1       VIA   -     D0100PA00X+018493Y+038388               S3      
317NNAME10259       VIA   -     D0100PA00X+019268Y+037755               S1      
317NNAME10260       VIA   -     D0100PA00X+019359Y+038338               S1      
317NNAME10257       VIA   -     D0100PA00X+018507Y+038073               S3      
327NNAME10203       C139  -2          A01X+018342Y+039731X0180Y0200R270 S2      
327NNAME10201       C139  -1          A01X+018342Y+039416X0180Y0200R270 S2      
327NNAME10202       R199  -2          A01X+018336Y+040157X0180Y0200R090 S2      
327NNAME10261       R199  -1          A01X+018336Y+040472X0180Y0200R090 S2      
327GND              U9    -8          A01X+019359Y+040026X0150Y0280R180 S2      
327NNAME10202       U9    -7          A01X+019615Y+040026X0150Y0280R180 S2      
327NNAME10201       U9    -10         A01X+019050Y+039461X0150Y0280R270 S2      
327NNAME10203       U9    -9          A01X+019050Y+039716X0150Y0280R270 S2      
317GND              VIA   -     D0100PA00X+019433Y+039643               S3      
317GND              VIA   -     D0100PA00X+019268Y+040296               S3      
317NNAME10202       VIA   -     D0100PA00X+019627Y+040315               S1      
327GND              PC26  -2          A01X+018826Y+041893X0180Y0200R180 S2      
327NNAME10207       PC26  -1          A01X+018511Y+041893X0180Y0200R180 S2      
327NNAME10207       R1103 -2          A01X+018512Y+041489X0180Y0200     S2      
327GND              R1103 -1          A01X+018827Y+041489X0180Y0200     S2      
317GND              VIA   -     D0100PA00X+018277Y+042401               S3      
317GND              VIA   -     D0100PA00X+018527Y+042401               S3      
317GND              VIA   -     D0100PA00X+018277Y+042151               S3      
317GND              VIA   -     D0100PA00X+018527Y+042151               S3      
317GND              VIA   -     D0100PA00X+019070Y+041833               S1      
317NNAME10207       VIA   -     D0100PA00X+018213Y+041833               S3      
327P12V_AUX         PU2   -14         A01X+018153Y+043879X0100Y0330     S2      
327P12V_AUX         PU2   -13         A01X+018350Y+043879X0100Y0330     S2      
327GND              PU2   -8          A01X+018350Y+042718X0100Y0330     S2      
327GND              PU2   -7          A01X+018153Y+042718X0100Y0330     S2      
327NNAME10262       PU2   -12         A01X+018635Y+043594X0100Y0330R090 S2      
327NNAME10263       PU2   -11         A01X+018635Y+043397X0100Y0330R090 S2      
327NNAME10263       PU2   -10         A01X+018635Y+043200X0100Y0330R090 S2      
327NNAME10263       PU2   -9          A01X+018635Y+043003X0100Y0330R090 S2      
327NNAME10263       PC15  -2          A01X+019180Y+043357X0180Y0200R090 S2      
327NNAME10262       PC15  -1          A01X+019180Y+043672X0180Y0200R090 S2      
317GND              VIA   -     D0100PA00X+018288Y+043066               S3      
317GND              VIA   -     D0100PA00X+018288Y+043531               S3      
327P12V_AUX         VIA   -           A10X+018237Y+043920X0260Y0260R180 S1      
317NNAME10263       VIA   -     D0100PA00X+019253Y+042905               S1      
317NNAME10262       VIA   -     D0100PA00X+018908Y+043828               S1      
327GND              PC12  -2          A01X+018917Y+044439X0180Y0200R180 S2      
327P12V_AUX         PC12  -1          A01X+018602Y+044439X0180Y0200R180 S2      
327GND              PC13  -2          A10X+019579Y+045051X0460Y0620     S1      
327P12V_AUX         PC13  -1          A10X+018419Y+045051X0460Y0620     S1      
327GND              PC11  -2          A01X+019581Y+045049X0460Y0620R180 S2      
327P12V_AUX         PC11  -1          A01X+018421Y+045049X0460Y0620R180 S2      
317GND              VIA   -     D0100PA00X+019207Y+044485               S3      
317P12V_AUX         VIA   -     D0100PA00X+018452Y+044192               S3      
317P12V_AUX         VIA   -     D0100PA00X+018192Y+044504               S3      
317P12V_AUX         VIA   -     D0100PA00X+018192Y+044254               S3      
317GND              VIA   -     D0100PA00X+018575Y+048766               S3      
317NNAME10209       VIA   -     D0100PA00X+019350Y+048980               S3      
327NNAME10063       VIA   -           A10X+019274Y+049793X0260Y0260R090 S1      
327GND              U15   -T9         A01X+018281Y+050773X0145Y0145     S2      
327NNAME10063       U15   -R9         A01X+018281Y+051088X0145Y0145     S2      
327GND              U15   -P9         A01X+018281Y+051403X0145Y0145     S2      
327NNAME10063       U15   -N9         A01X+018281Y+051718X0145Y0145     S2      
327GND              C232  -2          A10X+018463Y+050535X0180Y0200R180 S1      
327NNAME10063       C232  -1          A10X+018778Y+050535X0180Y0200R180 S1      
327GND              C235  -2          A10X+018513Y+051135X0180Y0200R180 S1      
327NNAME10063       C235  -1          A10X+018828Y+051135X0180Y0200R180 S1      
317GND              VIA   -     D0100PA00X+018642Y+051853               S3      
317GND              VIA   -     D0100PA00X+018647Y+051404               S3      
317GND              VIA   -     D0100PA00X+018492Y+050863               S3      
317NNAME10214       VIA   -     D0100PA00X+018123Y+051246               S3      
317NNAME10216       VIA   -     D0100PA00X+018123Y+051561               S3      
327NNAME10210       VIA   -           A01X+019691Y+051534X0300Y0300R090 S2      
317NNAME10063       VIA   -     D0100PA00X+018742Y+050876               S3      
317NNAME10063       VIA   -     D0100PA00X+018901Y+051485               S3      
327GND              U15   -M9         A01X+018281Y+052033X0145Y0145     S2      
327NNAME10264       U15   -L9         A01X+018281Y+052348X0145Y0145     S2      
327NNAME10265       U15   -K9         A01X+018281Y+052663X0145Y0145     S2      
327NNAME10266       U15   -J9         A01X+018281Y+052978X0145Y0145     S2      
327NNAME10063       U15   -H9         A01X+018281Y+053293X0145Y0145     S2      
327GND              C223  -1          A10X+018378Y+052005X0180Y0200R180 S1      
327GND              R260  -2          A10X+018155Y+052414X0180Y0200     S1      
317GND              VIA   -     D0100PA00X+018123Y+052821               S3      
317NNAME10223       VIA   -     D0100PA00X+018484Y+053400               S1      
317NNAME10266       VIA   -     D0100PA00X+018864Y+053067               S3      
327NNAME10266       VIA   -           A10X+018925Y+052624X0260Y0260     S1      
317NNAME10265       VIA   -     D0100PA00X+019146Y+053155               S1      
317NNAME10063       VIA   -     D0100PA00X+018788Y+053413               S3      
327GND              U15   -G9         A01X+018281Y+053608X0145Y0145     S2      
327GND              U15   -F9         A01X+018281Y+053923X0145Y0145     S2      
327NNAME10063       U15   -E9         A01X+018281Y+054238X0145Y0145     S2      
327NNAME10063       U15   -D9         A01X+018281Y+054553X0145Y0145     S2      
327NNAME10063       U15   -C9         A01X+018281Y+054868X0145Y0145     S2      
327GND              C233  -2          A10X+018563Y+054085X0180Y0200R180 S1      
327NNAME10063       C233  -1          A10X+018878Y+054085X0180Y0200R180 S1      
317GND              VIA   -     D0100PA00X+018123Y+054395               S3      
317GND              VIA   -     D0100PA00X+018438Y+053766               S3      
317NNAME10264       VIA   -     D0100PA00X+019347Y+054689               S1      
317NNAME10229       VIA   -     D0100PA00X+018684Y+054537               S1      
317NNAME10225       VIA   -     D0100PA00X+018123Y+053765               S3      
317NNAME10063       VIA   -     D0100PA00X+018438Y+054396               S3      
317NNAME10063       VIA   -     D0100PA00X+018893Y+053784               S3      
317NNAME10063       VIA   -     D0100PA00X+019043Y+054687               S3      
327GND              U15   -B9         A01X+018281Y+055183X0145Y0145     S2      
327GND              U15   -A9         A01X+018281Y+055498X0145Y0145     S2      
327GND              C236  -2          A10X+018889Y+055392X0180Y0200R090 S1      
327NNAME10063       C236  -1          A10X+018889Y+055077X0180Y0200R090 S1      
317GND              VIA   -     D0100PA00X+018838Y+055690               S3      
317GND              VIA   -     D0100PA00X+018439Y+055341               S3      
317NNAME10231       VIA   -     D0100PA00X+018123Y+055340               S3      
327NNAME10063       VIA   -           A10X+019471Y+055735X0260Y0260R090 S1      
317NNAME10063       VIA   -     D0100PA00X+018149Y+055744               S1      
327GND              C424  -2          A10X+018439Y+057340X0440Y0540R270 S1      
327P1V05_LAN1       C424  -1          A10X+018439Y+058088X0440Y0540R270 S1      
317GND              VIA   -     D0100PA00X+018865Y+057340               S3      
317NNAME10267       VIA   -     D0100PA00X+019308Y+058124               S1      
317NNAME10268       VIA   -     D0100PA00X+019150Y+057196               S3      
317NNAME10063       VIA   -     D0100PA00X+018248Y+056682               S1      
327P1V05_LAN1       U35   -18         A01X+019338Y+059714X0100Y0360R090 S2      
327PLT_RST_LAN1_N   U35   -17         A01X+019338Y+059517X0100Y0360R090 S2      
327NNAME10269       U35   -16         A01X+019023Y+059202X0100Y0360     S2      
327NNAME10267       U35   -15         A01X+018826Y+059202X0100Y0360     S2      
327NNAME10270       U35   -14         A01X+018629Y+059202X0100Y0360     S2      
327NNAME10271       U35   -13         A01X+018432Y+059202X0100Y0360     S2      
327NNAME10268       U35   -12         A01X+018235Y+059202X0100Y0360     S2      
327P1V05_LAN1       U35   -11         A01X+018038Y+059202X0100Y0360     S2      
327GND              C422  -2          A10X+018333Y+059321X0180Y0200R090 S1      
327P1V05_LAN1       C422  -1          A10X+018333Y+059006X0180Y0200R090 S1      
327GND              C420  -2          A10X+019036Y+059474X0180Y0200R180 S1      
327P1V05_LAN1       C420  -1          A10X+019351Y+059474X0180Y0200R180 S1      
317PLT_RST_LAN1_N   VIA   -     D0100PA00X+019674Y+058974               S1      
317P1V05_LAN1       VIA   -     D0100PA00X+018133Y+058754               S3      
327P1V05_LAN1       VIA   -           A10X+018946Y+058792X0260Y0260R090 S1      
327NNAME10272       U35   -26         A01X+019338Y+061289X0100Y0360R090 S2      
327NNAME10273       U35   -25         A01X+019338Y+061092X0100Y0360R090 S2      
327NNAME10054       U35   -24         A01X+019338Y+060895X0100Y0360R090 S2      
327NNAME10053       U35   -23         A01X+019338Y+060698X0100Y0360R090 S2      
327P1V9_LAN1        U35   -22         A01X+019338Y+060501X0100Y0360R090 S2      
327NNAME10274       U35   -21         A01X+019338Y+060304X0100Y0360R090 S2      
327NNAME10275       U35   -20         A01X+019338Y+060108X0100Y0360R090 S2      
327P1V9_LAN1        U35   -19         A01X+019338Y+059911X0100Y0360R090 S2      
327GND              C412  -2          A10X+019039Y+060383X0180Y0200R180 S1      
327P1V9_LAN1        C412  -1          A10X+019354Y+060383X0180Y0200R180 S1      
327GND              C410  -2          A10X+019036Y+060784X0180Y0200R180 S1      
327P1V9_LAN1        C410  -1          A10X+019351Y+060784X0180Y0200R180 S1      
327GND              C405  -2          A10X+019039Y+059893X0180Y0200R180 S1      
327P1V9_LAN1        C405  -1          A10X+019354Y+059893X0180Y0200R180 S1      
317GND              VIA   -     D0100PA00X+018503Y+060674               S3      
317GND              VIA   -     D0100PA00X+018493Y+060054               S3      
317GND              VIA   -     D0100PA00X+018503Y+061294               S3      
327P3V3_NODE1       U35   -32         A01X+019338Y+062470X0100Y0360R090 S2      
327NNAME10276       U35   -31         A01X+019338Y+062273X0100Y0360R090 S2      
327LAN1_LED_ACT_N   U35   -30         A01X+019338Y+062076X0100Y0360R090 S2      
327LAN1_TEST_EN     U35   -29         A01X+019338Y+061879X0100Y0360R090 S2      
327LAN1_DISABLE_N   U35   -28         A01X+019338Y+061682X0100Y0360R090 S2      
327P1V05_LAN1       U35   -27         A01X+019338Y+061485X0100Y0360R090 S2      
327PU_LAN1_TMS      U35   -38         A01X+018038Y+062785X0100Y0360R180 S2      
327P1V05_LAN1       U35   -37         A01X+018235Y+062785X0100Y0360R180 S2      
327SMB_LAN1_DAT     U35   -36         A01X+018432Y+062785X0100Y0360R180 S2      
327SMB_LAN1_ALT_N   U35   -35         A01X+018629Y+062785X0100Y0360R180 S2      
327SMB_LAN1_CLK     U35   -34         A01X+018826Y+062785X0100Y0360R180 S2      
327NNAME10277       U35   -33         A01X+019023Y+062785X0100Y0360R180 S2      
327GND              C421  -2          A10X+018243Y+062526X0180Y0200R270 S1      
327P1V05_LAN1       C421  -1          A10X+018243Y+062841X0180Y0200R270 S1      
327GND              C423  -2          A10X+019036Y+061474X0180Y0200R180 S1      
327P1V05_LAN1       C423  -1          A10X+019351Y+061474X0180Y0200R180 S1      
327GND              C398  -2          A10X+019039Y+062303X0180Y0200R180 S1      
327P3V3_NODE1       C398  -1          A10X+019354Y+062303X0180Y0200R180 S1      
327GND              C394  -2          A10X+019036Y+062714X0180Y0200R180 S1      
327P3V3_NODE1       C394  -1          A10X+019351Y+062714X0180Y0200R180 S1      
317GND              VIA   -     D0100PA00X+018493Y+061944               S3      
327SMB_LAN1_DAT     R540  -2          A01X+019641Y+064370X0180Y0200R090 S2      
327PU_LAN1_TMS      R537  -2          A01X+019191Y+064370X0180Y0200R090 S2      
327PU_LAN1_TDI      R536  -2          A01X+018741Y+064370X0180Y0200R090 S2      
317NNAME10277       VIA   -     D0100PA00X+019213Y+063224               S1      
317LAN1_AUX_PWR     VIA   -     D0100PA00X+018475Y+063969               S1      
317PU_LAN1_TMS      VIA   -     D0100PA00X+018248Y+063459               S1      
317SMB_LAN1_DAT     VIA   -     D0100PA00X+019148Y+063914               S1      
317P1V05_LAN1       VIA   -     D0100PA00X+018235Y+063161               S3      
327SMB_LAN1_DAT     R562  -2          A01X+019641Y+065370X0180Y0200R090 S2      
327SMB_PCH_SDA      R562  -1          A01X+019641Y+065685X0180Y0200R090 S2      
327LAN1_AUX_PWR     R541  -2          A01X+018741Y+065370X0180Y0200R090 S2      
327P3V3_NODE1       R541  -1          A01X+018741Y+065685X0180Y0200R090 S2      
327P3V3_NODE1       R540  -1          A01X+019641Y+064685X0180Y0200R090 S2      
327P3V3_NODE1       R537  -1          A01X+019191Y+064685X0180Y0200R090 S2      
327P3V3_NODE1       R536  -1          A01X+018741Y+064685X0180Y0200R090 S2      
317P3V3_NODE1       VIA   -     D0100PA00X+019641Y+065016               S3      
317P3V3_NODE1       VIA   -     D0100PA00X+018741Y+064972               S3      
317P3V3_NODE1       VIA   -     D0100PA00X+018741Y+065971               S3      
317P3V3_NODE1       VIA   -     D0100PA00X+019191Y+065006               S3      
327GND              C621  -2          A01X+019116Y+067253X0180Y0200     S2      
327P3V3_NODE1       C621  -1          A01X+019431Y+067253X0180Y0200     S2      
317GND              VIA   -     D0100PA00X+018820Y+067253               S3      
327N/C              U87   -1          A01X+019347Y+068800X0180Y0520R180 S2      
327NNAME10278       U87   -2          A01X+018973Y+068800X0180Y0520R180 S2      
327GND              U87   -3          A01X+018599Y+068800X0180Y0520R180 S2      
327PSU6_DC_OK       U87   -4          A01X+018599Y+067836X0180Y0520R180 S2      
327P3V3_NODE1       U87   -5          A01X+019347Y+067836X0180Y0520R180 S2      
317GND              VIA   -     D0100PA00X+019646Y+068504               S3      
317GND              VIA   -     D0100PA00X+018216Y+068456               S3      
317PSU6_DC_OK       VIA   -     D0100PA00X+018599Y+068267               S1      
317NNAME10278       VIA   -     D0100PA00X+019154Y+069193               S1      
327GND              R688  -2          A10X+018880Y+070194X0180Y0200R180 S1      
327N21699710        R688  -1          A10X+019195Y+070194X0180Y0200R180 S1      
327P12V_PDB         R1012 -2          A01X+018431Y+069389X0180Y0200     S2      
327PSU_DC_OK_N      R1012 -1          A01X+018746Y+069389X0180Y0200     S2      
327PSU_DC_OK_N      U99   -D          A01X+018744Y+069956X0400Y0500R180 S2      
327GND              U99   -S          A01X+018344Y+070836X0400Y0500R180 S2      
327NNAME10278       U99   -G          A01X+019144Y+070836X0400Y0500R180 S2      
327GND              U96   -S          A01X+019744Y+070836X0400Y0500R180 S2      
317GND              VIA   -     D0100PA00X+019451Y+070448               S3      
317GND              VIA   -     D0100PA00X+018780Y+070451               S3      
317P12V_PDB         VIA   -     D0100PA00X+018174Y+069483               S3      
317P12V_PDB         VIA   -     D0100PA00X+018195Y+069819               S1      
317PSU_DC_OK_N      VIA   -     D0100PA00X+019038Y+069562               S3      
327GND              C611  -2          A01X+018994Y+071593X0180Y0200R090 S2      
327PSU5_AC_OK       C611  -1          A01X+018994Y+071908X0180Y0200R090 S2      
327GND              C614  -2          A01X+018544Y+071593X0180Y0200R090 S2      
327PSU6_AC_OK       C614  -1          A01X+018544Y+071908X0180Y0200R090 S2      
327GND              C612  -2          A10X+018994Y+071493X0180Y0200R270 S1      
327NNAME10279       C612  -1          A10X+018994Y+071808X0180Y0200R270 S1      
327GND              C615  -2          A10X+018544Y+071493X0180Y0200R270 S1      
327NNAME10278       C615  -1          A10X+018544Y+071808X0180Y0200R270 S1      
327GND              C609  -2          A10X+019444Y+071490X0180Y0200R270 S1      
327NNAME10280       C609  -1          A10X+019444Y+071805X0180Y0200R270 S1      
327GND              C608  -2          A01X+019444Y+071590X0180Y0200R090 S2      
327PSU4_AC_OK       C608  -1          A01X+019444Y+071905X0180Y0200R090 S2      
327GND              C569  -1          A10X+019387Y+070816X0180Y0200     S1      
317GND              VIA   -     D0100PA00X+018544Y+071250               S3      
317GND              VIA   -     D0100PA00X+019614Y+071260               S3      
317GND              VIA   -     D0100PA00X+018774Y+070836               S3      
317GND              VIA   -     D0100PA00X+019193Y+071262               S3      
317PSU5_AC_OK       VIA   -     D0100PA00X+018857Y+072235               S1      
317PSU6_AC_OK       VIA   -     D0100PA00X+018357Y+072235               S1      
317PSU4_AC_OK       VIA   -     D0100PA00X+019357Y+072233               S1      
317NNAME10280       VIA   -     D0100PA00X+019608Y+072394               S3      
327GND              R850  -2          A01X+019444Y+073908X0180Y0200R090 S2      
327GND              R856  -2          A10X+019444Y+073908X0180Y0200R270 S1      
327PSU4_AC_OK       R839  -2          A01X+019444Y+072758X0180Y0200R090 S2      
327PSU4_AC_OK_R     R839  -1          A01X+019444Y+073073X0180Y0200R090 S2      
327NNAME10280       R840  -2          A10X+019444Y+072758X0180Y0200R270 S1      
327PSU4_DC_OK_R     R840  -1          A10X+019444Y+073073X0180Y0200R270 S1      
327NNAME10278       R847  -2          A10X+018544Y+072758X0180Y0200R270 S1      
327PSU6_DC_OK_R     R847  -1          A10X+018544Y+073073X0180Y0200R270 S1      
327PSU5_AC_OK       R842  -2          A01X+018994Y+072758X0180Y0200R090 S2      
327PSU5_AC_OK_R     R842  -1          A01X+018994Y+073073X0180Y0200R090 S2      
327PSU6_AC_OK       R846  -2          A01X+018544Y+072758X0180Y0200R090 S2      
327PSU6_AC_OK_R     R846  -1          A01X+018544Y+073073X0180Y0200R090 S2      
327NNAME10279       R843  -2          A10X+018994Y+072758X0180Y0200R270 S1      
327PSU5_DC_OK_R     R843  -1          A10X+018994Y+073073X0180Y0200R270 S1      
327GND              R851  -2          A01X+018994Y+073908X0180Y0200R090 S2      
327GND              R852  -2          A01X+018544Y+073908X0180Y0200R090 S2      
327GND              R857  -2          A10X+018994Y+073908X0180Y0200R270 S1      
327GND              R858  -2          A10X+018544Y+073908X0180Y0200R270 S1      
317GND              VIA   -     D0100PA00X+019444Y+073562               S3      
317GND              VIA   -     D0100PA00X+018994Y+073568               S3      
317GND              VIA   -     D0100PA00X+018544Y+073568               S3      
317GND              VIA   -     D0100PA00X+018267Y+073052               S3      
317NNAME10279       VIA   -     D0100PA00X+019115Y+072411               S3      
317NNAME10278       VIA   -     D0100PA00X+018616Y+072413               S3      
327PSU4_AC_OK_R     R850  -1          A01X+019444Y+074223X0180Y0200R090 S2      
327PSU4_DC_OK_R     R856  -1          A10X+019444Y+074223X0180Y0200R270 S1      
327PSU5_AC_OK_R     R851  -1          A01X+018994Y+074223X0180Y0200R090 S2      
327PSU6_AC_OK_R     R852  -1          A01X+018544Y+074223X0180Y0200R090 S2      
327PSU5_DC_OK_R     R857  -1          A10X+018994Y+074223X0180Y0200R270 S1      
327PSU6_DC_OK_R     R858  -1          A10X+018544Y+074223X0180Y0200R270 S1      
327PSU4_DC_OK_R     VIA   -           A10X+018757Y+077061X0260Y0260     S1      
317PSU3_AC_OK_R     VIA   -     D0100PA00X+019295Y+077102               S1      
327PSU3_DC_OK_R     VIA   -           A10X+019108Y+078577X0260Y0260     S1      
327PSU5_DC_OK_R     VIA   -           A10X+018365Y+077433X0260Y0260     S1      
317PSU5_AC_OK_R     VIA   -     D0100PA00X+018250Y+078079               S1      
317PSU4_AC_OK_R     VIA   -     D0100PA00X+018977Y+077808               S1      
327PSU4_DC_OK_R     J35   -A48        A10X+018510Y+080787X0300Y1660R180 S1      
327PSU3_DC_OK_R     J35   -A47        A10X+018904Y+080787X0300Y1660R180 S1      
327PSU2_DC_OK_R     J35   -A46        A10X+019297Y+080787X0300Y1660R180 S1      
327PSU1_DC_OK_R     J35   -A45        A10X+019691Y+080787X0300Y1660R180 S1      
327PSU4_AC_OK_R     J35   -B48        A01X+018510Y+080590X0300Y1260R180 S2      
327PSU3_AC_OK_R     J35   -B47        A01X+018904Y+080787X0300Y1660R180 S2      
327PSU2_AC_OK_R     J35   -B46        A01X+019297Y+080787X0300Y1660R180 S2      
327PSU1_AC_OK_R     J35   -B45        A01X+019691Y+080787X0300Y1660R180 S2      
327P12V_AUX         PR32  -2          A01X+019984Y+001132X0460Y0620R090 S2      
317P12V_AUX         VIA   -     D0100PA00X+020479Y+001376               S3      
317P12V_AUX         VIA   -     D0100PA00X+020498Y+001061               S1      
327NNAME10115       PR32  -1          A01X+019984Y+002292X0460Y0620R090 S2      
317P12V_AUX         VIA   -     D0100PA00X+020185Y+001529               S3      
317P12V_AUX         VIA   -     D0100PA00X+019858Y+001537               S3      
327PV_VDDR_NODE1    PL7   -2          A01X+020969Y+004316X0848Y1300     S2      
327NNAME10281       J2    -45         A01X+021083Y+008248X0150Y0810     S2      
327NNAME10282       J2    -43         A01X+020847Y+008248X0150Y0810     S2      
327GND              J2    -41         A01X+020610Y+008248X0150Y0810     S2      
327NNAME10283       J2    -39         A01X+020374Y+008248X0150Y0810     S2      
327NNAME10284       J2    -37         A01X+020138Y+008248X0150Y0810     S2      
327GND              J2    -35         A01X+019902Y+008248X0150Y0810     S2      
327NNAME10242       J2    -33         A01X+019665Y+008248X0150Y0810     S2      
317GND              VIA   -     D0100PA00X+019902Y+008843               S3      
317GND              VIA   -     D0100PA00X+020610Y+008821               S3      
317NNAME10283       VIA   -     D0100PA00X+020400Y+009125               S1      
317GND              VIA   -     D0100PA00X+020256Y+010780               S3      
317GND              VIA   -     D0100PA00X+021020Y+010846               S3      
317GND              VIA   -     D0100PA00X+020627Y+009836               S3      
317NNAME10284       VIA   -     D0100PA00X+020048Y+009769               S3      
317NNAME10285       VIA   -     D0100PA00X+021242Y+010496               S3      
317NNAME10282       VIA   -     D0100PA00X+020891Y+009698               S1      
317NNAME10244       VIA   -     D0100PA00X+020590Y+010148               S1      
317NNAME10286       VIA   -     D0100PA00X+019999Y+010364               S3      
327PD_NODE1_DM2     R210  -2          A10X+021100Y+011496X0180Y0200     S1      
327GND              R210  -1          A10X+020785Y+011496X0180Y0200     S1      
327PD_NODE1_DM2     J2    -44         A01X+020965Y+011476X0150Y0810     S2      
327NNAME10245       J2    -42         A01X+020728Y+011476X0150Y0810     S2      
327NNAME10285       J2    -40         A01X+020492Y+011476X0150Y0810     S2      
327GND              J2    -38         A01X+020256Y+011476X0150Y0810     S2      
327NNAME10286       J2    -36         A01X+020020Y+011476X0150Y0810     S2      
327NNAME10243       J2    -34         A01X+019784Y+011476X0150Y0810     S2      
317PD_NODE1_DM2     VIA   -     D0100PA00X+021062Y+012127               S1      
317GND              VIA   -     D0100PA00X+020707Y+017974               S3      
317GND              VIA   -     D0100PA00X+020715Y+017521               S1      
317GND              VIA   -     D0100PA00X+020704Y+018450               S3      
317GND              VIA   -     D0100PA00X+020707Y+018898               S1      
327GND              C113  -2          A10X+020221Y+022212X0440Y0540R180 S1      
327PV_VDDR_NODE1    C113  -1          A10X+020969Y+022212X0440Y0540R180 S1      
317GND              VIA   -     D0100PA00X+021202Y+023436               S3      
317NNAME10287       VIA   -     D0100PA00X+020554Y+023450               S1      
317NNAME10288       VIA   -     D0100PA00X+020554Y+022868               S1      
317NNAME10289       VIA   -     D0100PA00X+021194Y+023059               S1      
317NNAME10242       VIA   -     D0100PA00X+019830Y+023270               S3      
327NNAME10290       U2    -BM25       A01X+021083Y+024998X0120Y0120     S2      
327GND              U2    -BP25       A01X+021103Y+024626X0100Y0135     S2      
327NNAME10242       U2    -BM18       A01X+019796Y+025021X0120Y0120     S2      
327NNAME10291       U2    -BM22       A01X+020627Y+025022X0120Y0120     S2      
327NNAME10292       U2    -BP22       A01X+020536Y+024626X0100Y0135     S2      
327GND              U2    -BP19       A01X+019896Y+024626X0100Y0135     S2      
327NNAME10239       U2    -BN17       A01X+019629Y+024801X0120Y0120     S2      
327NNAME10176       U2    -BN19       A01X+020034Y+024866X0120Y0120     S2      
327NNAME10287       U2    -BN23       A01X+020819Y+024822X0120Y0120     S2      
327GND              U2    -BN21       A01X+020399Y+024866X0120Y0120     S2      
317GND              VIA   -     D0100PA00X+021194Y+024409               S3      
317GND              VIA   -     D0100PA00X+019869Y+024079               S3      
317NNAME10293       VIA   -     D0100PA00X+021194Y+023739               S3      
317NNAME10290       VIA   -     D0100PA00X+021194Y+024079               S3      
317NNAME10292       VIA   -     D0100PA00X+020557Y+024350               S3      
317NNAME10291       VIA   -     D0100PA00X+020527Y+024021               S1      
317NNAME10286       VIA   -     D0100PA00X+019869Y+023739               S1      
317NNAME10176       VIA   -     D0100PA00X+019869Y+024409               S1      
327NNAME10241       U2    -BL19       A01X+020036Y+025157X0120Y0120     S2      
327NNAME10288       U2    -BL23       A01X+020840Y+025199X0120Y0120     S2      
327GND              U2    -BL21       A01X+020386Y+025157X0120Y0120     S2      
327GND              U2    -BL25       A01X+021103Y+025298X0120Y0120     S2      
327GND              U2    -BE17       A01X+019616Y+026370X0120Y0120     S2      
327NNAME10179       U2    -BH17       A01X+019616Y+025770X0120Y0120     S2      
327NNAME10178       U2    -BG17       A01X+019616Y+026070X0120Y0120     S2      
327GND              U2    -BE19       A01X+019892Y+026370X0120Y0120     S2      
327NNAME10172       U2    -BH19       A01X+019892Y+025770X0120Y0120     S2      
327NNAME10124       U2    -BG19       A01X+019892Y+026070X0120Y0120     S2      
327GND              U2    -BF23       A01X+020674Y+026220X0120Y0120     S2      
327GND              U2    -BD23       A01X+020674Y+026520X0120Y0120     S2      
327GND              U2    -BG23       A01X+020674Y+025920X0120Y0120     S2      
327NNAME10174       U2    -BF21       A01X+020398Y+026220X0120Y0120     S2      
327GND              U2    -BD21       A01X+020398Y+026520X0120Y0120     S2      
327NNAME10125       U2    -BG21       A01X+020398Y+025920X0120Y0120     S2      
327NNAME10286       U2    -BL17       A01X+019598Y+025216X0120Y0120     S2      
327GND              U2    -BK19       A01X+020075Y+025431X0120Y0120     S2      
327GND              U2    -BK21       A01X+020350Y+025431X0120Y0120     S2      
327GND              U2    -BK18       A01X+019808Y+025506X0120Y0120     S2      
327GND              U2    -BK24       A01X+020902Y+025487X0120Y0120     S2      
327GND              U2    -BK22       A01X+020623Y+025483X0120Y0120     S2      
317GND              VIA   -     D0100PA00X+021103Y+025570               S3      
317GND              VIA   -     D0100PA00X+021033Y+026520               S3      
317GND              VIA   -     D0100PA00X+020813Y+025752               S3      
317GND              VIA   -     D0100PA00X+020614Y+025248               S3      
317GND              VIA   -     D0100PA00X+020829Y+026364               S3      
317NNAME10284       VIA   -     D0100PA00X+021031Y+025933               S1      
317NNAME10294       VIA   -     D0100PA00X+021031Y+026229               S3      
317NNAME10125       VIA   -     D0100PA00X+020199Y+026125               S3      
317NNAME10172       VIA   -     D0100PA00X+020098Y+025631               S1      
317NNAME10174       VIA   -     D0100PA00X+020240Y+026371               S3      
317NNAME10124       VIA   -     D0100PA00X+020047Y+025914               S3      
327NNAME10185       VIA   -           A10X+019707Y+026502X0160Y0042R090 S1      
317NNAME10183       VIA   -     D0100PA00X+020152Y+026599               S3      
327P1V5_NODE1       R149  -1          A10X+019865Y+028165X0180Y0200R090 S1      
327NNAME10295       R36   -2          A10X+020571Y+027761X0180Y0200     S1      
327P1V5_NODE1       R36   -1          A10X+020256Y+027761X0180Y0200     S1      
327GND              U2    -AT17       A01X+019681Y+028093X0120Y0120     S2      
327GND              U2    -AT19       A01X+019981Y+028093X0120Y0120     S2      
327GND              U2    -AU21       A01X+020472Y+027952X0150Y0150     S2      
327P1V05_NODE1      U2    -AU23       A01X+020787Y+027952X0150Y0150     S2      
327P1V05_NODE1      U2    -AU25       A01X+021102Y+027952X0150Y0150     S2      
327P1V05_NODE1      U2    -AW21       A01X+020512Y+027677X0120Y0120     S2      
327GND              U2    -AW20       A01X+020157Y+027677X0120Y0120     S2      
327P1V05_NODE1      U2    -AW23       A01X+020787Y+027677X0120Y0120     S2      
327GND              U2    -AW17       A01X+019616Y+027570X0120Y0120     S2      
327GND              U2    -BA17       A01X+019616Y+027270X0120Y0120     S2      
327NNAME10248       U2    -BB17       A01X+019616Y+026970X0120Y0120     S2      
327GND              U2    -AW19       A01X+019892Y+027570X0120Y0120     S2      
327GND              U2    -AY19       A01X+019892Y+027270X0120Y0120     S2      
327NNAME10185       U2    -BB19       A01X+019892Y+026970X0120Y0120     S2      
327GND              U2    -BC23       A01X+020674Y+026820X0120Y0120     S2      
327GND              U2    -BA23       A01X+020674Y+027120X0120Y0120     S2      
327P1V05_NODE1      U2    -AY23       A01X+020674Y+027420X0120Y0120     S2      
327GND              U2    -BC21       A01X+020398Y+026820X0120Y0120     S2      
327GND              U2    -BA21       A01X+020398Y+027120X0120Y0120     S2      
327P1V05_NODE1      U2    -AY21       A01X+020398Y+027420X0120Y0120     S2      
327NNAME10249       U2    -BD17       A01X+019616Y+026670X0120Y0120     S2      
327NNAME10183       U2    -BD19       A01X+019892Y+026670X0120Y0120     S2      
317GND              VIA   -     D0100PA00X+020823Y+026970               S3      
317GND              VIA   -     D0100PA00X+020167Y+027454               S3      
317GND              VIA   -     D0100PA00X+019951Y+027809               S3      
317P1V05_NODE1      VIA   -     D0100PA00X+020945Y+028110               S3      
327NNAME10296       VIA   -           A10X+020810Y+027301X0260Y0260R180 S1      
317NNAME10245       VIA   -     D0100PA00X+021030Y+026823               S3      
327NNAME10295       VIA   -           A10X+019785Y+027267X0260Y0260     S1      
317NNAME10295       VIA   -     D0100PA00X+020630Y+028110               S3      
317NNAME10283       VIA   -     D0100PA00X+021030Y+027123               S3      
317P1V5_NODE1       VIA   -     D0100PA00X+020315Y+028110               S3      
317NNAME10185       VIA   -     D0100PA00X+020152Y+026889               S3      
327GND              C50   -2          A10X+020945Y+029669X0180Y0200R090 S1      
327P1V05_NODE1      C50   -1          A10X+020945Y+029354X0180Y0200R090 S1      
327GND              C125  -2          A10X+021187Y+028462X0180Y0200R180 S1      
327GND              C126  -2          A10X+020802Y+028462X0180Y0200     S1      
327P1V05_NODE1      C126  -1          A10X+020487Y+028462X0180Y0200     S1      
327NNAME10250       R39   -1          A10X+019785Y+029773X0180Y0200R090 S1      
327NNAME10297       R149  -2          A10X+019865Y+028480X0180Y0200R090 S1      
327GND              U2    -AM18       A01X+019831Y+028875X0120Y0120     S2      
327P1V05_NODE1      U2    -AL18       A01X+019831Y+029151X0120Y0120     S2      
327GND              U2    -AM20       A01X+020107Y+028875X0120Y0120     S2      
327P1V05_NODE1      U2    -AL20       A01X+020107Y+029151X0120Y0120     S2      
327GND              U2    -AK20       A01X+020141Y+029427X0120Y0120     S2      
327P1V05_NODE1      U2    -AP20       A01X+020141Y+028600X0120Y0120     S2      
327GND              U2    -AR17       A01X+019681Y+028369X0120Y0120     S2      
327P1V05_NODE1      U2    -AR19       A01X+019981Y+028369X0120Y0120     S2      
327GND              U2    -AH17       A01X+019681Y+029657X0120Y0120     S2      
327GND              U2    -AH19       A01X+019981Y+029657X0120Y0120     S2      
327P1V5_NODE1       U2    -AT21       A01X+020472Y+028267X0150Y0150     S2      
327P1V05_NODE1      U2    -AP21       A01X+020472Y+028582X0150Y0150     S2      
327NNAME10297       U2    -AM21       A01X+020472Y+028897X0150Y0150     S2      
327P1V05_NODE1      U2    -AL21       A01X+020472Y+029212X0150Y0150     S2      
327NNAME10100       U2    -AJ21       A01X+020472Y+029527X0150Y0150     S2      
327NNAME10295       U2    -AT23       A01X+020787Y+028267X0150Y0150     S2      
327P1V05_NODE1      U2    -AP23       A01X+020787Y+028582X0150Y0150     S2      
327NNAME10250       U2    -AM23       A01X+020787Y+028897X0150Y0150     S2      
327P1V05_NODE1      U2    -AL23       A01X+020787Y+029212X0150Y0150     S2      
327NNAME10298       U2    -AJ23       A01X+020787Y+029527X0150Y0150     S2      
327GND              U2    -AT25       A01X+021102Y+028267X0150Y0150     S2      
327P1V05_NODE1      U2    -AP25       A01X+021102Y+028582X0150Y0150     S2      
327GND              U2    -AM25       A01X+021102Y+028897X0150Y0150     S2      
327P1V05_NODE1      U2    -AL25       A01X+021102Y+029212X0150Y0150     S2      
327GND              U2    -AJ25       A01X+021102Y+029527X0150Y0150     S2      
317P1V05_NODE1      VIA   -     D0100PA00X+020945Y+028740               S3      
317P1V05_NODE1      VIA   -     D0100PA00X+020945Y+029055               S3      
317P1V05_NODE1      VIA   -     D0100PA00X+020315Y+028740               S3      
317P1V05_NODE1      VIA   -     D0100PA00X+020630Y+028740               S3      
317P1V05_NODE1      VIA   -     D0100PA00X+019687Y+029434               S3      
317NNAME10250       VIA   -     D0100PA00X+020630Y+029055               S3      
317NNAME10251       VIA   -     D0100PA00X+020632Y+029686               S3      
317NNAME10297       VIA   -     D0100PA00X+020315Y+029055               S3      
327NNAME10297       VIA   -           A10X+019747Y+028919X0260Y0260R180 S1      
327NNAME10298       VIA   -           A10X+020269Y+029602X0260Y0260     S1      
317NNAME10298       VIA   -     D0100PA00X+020630Y+029370               S3      
327P1V05_NODE1      C99   -1          A10X+019952Y+031362X0180Y0200R180 S1      
327GND              C103  -2          A10X+020902Y+030454X0180Y0200R270 S1      
327P1V05_NODE1      C103  -1          A10X+020902Y+030769X0180Y0200R270 S1      
327GND              C59   -2          A10X+020345Y+030474X0180Y0200R270 S1      
327P1V05_NODE1      C59   -1          A10X+020345Y+030789X0180Y0200R270 S1      
327GND              C51   -2          A10X+019945Y+030474X0180Y0200R270 S1      
327P1V05_NODE1      C51   -1          A10X+019945Y+030789X0180Y0200R270 S1      
327GND              R42   -2          A10X+020917Y+030044X0180Y0200     S1      
327NNAME10298       R42   -1          A10X+020602Y+030044X0180Y0200     S1      
327GND              R39   -2          A10X+019785Y+030088X0180Y0200R090 S1      
327GND              U2    -AG17       A01X+019681Y+029933X0120Y0120     S2      
327GND              U2    -AG19       A01X+019981Y+029933X0120Y0120     S2      
327GND              U2    -AF20       A01X+020141Y+030164X0120Y0120     S2      
327P1V05_NODE1      U2    -AD20       A01X+020107Y+030439X0120Y0120     S2      
327P1V05_NODE1      U2    -AC20       A01X+020107Y+030715X0120Y0120     S2      
327GND              U2    -AB20       A01X+020141Y+030991X0120Y0120     S2      
327P1V05_NODE1      U2    -AC18       A01X+019831Y+030715X0120Y0120     S2      
327P1V05_NODE1      U2    -AD18       A01X+019831Y+030439X0120Y0120     S2      
327GND              U2    -AF21       A01X+020472Y+030157X0150Y0150     S2      
327GND              U2    -AG21       A01X+020472Y+029842X0150Y0150     S2      
327NNAME10254       U2    -AA21       A01X+020472Y+031102X0150Y0150     S2      
327P1V05_NODE1      U2    -AC21       A01X+020472Y+030787X0150Y0150     S2      
327GND              U2    -AD21       A01X+020472Y+030472X0150Y0150     S2      
327P3V3_NODE1       U2    -AF23       A01X+020787Y+030157X0150Y0150     S2      
327NNAME10251       U2    -AG23       A01X+020787Y+029842X0150Y0150     S2      
327NNAME10299       U2    -AA23       A01X+020787Y+031102X0150Y0150     S2      
327P1V05_NODE1      U2    -AC23       A01X+020787Y+030787X0150Y0150     S2      
327NNAME10097       U2    -AD23       A01X+020787Y+030472X0150Y0150     S2      
327GND              U2    -AF25       A01X+021102Y+030157X0150Y0150     S2      
327GND              U2    -AG25       A01X+021102Y+029842X0150Y0150     S2      
327GND              U2    -AA25       A01X+021102Y+031102X0150Y0150     S2      
327P1V05_NODE1      U2    -AC25       A01X+021102Y+030787X0150Y0150     S2      
327NNAME10097       U2    -AD25       A01X+021102Y+030472X0150Y0150     S2      
327GND              U2    -Y17        A01X+019681Y+031221X0120Y0120     S2      
327GND              U2    -Y19        A01X+019981Y+031221X0120Y0120     S2      
317GND              VIA   -     D0100PA00X+020630Y+031260               S3      
317P1V05_NODE1      VIA   -     D0100PA00X+019888Y+031025               S3      
317P1V05_NODE1      VIA   -     D0100PA00X+019681Y+030862               S3      
317NNAME10097       VIA   -     D0100PA00X+020630Y+030630               S3      
317P3V3_NODE1       VIA   -     D0100PA00X+020630Y+030315               S3      
317NNAME10299       VIA   -     D0100PA00X+020945Y+031260               S3      
317NNAME10254       VIA   -     D0100PA00X+020317Y+031258               S3      
317NNAME10100       VIA   -     D0100PA00X+020253Y+029936               S3      
327GND              R120  -2          A10X+020352Y+032797X0180Y0200R090 S1      
327NNAME10300       R120  -1          A10X+020352Y+032482X0180Y0200R090 S1      
327GND              R102  -2          A10X+019689Y+032662X0180Y0200R090 S1      
327NNAME10299       R102  -1          A10X+019689Y+032347X0180Y0200R090 S1      
327P1V05_NODE1      R200  -2          A10X+020668Y+032080X0180Y0200     S1      
327NNAME10300       R200  -1          A10X+020353Y+032080X0180Y0200     S1      
327NNAME10252       U2    -W17        A01X+019681Y+031497X0120Y0120     S2      
327GND              U2    -W19        A01X+019981Y+031497X0120Y0120     S2      
327GND              U2    -T25        A01X+021086Y+032115X0120Y0120     S2      
327N/C              U2    -N25        A01X+021086Y+032715X0120Y0120     S2      
327GND              U2    -P25        A01X+021086Y+032415X0120Y0120     S2      
327GND              U2    -T23        A01X+020787Y+032008X0120Y0120     S2      
327GND              U2    -T21        A01X+020472Y+032008X0120Y0120     S2      
327GND              U2    -T20        A01X+020197Y+032008X0120Y0120     S2      
327NNAME10300       U2    -R22        A01X+020580Y+032265X0120Y0120     S2      
327NNAME10201       U2    -R21        A01X+020304Y+032265X0120Y0120     S2      
327NNAME10203       U2    -P21        A01X+020304Y+032565X0120Y0120     S2      
327NNAME10301       U2    -P22        A01X+020580Y+032565X0120Y0120     S2      
327GND              U2    -M22        A01X+020580Y+032865X0120Y0120     S2      
327GND              U2    -M21        A01X+020304Y+032865X0120Y0120     S2      
327NNAME10253       U2    -T18        A01X+019798Y+032115X0120Y0120     S2      
327GND              U2    -P18        A01X+019798Y+032415X0120Y0120     S2      
327N/C              U2    -N18        A01X+019798Y+032715X0120Y0120     S2      
327GND              U2    -W21        A01X+020472Y+031417X0150Y0150     S2      
327GND              U2    -V23        A01X+020787Y+031732X0150Y0150     S2      
327GND              U2    -W23        A01X+020787Y+031417X0150Y0150     S2      
327GND              U2    -V25        A01X+021102Y+031732X0150Y0150     S2      
327GND              U2    -W25        A01X+021102Y+031417X0150Y0150     S2      
327NNAME10302       U2    -V21        A01X+020472Y+031732X0150Y0150     S2      
327NNAME10303       U2    -V20        A01X+020187Y+031732X0120Y0120R180 S2      
317GND              VIA   -     D0100PA00X+020930Y+032280               S3      
317GND              VIA   -     D0100PA00X+020731Y+033015               S3      
317NNAME10302       VIA   -     D0100PA00X+020630Y+031575               S3      
317NNAME10303       VIA   -     D0100PA00X+020306Y+031559               S3      
327NNAME10299       VIA   -           A10X+019880Y+031873X0260Y0260     S1      
317NNAME10201       VIA   -     D0100PA00X+020021Y+032145               S3      
317NNAME10203       VIA   -     D0100PA00X+020057Y+032392               S3      
317NNAME10300       VIA   -     D0100PA00X+020800Y+032520               S1      
317NNAME10301       VIA   -     D0100PA00X+020870Y+032800               S3      
317P1V5_NODE1       VIA   -     D0100PA00X+020059Y+032762               S3      
327P1V8_NODE1       C92   -1          A10X+020895Y+034372X0280Y0320     S1      
327P1V5_NODE1       R148  -1          A10X+019950Y+033101X0180Y0200R180 S1      
327GND              U2    -E18        A01X+019728Y+034205X0120Y0120     S2      
327GND              U2    -E22        A01X+020544Y+034178X0120Y0120     S2      
327NNAME10106       U2    -E23        A01X+020820Y+034198X0120Y0120     S2      
327N/C              U2    -H25        A01X+021086Y+033615X0120Y0120     S2      
327GND              U2    -K25        A01X+021086Y+033315X0120Y0120     S2      
327N/C              U2    -L25        A01X+021086Y+033015X0120Y0120     S2      
327N/C              U2    -G25        A01X+021086Y+033915X0120Y0120     S2      
327GND              U2    -H21        A01X+020304Y+033765X0120Y0120     S2      
327GND              U2    -H22        A01X+020580Y+033765X0120Y0120     S2      
327N/C              U2    -L22        A01X+020580Y+033165X0120Y0120     S2      
327N/C              U2    -J22        A01X+020580Y+033465X0120Y0120     S2      
327N/C              U2    -L21        A01X+020304Y+033165X0120Y0120     S2      
327N/C              U2    -J21        A01X+020304Y+033465X0120Y0120     S2      
327N/C              U2    -L18        A01X+019798Y+033015X0120Y0120     S2      
327GND              U2    -K18        A01X+019798Y+033315X0120Y0120     S2      
327N/C              U2    -H18        A01X+019798Y+033615X0120Y0120     S2      
327N/C              U2    -G18        A01X+019798Y+033915X0120Y0120     S2      
327NNAME10102       U2    -E19        A01X+020001Y+034254X0120Y0120     S2      
327NNAME10102       U2    -D23        A01X+020754Y+034469X0120Y0120     S2      
327NNAME10106       U2    -E21        A01X+020277Y+034254X0120Y0120     S2      
327NNAME10102       U2    -D24        A01X+021021Y+034387X0120Y0120     S2      
317GND              VIA   -     D0100PA00X+020849Y+033236               S3      
317GND              VIA   -     D0100PA00X+020091Y+033378               S3      
317GND              VIA   -     D0100PA00X+020149Y+033621               S3      
317GND              VIA   -     D0100PA00X+020149Y+033911               S3      
317GND              VIA   -     D0100PA00X+019724Y+034452               S3      
327NNAME10301       VIA   -           A10X+020632Y+033499X0260Y0260R180 S1      
327GND              C92   -2          A10X+020895Y+034952X0280Y0320     S1      
327GND              U2    -A21        A01X+020455Y+035059X0100Y0135     S2      
327GND              U2    -A18        A01X+019815Y+035059X0100Y0135     S2      
327GND              U2    -A24        A01X+021021Y+035059X0100Y0135     S2      
327NNAME10106       U2    -B21        A01X+020317Y+034819X0120Y0120     S2      
327GND              U2    -C18        A01X+019724Y+034662X0120Y0120     S2      
327NNAME10102       U2    -D19        A01X+019965Y+034528X0120Y0120     S2      
327NNAME10106       U2    -B19        A01X+019953Y+034818X0120Y0120     S2      
327GND              U2    -B23        A01X+020722Y+034884X0120Y0120     S2      
327GND              U2    -C22        A01X+020556Y+034664X0120Y0120     S2      
327NNAME10102       U2    -D21        A01X+020315Y+034528X0120Y0120     S2      
327NNAME10102       U2    -C24        A01X+021041Y+034687X0120Y0120     S2      
317GND              VIA   -     D0100PA00X+020682Y+035887               S3      
317GND              VIA   -     D0100PA00X+020727Y+035312               S3      
317GND              VIA   -     D0100PA00X+019899Y+035314               S3      
317GND              VIA   -     D0100PA00X+020666Y+035612               S3      
327GND              C136  -2          A01X+020200Y+037370X0180Y0200R180 S2      
327P3V3_NODE1       C136  -1          A01X+019885Y+037370X0180Y0200R180 S2      
317GND              VIA   -     D0100PA00X+020282Y+037692               S3      
317P3V3_NODE1       VIA   -     D0100PA00X+019794Y+037684               S3      
327NNAME10304       VIA   -           A10X+020069Y+037452X0260Y0260     S1      
317NNAME10305       VIA   -     D0100PA00X+020697Y+036190               S1      
327NNAME10306       VIA   -           A10X+020853Y+036678X0260Y0260     S1      
327NNAME10307       C137  -2          A01X+021166Y+039175X0180Y0200R270 S2      
327NNAME10308       C137  -1          A01X+021166Y+038860X0180Y0200R270 S2      
327P1V8_NODE1       R51   -2          A10X+020869Y+038227X0180Y0200R090 S1      
327NNAME10309       R51   -1          A10X+020869Y+037912X0180Y0200R090 S1      
327NNAME10305       R84   -2          A01X+020873Y+037917X0180Y0200R090 S2      
327GND              R84   -1          A01X+020873Y+038232X0180Y0200R090 S2      
327NNAME10304       R79   -2          A10X+020069Y+037912X0180Y0200R270 S1      
327GND              R79   -1          A10X+020069Y+038227X0180Y0200R270 S1      
327GND              R50   -2          A10X+020469Y+038227X0180Y0200R090 S1      
327NNAME10306       R50   -1          A10X+020469Y+037912X0180Y0200R090 S1      
327P3V3_NODE1       U9    -16         A01X+020127Y+038640X0150Y0280R180 S2      
327NNAME10258       U9    -15         A01X+019871Y+038640X0150Y0280R180 S2      
327NNAME10307       U9    -2          A01X+020436Y+039205X0150Y0280R270 S2      
327NNAME10308       U9    -1          A01X+020436Y+038949X0150Y0280R270 S2      
317GND              VIA   -     D0100PA00X+020044Y+039017               S3      
317GND              VIA   -     D0100PA00X+020388Y+038527               S3      
317P1V8_NODE1       VIA   -     D0100PA00X+020579Y+038700               S3      
327NNAME10310       C138  -2          A01X+021170Y+039869X0180Y0200R270 S2      
327NNAME10311       C138  -1          A01X+021170Y+039554X0180Y0200R270 S2      
327NNAME10312       U9    -6          A01X+019871Y+040026X0150Y0280R180 S2      
327NNAME10313       U9    -5          A01X+020127Y+040026X0150Y0280R180 S2      
327NNAME10310       U9    -4          A01X+020436Y+039716X0150Y0280R270 S2      
327NNAME10311       U9    -3          A01X+020436Y+039461X0150Y0280R270 S2      
317GND              VIA   -     D0100PA00X+020049Y+039643               S3      
317NNAME10313       VIA   -     D0100PA00X+020127Y+040329               S1      
317P1V8_NODE1       VIA   -     D0100PA00X+021088Y+040236               S3      
317P1V8_NODE1       VIA   -     D0100PA00X+020638Y+040220               S3      
327NNAME10263       PL2   -1          A01X+019982Y+042778X0848Y1300     S2      
317GND              VIA   -     D0100PA00X+020004Y+044875               S3      
317GND              VIA   -     D0100PA00X+020004Y+045135               S3      
327NNAME10314       C247  -2          A01X+020358Y+046995X0180Y0200R180 S2      
327GND              C247  -1          A01X+020043Y+046995X0180Y0200R180 S2      
327NNAME10314       R311  -2          A01X+020201Y+046563X0180Y0200R270 S2      
327NNAME10315       R311  -1          A01X+020201Y+046248X0180Y0200R270 S2      
327NNAME10314       OSC3  -4          A01X+020938Y+046940X0480Y0560R090 S2      
327NNAME10315       OSC3  -1          A01X+020938Y+046271X0480Y0560R090 S2      
317GND              VIA   -     D0100PA00X+019781Y+046995               S3      
317NNAME10315       VIA   -     D0100PA00X+020458Y+046248               S1      
317NNAME10314       VIA   -     D0100PA00X+019716Y+046563               S1      
327GND              C296  -2          A10X+020821Y+048643X0180Y0200R090 S1      
327NNAME10316       C296  -1          A10X+020821Y+048328X0180Y0200R090 S1      
327GND              C246  -2          A01X+020043Y+047425X0180Y0200     S2      
327NNAME10314       C246  -1          A01X+020358Y+047425X0180Y0200     S2      
327NNAME10316       L19   -1          A10X+020351Y+048145X0280Y0320     S1      
327NNAME10317       L19   -2          A10X+020351Y+048725X0280Y0320     S1      
327NNAME10314       L13   -1          A01X+020821Y+047615X0280Y0320R270 S2      
317GND              VIA   -     D0100PA00X+020043Y+047835               S3      
327NNAME10316       VIA   -           A10X+020363Y+047599X0260Y0260R090 S1      
317NNAME10317       VIA   -     D0100PA00X+020046Y+048725               S3      
327NNAME10317       C286  -1          A10X+020301Y+049265X0280Y0320R270 S1      
327GND              C286  -2          A10X+020881Y+049265X0280Y0320R270 S1      
317GND              VIA   -     D0100PA00X+020871Y+050086               S3      
317GND              VIA   -     D0100PA00X+021138Y+050190               S3      
327NNAME10317       VIA   -           A10X+019763Y+048984X0260Y0260R090 S1      
327NNAME10143       VIA   -           A01X+020821Y+050408X0300Y0300     S2      
317NNAME10216       VIA   -     D0100PA00X+021161Y+051655               S1      
327NNAME10142       VIA   -           A01X+019957Y+050645X0300Y0300     S2      
327NNAME10213       VIA   -           A01X+020529Y+051437X0300Y0300     S2      
327NNAME10211       VIA   -           A01X+020525Y+050871X0300Y0300     S2      
327GND              C204  -2          A10X+021142Y+052147X0180Y0200R180 S1      
317GND              VIA   -     D0100PA00X+020805Y+052888               S3      
327NNAME10212       VIA   -           A01X+020520Y+052234X0300Y0300     S2      
317NNAME10151       VIA   -     D0100PA00X+020526Y+052882               S1      
317NNAME10222       VIA   -     D0100PA00X+021129Y+052855               S1      
317GND              VIA   -     D0100PA00X+020989Y+053996               S3      
317GND              VIA   -     D0100PA00X+020151Y+053985               S3      
317NNAME10226       VIA   -     D0100PA00X+021234Y+053673               S1      
317NNAME10225       VIA   -     D0100PA00X+019954Y+053711               S1      
317NNAME10160       VIA   -     D0100PA00X+020731Y+053995               S3      
327NNAME10160       VIA   -           A01X+021071Y+054195X0200Y0040     S2      
317NNAME10158       VIA   -     D0100PA00X+020431Y+053995               S1      
317GND              VIA   -     D0100PA00X+019971Y+055165               S3      
317GND              VIA   -     D0100PA00X+020811Y+055105               S3      
317NNAME10230       VIA   -     D0100PA00X+020529Y+055113               S1      
317NNAME10232       VIA   -     D0100PA00X+020249Y+055113               S3      
327LAN1_NVM_SO_R    R549  -2          A01X+020718Y+057689X0180Y0200R180 S2      
327NNAME10270       R549  -1          A01X+020403Y+057689X0180Y0200R180 S2      
327LAN1_NVM_SK_R    R545  -2          A01X+020718Y+057289X0180Y0200R180 S2      
327NNAME10271       R545  -1          A01X+020403Y+057289X0180Y0200R180 S2      
327NNAME10267       R542  -2          A01X+020403Y+058089X0180Y0200     S2      
327P3V3_NODE1       R542  -1          A01X+020718Y+058089X0180Y0200     S2      
317LAN1_NVM_SK_R    VIA   -     D0100PA00X+021124Y+057289               S1      
317LAN1_NVM_SO_R    VIA   -     D0100PA00X+021004Y+057689               S3      
317NNAME10270       VIA   -     D0100PA00X+020151Y+057689               S1      
317NNAME10271       VIA   -     D0100PA00X+019773Y+057289               S1      
317NNAME10219       VIA   -     D0100PA00X+019771Y+056746               S1      
317P3V3_NODE1       VIA   -     D0100PA00X+020959Y+058089               S3      
317NNAME10045       VIA   -     D0100PA00X+021079Y+056693               S1      
327NNAME10318       R543  -2          A01X+020718Y+058489X0180Y0200R180 S2      
327NNAME10267       R543  -1          A01X+020403Y+058489X0180Y0200R180 S2      
327PLT_RST_LAN1_N   R560  -2          A01X+020403Y+058889X0180Y0200     S2      
327NNAME10319       R560  -1          A01X+020718Y+058889X0180Y0200     S2      
317NNAME10318       VIA   -     D0100PA00X+020994Y+058489               S1      
317P1V05_LAN1       VIA   -     D0100PA00X+019723Y+059534               S3      
317NNAME10269       VIA   -     D0100PA00X+019889Y+058411               S3      
317NNAME10319       VIA   -     D0100PA00X+020718Y+059160               S3      
317GND              VIA   -     D0100PA00X+021176Y+061092               S3      
317GND              VIA   -     D0100PA00X+020748Y+060894               S3      
317GND              VIA   -     D0100PA00X+020701Y+060247               S3      
327NNAME10274       VIA   -           A01X+020843Y+059974X0160Y0042R180 S2      
327NNAME10275       VIA   -           A01X+019821Y+060146X0160Y0042R180 S2      
317P1V9_LAN1        VIA   -     D0100PA00X+019691Y+060501               S3      
317P1V9_LAN1        VIA   -     D0100PA00X+019703Y+059854               S3      
327P1V05_LAN1       VIA   -           A10X+019821Y+061109X0260Y0260R090 S1      
317NNAME10053       VIA   -     D0100PA00X+020402Y+060414               S1      
317NNAME10054       VIA   -     D0100PA00X+020402Y+060914               S1      
317NNAME10273       VIA   -     D0100PA00X+020890Y+061152               S1      
327LAN1_DISABLE_N   R596  -2          A01X+020930Y+062198X0180Y0200     S2      
327LAN1_TEST_EN     R558  -2          A01X+020930Y+062598X0180Y0200     S2      
317NNAME10276       VIA   -     D0100PA00X+020038Y+062909               S1      
317LAN1_DISABLE_N   VIA   -     D0100PA00X+019979Y+061889               S1      
317GND              VIA   -     D0100PA00X+021186Y+061771               S3      
317LAN1_TEST_EN     VIA   -     D0100PA00X+020251Y+062401               S1      
317P1V05_LAN1       VIA   -     D0100PA00X+019723Y+061544               S3      
317P3V3_NODE1       VIA   -     D0100PA00X+019713Y+062614               S3      
317NNAME10272       VIA   -     D0100PA00X+020890Y+061652               S1      
327LAN1_LED_ACT_N   C517  -1          A01X+020930Y+062998X0180Y0200R180 S2      
327NNAME10277       C519  -1          A01X+020930Y+063798X0180Y0200R180 S2      
327NNAME10276       C518  -1          A01X+020930Y+063398X0180Y0200R180 S2      
327SMB_LAN1_CLK     R539  -2          A01X+020541Y+064370X0180Y0200R090 S2      
327SMB_LAN1_ALT_N   R538  -2          A01X+020091Y+064370X0180Y0200R090 S2      
317SMB_LAN1_ALT_N   VIA   -     D0100PA00X+019748Y+063982               S1      
317SMB_LAN1_CLK     VIA   -     D0100PA00X+020307Y+063870               S1      
317LAN1_LED_ACT_N   VIA   -     D0100PA00X+020522Y+063089               S1      
327SMB_LAN1_CLK     R563  -2          A01X+020541Y+065370X0180Y0200R090 S2      
327SMB_PCH_SCL      R563  -1          A01X+020541Y+065685X0180Y0200R090 S2      
327SMB_LAN1_ALT_N   R561  -2          A01X+020091Y+065370X0180Y0200R090 S2      
327NNAME10320       R561  -1          A01X+020091Y+065685X0180Y0200R090 S2      
327P3V3_NODE1       R539  -1          A01X+020541Y+064685X0180Y0200R090 S2      
327P3V3_NODE1       R538  -1          A01X+020091Y+064685X0180Y0200R090 S2      
317NNAME10320       VIA   -     D0100PA00X+020091Y+065974               S3      
317P3V3_NODE1       VIA   -     D0100PA00X+020091Y+065016               S3      
317P3V3_NODE1       VIA   -     D0100PA00X+020541Y+065004               S3      
327GND              C618  -2          A01X+020888Y+067177X0180Y0200R180 S2      
327P3V3_NODE1       C618  -1          A01X+020573Y+067177X0180Y0200R180 S2      
317GND              VIA   -     D0100PA00X+020924Y+067437               S3      
317GND              VIA   -     D0100PA00X+020245Y+066363               S3      
317SMB_PCH_SDA      VIA   -     D0100PA00X+019951Y+066316               S3      
317SMB_PCH_SCL      VIA   -     D0100PA00X+020541Y+066120               S1      
317PSU4_DC_OK       VIA   -     D0100PA00X+021156Y+067058               S1      
317P3V3_NODE1       VIA   -     D0100PA00X+020252Y+067327               S3      
317P3V3_NODE1       VIA   -     D0100PA00X+019789Y+067123               S3      
327PSU_ALERT_N      U63   -17         A10X+020594Y+069032X0140Y0590R090 S1      
327PSU6_DC_OK       U63   -16         A10X+020594Y+068776X0140Y0590R090 S1      
327PSU5_DC_OK       U63   -15         A10X+020594Y+068520X0140Y0590R090 S1      
327PSU4_DC_OK       U63   -14         A10X+020594Y+068264X0140Y0590R090 S1      
327PSU3_DC_OK       U63   -13         A10X+020594Y+068008X0140Y0590R090 S1      
327N/C              U85   -1          A01X+020747Y+068800X0180Y0520R180 S2      
327NNAME10279       U85   -2          A01X+020373Y+068800X0180Y0520R180 S2      
327GND              U85   -3          A01X+019999Y+068800X0180Y0520R180 S2      
327PSU5_DC_OK       U85   -4          A01X+019999Y+067836X0180Y0520R180 S2      
327P3V3_NODE1       U85   -5          A01X+020747Y+067836X0180Y0520R180 S2      
317PSU_ALERT_N      VIA   -     D0100PA00X+021082Y+069227               S3      
317PSU5_DC_OK       VIA   -     D0100PA00X+019959Y+068287               S1      
327I2C_COM3_SDA     U63   -23         A10X+020594Y+070567X0140Y0590R090 S1      
327I2C_COM3_SCL     U63   -22         A10X+020594Y+070311X0140Y0590R090 S1      
327N21699710        U63   -21         A10X+020594Y+070055X0140Y0590R090 S1      
327N/C              U63   -20         A10X+020594Y+069800X0140Y0590R090 S1      
327NNAME10238       U63   -19         A10X+020594Y+069544X0140Y0590R090 S1      
327N/C              U63   -18         A10X+020594Y+069288X0140Y0590R090 S1      
327PSU_DC_OK_N      U96   -D          A01X+020144Y+069956X0400Y0500R180 S2      
327NNAME10279       U96   -G          A01X+020544Y+070836X0400Y0500R180 S2      
327GND              U98   -S          A01X+021144Y+070836X0400Y0500R180 S2      
317I2C_COM3_SCL     VIA   -     D0100PA00X+019758Y+070347               S3      
317I2C_COM3_SDA     VIA   -     D0100PA00X+020069Y+070408               S3      
317NNAME10279       VIA   -     D0100PA00X+019935Y+069272               S1      
327N21699710        VIA   -           A10X+019697Y+070071X0260Y0260     S1      
317PSU_DC_OK_N      VIA   -     D0100PA00X+021124Y+069559               S3      
317PSU_DC_OK_N      VIA   -     D0100PA00X+019724Y+069790               S3      
327P3V3_NODE1       U63   -24         A10X+020594Y+070823X0140Y0590R090 S1      
327P3V3_NODE1       C569  -2          A10X+019702Y+070816X0180Y0200     S1      
327GND              C605  -2          A01X+019894Y+071593X0180Y0200R090 S2      
327PSU3_AC_OK       C605  -1          A01X+019894Y+071908X0180Y0200R090 S2      
327GND              C601  -2          A10X+020794Y+071493X0180Y0200R270 S1      
327NNAME10321       C601  -1          A10X+020794Y+071808X0180Y0200R270 S1      
327GND              C603  -2          A10X+020344Y+071490X0180Y0200R270 S1      
327NNAME10322       C603  -1          A10X+020344Y+071805X0180Y0200R270 S1      
327GND              C606  -2          A10X+019894Y+071493X0180Y0200R270 S1      
327NNAME10323       C606  -1          A10X+019894Y+071808X0180Y0200R270 S1      
327GND              C600  -2          A01X+020794Y+071593X0180Y0200R090 S2      
327PSU1_AC_OK       C600  -1          A01X+020794Y+071908X0180Y0200R090 S2      
327GND              C602  -2          A01X+020344Y+071590X0180Y0200R090 S2      
327PSU2_AC_OK       C602  -1          A01X+020344Y+071905X0180Y0200R090 S2      
317GND              VIA   -     D0100PA00X+021002Y+071284               S3      
317GND              VIA   -     D0100PA00X+020166Y+071269               S3      
317GND              VIA   -     D0100PA00X+019894Y+071250               S3      
317PSU3_AC_OK       VIA   -     D0100PA00X+019857Y+072235               S1      
317PSU1_AC_OK       VIA   -     D0100PA00X+020902Y+072234               S1      
317PSU2_AC_OK       VIA   -     D0100PA00X+020361Y+072230               S1      
317NNAME10279       VIA   -     D0100PA00X+020544Y+071251               S3      
317NNAME10321       VIA   -     D0100PA00X+021190Y+072387               S3      
317P3V3_NODE1       VIA   -     D0100PA00X+020141Y+070823               S3      
327GND              R845  -2          A01X+020794Y+073908X0180Y0200R090 S2      
327GND              R848  -2          A01X+020344Y+073908X0180Y0200R090 S2      
327GND              R849  -2          A01X+019894Y+073908X0180Y0200R090 S2      
327GND              R853  -2          A10X+020794Y+073908X0180Y0200R270 S1      
327GND              R854  -2          A10X+020344Y+073908X0180Y0200R270 S1      
327GND              R855  -2          A10X+019894Y+073908X0180Y0200R270 S1      
327NNAME10321       R832  -2          A10X+020794Y+072758X0180Y0200R270 S1      
327PSU1_DC_OK_R     R832  -1          A10X+020794Y+073073X0180Y0200R270 S1      
327NNAME10322       R834  -2          A10X+020344Y+072758X0180Y0200R270 S1      
327PSU2_DC_OK_R     R834  -1          A10X+020344Y+073073X0180Y0200R270 S1      
327NNAME10323       R837  -2          A10X+019894Y+072758X0180Y0200R270 S1      
327PSU3_DC_OK_R     R837  -1          A10X+019894Y+073073X0180Y0200R270 S1      
327PSU1_AC_OK       R831  -2          A01X+020794Y+072758X0180Y0200R090 S2      
327PSU1_AC_OK_R     R831  -1          A01X+020794Y+073073X0180Y0200R090 S2      
327PSU2_AC_OK       R833  -2          A01X+020344Y+072758X0180Y0200R090 S2      
327PSU2_AC_OK_R     R833  -1          A01X+020344Y+073073X0180Y0200R090 S2      
327PSU3_AC_OK       R836  -2          A01X+019894Y+072758X0180Y0200R090 S2      
327PSU3_AC_OK_R     R836  -1          A01X+019894Y+073073X0180Y0200R090 S2      
317GND              VIA   -     D0100PA00X+021244Y+073583               S3      
317GND              VIA   -     D0100PA00X+019894Y+073568               S3      
317GND              VIA   -     D0100PA00X+020794Y+073568               S3      
317GND              VIA   -     D0100PA00X+020344Y+073568               S3      
317NNAME10322       VIA   -     D0100PA00X+020588Y+072437               S3      
317NNAME10323       VIA   -     D0100PA00X+020082Y+072418               S3      
327PSU1_AC_OK_R     R845  -1          A01X+020794Y+074223X0180Y0200R090 S2      
327PSU2_AC_OK_R     R848  -1          A01X+020344Y+074223X0180Y0200R090 S2      
327PSU3_AC_OK_R     R849  -1          A01X+019894Y+074223X0180Y0200R090 S2      
327PSU1_DC_OK_R     R853  -1          A10X+020794Y+074223X0180Y0200R270 S1      
327PSU2_DC_OK_R     R854  -1          A10X+020344Y+074223X0180Y0200R270 S1      
327PSU3_DC_OK_R     R855  -1          A10X+019894Y+074223X0180Y0200R270 S1      
317PSU2_AC_OK_R     VIA   -     D0100PA00X+019976Y+076393               S1      
327NNAME10324       VIA   -           A10X+021025Y+078492X0260Y0260     S1      
317PSU1_AC_OK_R     VIA   -     D0100PA00X+020205Y+078492               S1      
327PSU1_DC_OK_R     VIA   -           A10X+020055Y+077205X0260Y0260     S1      
327NNAME10325       VIA   -           A10X+020618Y+077765X0260Y0260     S1      
327PSU2_DC_OK_R     VIA   -           A10X+019689Y+077916X0260Y0260     S1      
317I2C_PSU1_R_SDA   VIA   -     D0100PA00X+020621Y+077158               S1      
317I2C_PSU1_R_SCL   VIA   -     D0100PA00X+021235Y+077328               S1      
327GND              J35   -A44        A10X+020085Y+080787X0300Y1660R180 S1      
327NNAME10325       J35   -A43        A10X+020478Y+080787X0300Y1660R180 S1      
327NNAME10324       J35   -A42        A10X+020872Y+080787X0300Y1660R180 S1      
327NNAME10326       J35   -A41        A10X+021266Y+080787X0300Y1660R180 S1      
327GND              J35   -B44        A01X+020085Y+080787X0300Y1660R180 S2      
327I2C_PSU1_R_SDA   J35   -B43        A01X+020478Y+080787X0300Y1660R180 S2      
327I2C_PSU1_R_SCL   J35   -B42        A01X+020872Y+080787X0300Y1660R180 S2      
327GND              J35   -B41        A01X+021266Y+080787X0300Y1660R180 S2      
317GND              VIA   -     D0100PA00X+020085Y+078870               S3      
317GND              VIA   -     D0100PA00X+020085Y+079170               S3      
327GND              PC80  -2          A01X+022633Y+001389X0950Y1110R270 S2      
317GND              VIA   -     D0100PA00X+022599Y+002122               S3      
317GND              VIA   -     D0100PA00X+022199Y+002122               S3      
327PV_VDDR_NODE1    PC80  -1          A01X+022633Y+003908X0950Y1110R270 S2      
317PV_VDDR_NODE1    VIA   -     D0100PA00X+022229Y+004550               S3      
317PV_VDDR_NODE1    VIA   -     D0100PA00X+022629Y+004550               S3      
327GND              PC83  -2          A01X+022331Y+006244X0440Y0540R270 S2      
327PV_VDDR_NODE1    PC83  -1          A01X+022331Y+005496X0440Y0540R270 S2      
317PV_VDDR_NODE1    VIA   -     D0100PA00X+022131Y+005110               S3      
317PV_VDDR_NODE1    VIA   -     D0100PA00X+022531Y+005110               S3      
317GND              VIA   -     D0100PA00X+022160Y+006632               S3      
317GND              VIA   -     D0100PA00X+022560Y+006632               S3      
327PD_NODE1_DM3     R209  -2          A10X+022474Y+008463X0180Y0200     S1      
327GND              R209  -1          A10X+022159Y+008463X0180Y0200     S1      
327PD_NODE1_DM3     J2    -59         A01X+022736Y+008248X0150Y0810     S2      
327NNAME10327       J2    -57         A01X+022500Y+008248X0150Y0810     S2      
327NNAME10291       J2    -55         A01X+022264Y+008248X0150Y0810     S2      
327GND              J2    -53         A01X+022028Y+008248X0150Y0810     S2      
327NNAME10328       J2    -51         A01X+021791Y+008248X0150Y0810     S2      
327NNAME10294       J2    -49         A01X+021555Y+008248X0150Y0810     S2      
327GND              J2    -47         A01X+021319Y+008248X0150Y0810     S2      
317GND              VIA   -     D0100PA00X+021319Y+008841               S3      
317GND              VIA   -     D0100PA00X+022028Y+008844               S3      
317GND              VIA   -     D0100PA00X+021457Y+009377               S3      
317NNAME10294       VIA   -     D0100PA00X+021577Y+009015               S1      
317NNAME10291       VIA   -     D0100PA00X+022298Y+009159               S3      
317NNAME10328       VIA   -     D0100PA00X+022020Y+009356               S1      
317PD_NODE1_DM3     VIA   -     D0100PA00X+022662Y+008939               S1      
317GND              VIA   -     D0100PA00X+021910Y+010868               S3      
317GND              VIA   -     D0100PA00X+021704Y+010312               S3      
317NNAME10329       VIA   -     D0100PA00X+021432Y+010198               S1      
317NNAME10292       VIA   -     D0100PA00X+022098Y+010617               S1      
317NNAME10281       VIA   -     D0100PA00X+021391Y+009698               S1      
317NNAME10330       VIA   -     D0100PA00X+021951Y+010134               S1      
327GND              J2    -58         A01X+022618Y+011476X0150Y0810     S2      
327NNAME10331       J2    -56         A01X+022382Y+011476X0150Y0810     S2      
327NNAME10292       J2    -54         A01X+022146Y+011476X0150Y0810     S2      
327GND              J2    -52         A01X+021910Y+011476X0150Y0810     S2      
327NNAME10330       J2    -50         A01X+021673Y+011476X0150Y0810     S2      
327NNAME10329       J2    -48         A01X+021437Y+011476X0150Y0810     S2      
327GND              J2    -46         A01X+021201Y+011476X0150Y0810     S2      
317GND              VIA   -     D0100PA00X+022671Y+012201               S3      
317NNAME10290       VIA   -     D0100PA00X+022814Y+012580               S1      
327NNAME10332       R33   -1          A10X+022685Y+021690X0180Y0200     S1      
327PV_VDDR_NODE1    C117  -1          A10X+022142Y+023397X0180Y0200R090 S1      
327NNAME10332       R32   -1          A10X+022685Y+022090X0180Y0200     S1      
317NNAME10333       VIA   -     D0100PA00X+022601Y+023354               S1      
317NNAME10331       VIA   -     D0100PA00X+021714Y+023059               S1      
327GND              C118  -2          A10X+022187Y+024362X0180Y0200R180 S1      
327PV_VDDR_NODE1    C118  -1          A10X+022502Y+024362X0180Y0200R180 S1      
327GND              C117  -2          A10X+022142Y+023712X0180Y0200R090 S1      
327NNAME10334       R28   -2          A10X+022545Y+024752X0180Y0200     S1      
327GND              R28   -1          A10X+022230Y+024752X0180Y0200     S1      
327GND              R30   -2          A10X+021756Y+024680X0180Y0200R270 S1      
327NNAME10335       R30   -1          A10X+021756Y+024995X0180Y0200R270 S1      
327NNAME10336       U2    -BM31       A01X+022400Y+025022X0120Y0120     S2      
327NNAME10337       U2    -BM27       A01X+021569Y+025021X0120Y0120     S2      
327GND              U2    -BP28       A01X+021669Y+024626X0100Y0135     S2      
327NNAME10338       U2    -BP31       A01X+022309Y+024626X0100Y0135     S2      
327NNAME10293       U2    -BN26       A01X+021402Y+024801X0120Y0120     S2      
327NNAME10327       U2    -BN28       A01X+021807Y+024866X0120Y0120     S2      
327GND              U2    -BN30       A01X+022172Y+024866X0120Y0120     S2      
327NNAME10339       U2    -BN32       A01X+022592Y+024822X0120Y0120     S2      
317GND              VIA   -     D0100PA00X+021714Y+024409               S3      
317NNAME10339       VIA   -     D0100PA00X+022601Y+024034               S3      
317NNAME10337       VIA   -     D0100PA00X+021714Y+024079               S1      
317NNAME10327       VIA   -     D0100PA00X+021714Y+023739               S3      
317PV_VDDR_NODE1    VIA   -     D0100PA00X+022752Y+024419               S3      
327GND              C93   -2          A10X+022022Y+026669X0280Y0320R180 S1      
327GND              R29   -2          A10X+022230Y+025152X0180Y0200R180 S1      
327NNAME10340       R29   -1          A10X+022545Y+025152X0180Y0200R180 S1      
327GND              U2    -BL30       A01X+022159Y+025157X0120Y0120     S2      
327NNAME10331       U2    -BL28       A01X+021809Y+025157X0120Y0120     S2      
327GND              U2    -BG30       A01X+022238Y+025920X0120Y0120     S2      
327NNAME10330       U2    -BG29       A01X+021962Y+025920X0120Y0120     S2      
327GND              U2    -BD29       A01X+021962Y+026520X0120Y0120     S2      
327GND              U2    -BF29       A01X+021962Y+026220X0120Y0120     S2      
327GND              U2    -BD30       A01X+022238Y+026520X0120Y0120     S2      
327GND              U2    -BF30       A01X+022238Y+026220X0120Y0120     S2      
327GND              U2    -BG26       A01X+021456Y+026070X0120Y0120     S2      
327NNAME10285       U2    -BH26       A01X+021456Y+025770X0120Y0120     S2      
327NNAME10281       U2    -BE26       A01X+021456Y+026370X0120Y0120     S2      
327NNAME10294       U2    -BG25       A01X+021180Y+026070X0120Y0120     S2      
327NNAME10284       U2    -BH25       A01X+021180Y+025770X0120Y0120     S2      
327GND              U2    -BE25       A01X+021180Y+026370X0120Y0120     S2      
327NNAME10289       U2    -BL26       A01X+021370Y+025216X0120Y0120     S2      
327GND              U2    -BK26       A01X+021304Y+025487X0120Y0120     S2      
327GND              U2    -BK31       A01X+022396Y+025483X0120Y0120     S2      
327GND              U2    -BK27       A01X+021580Y+025506X0120Y0120     S2      
327GND              U2    -BK30       A01X+022123Y+025431X0120Y0120     S2      
327GND              U2    -BK28       A01X+021847Y+025431X0120Y0120     S2      
327NNAME10333       U2    -BL32       A01X+022612Y+025199X0120Y0120     S2      
327PV_VDDR_NODE1    U2    -BK32       A01X+022675Y+025487X0120Y0120     S2      
317GND              VIA   -     D0100PA00X+021977Y+025266               S3      
317GND              VIA   -     D0100PA00X+021576Y+025283               S3      
317GND              VIA   -     D0100PA00X+022479Y+025675               S3      
317GND              VIA   -     D0100PA00X+021815Y+026070               S3      
317GND              VIA   -     D0100PA00X+021815Y+026370               S3      
317GND              VIA   -     D0100PA00X+022393Y+026364               S3      
317NNAME10285       VIA   -     D0100PA00X+021651Y+025849               S1      
317NNAME10341       VIA   -     D0100PA00X+022597Y+026220               S3      
317NNAME10282       VIA   -     D0100PA00X+021611Y+026514               S3      
317NNAME10281       VIA   -     D0100PA00X+021611Y+026214               S3      
317NNAME10330       VIA   -     D0100PA00X+021851Y+025666               S3      
317PV_VDDR_NODE1    VIA   -     D0100PA00X+022597Y+026520               S3      
327NNAME10335       VIA   -           A10X+022178Y+025632X0260Y0260     S1      
317NNAME10335       VIA   -     D0100PA00X+022597Y+025920               S3      
327GND              C80   -2          A10X+022409Y+027699X0180Y0200     S1      
327NNAME10342       C80   -1          A10X+022094Y+027699X0180Y0200     S1      
327GND              C95   -2          A10X+021327Y+026813X0180Y0200R270 S1      
327P1V5_SUS_NODE1   C95   -1          A10X+021327Y+027128X0180Y0200R270 S1      
327GND              C94   -2          A10X+022700Y+026901X0180Y0200R270 S1      
327NNAME10296       C94   -1          A10X+022700Y+027216X0180Y0200R270 S1      
327NNAME10296       C93   -1          A10X+022022Y+027249X0280Y0320R180 S1      
327NNAME10342       L7    -2          A10X+022202Y+028091X0180Y0200R270 S1      
327NNAME10296       L8    -2          A10X+021707Y+027757X0180Y0200     S1      
327P1V5_SUS_NODE1   L8    -1          A10X+021392Y+027757X0180Y0200     S1      
327NNAME10038       PJ7   -2          A10X+022772Y+027784X0180Y0200R270 S1      
327GND              PJ7   -1          A10X+022772Y+028099X0200Y0400     S1      
327GND              U2    -AU31       A01X+022362Y+027952X0150Y0150     S2      
327P1V05_NODE1      U2    -AU29       A01X+022047Y+027952X0150Y0150     S2      
327P1V05_NODE1      U2    -AU26       A01X+021417Y+027952X0150Y0150     S2      
327P1V05_NODE1      U2    -AU28       A01X+021732Y+027952X0150Y0150     S2      
327GND              U2    -AW30       A01X+022087Y+027677X0120Y0120     S2      
327GND              U2    -AW25       A01X+021180Y+027570X0120Y0120     S2      
327GND              U2    -AW26       A01X+021456Y+027570X0120Y0120     S2      
327GND              U2    -AW28       A01X+021732Y+027677X0120Y0120     S2      
327GND              U2    -AW31       A01X+022362Y+027677X0120Y0120     S2      
327GND              U2    -AY29       A01X+021962Y+027420X0120Y0120     S2      
327GND              U2    -AY30       A01X+022238Y+027420X0120Y0120     S2      
327GND              U2    -BA30       A01X+022238Y+027120X0120Y0120     S2      
327NNAME10329       U2    -BA29       A01X+021962Y+027120X0120Y0120     S2      
327GND              U2    -BC29       A01X+021962Y+026820X0120Y0120     S2      
327GND              U2    -BC30       A01X+022238Y+026820X0120Y0120     S2      
327NNAME10328       U2    -BB26       A01X+021456Y+026970X0120Y0120     S2      
327GND              U2    -BA26       A01X+021456Y+027270X0120Y0120     S2      
327NNAME10245       U2    -BB25       A01X+021180Y+026970X0120Y0120     S2      
327NNAME10283       U2    -BA25       A01X+021180Y+027270X0120Y0120     S2      
327NNAME10282       U2    -BD26       A01X+021456Y+026670X0120Y0120     S2      
327GND              U2    -BD25       A01X+021180Y+026670X0120Y0120     S2      
327P1V05_NODE1      U2    -AU32       A01X+022677Y+027952X0150Y0150     S2      
317GND              VIA   -     D0100PA00X+022520Y+028110               S3      
317GND              VIA   -     D0100PA00X+021611Y+027414               S3      
317GND              VIA   -     D0100PA00X+021260Y+028110               S3      
317P1V05_NODE1      VIA   -     D0100PA00X+021890Y+028110               S3      
317NNAME10342       VIA   -     D0100PA00X+022436Y+027323               S3      
317NNAME10329       VIA   -     D0100PA00X+021618Y+026859               S3      
317NNAME10328       VIA   -     D0100PA00X+021611Y+027114               S3      
317P1V5_NODE1       VIA   -     D0100PA00X+021575Y+028110               S3      
317P1V5_SUS_NODE1   VIA   -     D0100PA00X+021314Y+027419               S3      
327P1V05_NODE1      C125  -1          A10X+021502Y+028462X0180Y0200R180 S1      
327GND              C129  -2          A10X+021818Y+029703X0180Y0200R180 S1      
327P1V05_NODE1      C129  -1          A10X+022133Y+029703X0180Y0200R180 S1      
327GND              C121  -2          A10X+021815Y+029309X0180Y0200R180 S1      
327P1V05_NODE1      C121  -1          A10X+022130Y+029309X0180Y0200R180 S1      
327P1V05_NODE1      L7    -1          A10X+022202Y+028406X0180Y0200R270 S1      
327P1V05_NODE1      U2    -AT31       A01X+022362Y+028267X0150Y0150     S2      
327GND              U2    -AT29       A01X+022047Y+028267X0150Y0150     S2      
327P1V5_NODE1       U2    -AT28       A01X+021732Y+028267X0150Y0150     S2      
327GND              U2    -AT26       A01X+021417Y+028267X0150Y0150     S2      
327GND              U2    -AP31       A01X+022362Y+028582X0150Y0150     S2      
327P1V05_NODE1      U2    -AM31       A01X+022362Y+028897X0150Y0150     S2      
327GND              U2    -AL31       A01X+022362Y+029212X0150Y0150     S2      
327P1V05_NODE1      U2    -AJ31       A01X+022362Y+029527X0150Y0150     S2      
327P1V05_NODE1      U2    -AP29       A01X+022047Y+028582X0150Y0150     S2      
327GND              U2    -AM29       A01X+022047Y+028897X0150Y0150     S2      
327P1V05_NODE1      U2    -AL29       A01X+022047Y+029212X0150Y0150     S2      
327GND              U2    -AJ29       A01X+022047Y+029527X0150Y0150     S2      
327P1V05_NODE1      U2    -AP28       A01X+021732Y+028582X0150Y0150     S2      
327P1V5_NODE1       U2    -AM28       A01X+021732Y+028897X0150Y0150     S2      
327P1V05_NODE1      U2    -AL28       A01X+021732Y+029212X0150Y0150     S2      
327P1V5_NODE1       U2    -AJ28       A01X+021732Y+029527X0150Y0150     S2      
327P1V05_NODE1      U2    -AP26       A01X+021417Y+028582X0150Y0150     S2      
327GND              U2    -AM26       A01X+021417Y+028897X0150Y0150     S2      
327P1V05_NODE1      U2    -AL26       A01X+021417Y+029212X0150Y0150     S2      
327GND              U2    -AJ26       A01X+021417Y+029527X0150Y0150     S2      
327GND              U2    -AT32       A01X+022677Y+028267X0150Y0150     S2      
327GND              U2    -AJ32       A01X+022677Y+029527X0150Y0150     S2      
327P1V05_NODE1      U2    -AL32       A01X+022677Y+029212X0150Y0150     S2      
327GND              U2    -AM32       A01X+022677Y+028897X0150Y0150     S2      
327P1V05_NODE1      U2    -AP32       A01X+022677Y+028582X0150Y0150     S2      
317GND              VIA   -     D0100PA00X+021260Y+029055               S3      
317GND              VIA   -     D0100PA00X+022520Y+028740               S3      
317GND              VIA   -     D0100PA00X+021260Y+029370               S3      
317GND              VIA   -     D0100PA00X+022205Y+029055               S3      
317P1V05_NODE1      VIA   -     D0100PA00X+022516Y+029368               S3      
317P1V05_NODE1      VIA   -     D0100PA00X+022520Y+029055               S3      
317P1V05_NODE1      VIA   -     D0100PA00X+022520Y+028425               S3      
317P1V05_NODE1      VIA   -     D0100PA00X+022205Y+028740               S3      
317P1V05_NODE1      VIA   -     D0100PA00X+021260Y+028740               S3      
317P1V05_NODE1      VIA   -     D0100PA00X+021575Y+029055               S3      
327NNAME10342       VIA   -           A10X+021920Y+028834X0260Y0260R180 S1      
317P1V5_NODE1       VIA   -     D0100PA00X+021575Y+029370               S3      
317P1V5_NODE1       VIA   -     D0100PA00X+021575Y+028740               S3      
327GND              C49   -2          A10X+021602Y+031312X0180Y0200     S1      
327P1V05_NODE1      C49   -1          A10X+021287Y+031312X0180Y0200     S1      
327GND              C104  -2          A10X+021602Y+030912X0180Y0200     S1      
327P1V05_NODE1      C104  -1          A10X+021287Y+030912X0180Y0200     S1      
327GND              C58   -2          A10X+021552Y+030204X0180Y0200R270 S1      
327P1V05_NODE1      C58   -1          A10X+021552Y+030519X0180Y0200R270 S1      
327GND              C44   -2          A10X+022795Y+030954X0180Y0200R270 S1      
327P1V05_NODE1      C44   -1          A10X+022795Y+031269X0180Y0200R270 S1      
327GND              C45   -2          A10X+022771Y+030277X0180Y0200R090 S1      
327P1V05_NODE1      C45   -1          A10X+022771Y+029962X0180Y0200R090 S1      
327P1V05_NODE1      U2    -AF31       A01X+022362Y+030157X0150Y0150     S2      
327GND              U2    -AG31       A01X+022362Y+029842X0150Y0150     S2      
327GND              U2    -AF29       A01X+022047Y+030157X0150Y0150     S2      
327P1V05_NODE1      U2    -AG29       A01X+022047Y+029842X0150Y0150     S2      
327P1V5_NODE1       U2    -AF28       A01X+021732Y+030157X0150Y0150     S2      
327P1V8_NODE1       U2    -AG28       A01X+021732Y+029842X0150Y0150     S2      
327GND              U2    -AF26       A01X+021417Y+030157X0150Y0150     S2      
327GND              U2    -AG26       A01X+021417Y+029842X0150Y0150     S2      
327P1V05_NODE1      U2    -AA31       A01X+022362Y+031102X0150Y0150     S2      
327P1V05_NODE1      U2    -AC31       A01X+022362Y+030787X0150Y0150     S2      
327GND              U2    -AD31       A01X+022362Y+030472X0150Y0150     S2      
327GND              U2    -AA29       A01X+022047Y+031102X0150Y0150     S2      
327GND              U2    -AC29       A01X+022047Y+030787X0150Y0150     S2      
327P1V05_NODE1      U2    -AD29       A01X+022047Y+030472X0150Y0150     S2      
327P1V5_NODE1       U2    -AA28       A01X+021732Y+031102X0150Y0150     S2      
327GND              U2    -AC28       A01X+021732Y+030787X0150Y0150     S2      
327P1V05_NODE1      U2    -AD28       A01X+021732Y+030472X0150Y0150     S2      
327GND              U2    -AA26       A01X+021417Y+031102X0150Y0150     S2      
327P1V05_NODE1      U2    -AC26       A01X+021417Y+030787X0150Y0150     S2      
327GND              U2    -AD26       A01X+021417Y+030472X0150Y0150     S2      
327P1V05_NODE1      U2    -AG32       A01X+022677Y+029842X0150Y0150     S2      
327GND              U2    -AF32       A01X+022677Y+030157X0150Y0150     S2      
327P1V05_NODE1      U2    -AD32       A01X+022677Y+030472X0150Y0150     S2      
327GND              U2    -AC32       A01X+022677Y+030787X0150Y0150     S2      
327GND              U2    -AA32       A01X+022677Y+031102X0150Y0150     S2      
317GND              VIA   -     D0100PA00X+022520Y+030945               S3      
317GND              VIA   -     D0100PA00X+022520Y+030000               S3      
317GND              VIA   -     D0100PA00X+022520Y+030315               S3      
317GND              VIA   -     D0100PA00X+022205Y+030945               S3      
317GND              VIA   -     D0100PA00X+021260Y+030000               S3      
317GND              VIA   -     D0100PA00X+021260Y+030315               S3      
317GND              VIA   -     D0100PA00X+022205Y+031260               S3      
317GND              VIA   -     D0100PA00X+021890Y+030945               S3      
317GND              VIA   -     D0100PA00X+022205Y+030315               S3      
317P1V05_NODE1      VIA   -     D0100PA00X+022520Y+030630               S3      
317P1V05_NODE1      VIA   -     D0100PA00X+022520Y+031260               S3      
317P1V05_NODE1      VIA   -     D0100PA00X+022205Y+030630               S3      
317P1V05_NODE1      VIA   -     D0100PA00X+021890Y+030630               S3      
317P1V05_NODE1      VIA   -     D0100PA00X+022205Y+030000               S3      
317P1V05_NODE1      VIA   -     D0100PA00X+021261Y+030631               S3      
317P1V8_NODE1       VIA   -     D0100PA00X+021890Y+030000               S3      
317P1V5_NODE1       VIA   -     D0100PA00X+021890Y+030315               S3      
317P1V5_NODE1       VIA   -     D0100PA00X+021895Y+031262               S3      
327GND              C37   -2          A10X+021245Y+032704X0180Y0200R270 S1      
327GND              C38   -2          A10X+022045Y+032354X0180Y0200R270 S1      
327P1V8_NODE1       C38   -1          A10X+022045Y+032669X0180Y0200R270 S1      
327GND              C57   -2          A10X+021957Y+031962X0180Y0200R180 S1      
327P1V05_NODE1      C57   -1          A10X+022272Y+031962X0180Y0200R180 S1      
327GND              C48   -2          A10X+021957Y+031562X0180Y0200R180 S1      
327P1V05_NODE1      C48   -1          A10X+022272Y+031562X0180Y0200R180 S1      
327P1V05_NODE1      C46   -1          A10X+022787Y+031662X0180Y0200     S1      
327GND              U2    -T28        A01X+021732Y+032008X0120Y0120     S2      
327GND              U2    -T31        A01X+022362Y+032008X0120Y0120     S2      
327GND              U2    -T29        A01X+022008Y+032008X0120Y0120     S2      
327GND              U2    -M29        A01X+021868Y+032865X0120Y0120     S2      
327GND              U2    -M30        A01X+022144Y+032865X0120Y0120     S2      
327GND              U2    -P30        A01X+022144Y+032565X0120Y0120     S2      
327GND              U2    -P29        A01X+021868Y+032565X0120Y0120     S2      
327GND              U2    -R29        A01X+021868Y+032265X0120Y0120     S2      
327GND              U2    -R30        A01X+022144Y+032265X0120Y0120     S2      
327GND              U2    -T26        A01X+021362Y+032115X0120Y0120     S2      
327N/C              U2    -N26        A01X+021362Y+032715X0120Y0120     S2      
327GND              U2    -P26        A01X+021362Y+032415X0120Y0120     S2      
327GND              U2    -V31        A01X+022362Y+031732X0150Y0150     S2      
327GND              U2    -W31        A01X+022362Y+031417X0150Y0150     S2      
327GND              U2    -V29        A01X+022047Y+031732X0150Y0150     S2      
327GND              U2    -W29        A01X+022047Y+031417X0150Y0150     S2      
327GND              U2    -V28        A01X+021732Y+031732X0150Y0150     S2      
327GND              U2    -W28        A01X+021732Y+031417X0150Y0150     S2      
327GND              U2    -V26        A01X+021417Y+031732X0150Y0150     S2      
327GND              U2    -W26        A01X+021417Y+031417X0150Y0150     S2      
327P1V8_NODE1       U2    -T32        A01X+022650Y+032115X0120Y0120     S2      
327P1V8_NODE1       U2    -P32        A01X+022650Y+032415X0120Y0120     S2      
327P1V8_NODE1       U2    -N32        A01X+022650Y+032715X0120Y0120     S2      
327P1V05_NODE1      U2    -W32        A01X+022677Y+031417X0150Y0150     S2      
327P1V8_NODE1       U2    -V32        A01X+022677Y+031732X0150Y0150     S2      
317GND              VIA   -     D0100PA00X+021510Y+032270               S3      
317GND              VIA   -     D0100PA00X+021713Y+032721               S3      
317GND              VIA   -     D0100PA00X+021509Y+032565               S3      
317GND              VIA   -     D0100PA00X+021260Y+031910               S3      
317GND              VIA   -     D0100PA00X+021713Y+032421               S3      
317P1V8_NODE1       VIA   -     D0100PA00X+022495Y+032871               S3      
317P1V8_NODE1       VIA   -     D0100PA00X+022520Y+031575               S3      
317P1V8_NODE1       VIA   -     D0100PA00X+022459Y+032299               S3      
317P1V8_NODE1       VIA   -     D0100PA00X+022471Y+032592               S3      
327P1V8_NODE1       C37   -1          A10X+021245Y+033019X0180Y0200R270 S1      
327P1V8_NODE1       C91   -1          A10X+021445Y+034372X0280Y0320     S1      
327GND              R100  -2          A10X+022777Y+033632X0180Y0200R090 S1      
327NNAME10343       R100  -1          A10X+022777Y+033317X0180Y0200R090 S1      
327NNAME10309       U2    -E31        A01X+022317Y+034178X0120Y0120     S2      
327GND              U2    -E27        A01X+021501Y+034205X0120Y0120     S2      
327GND              U2    -E25        A01X+021223Y+034198X0120Y0120     S2      
327GND              U2    -J29        A01X+021868Y+033465X0120Y0120     S2      
327GND              U2    -L29        A01X+021868Y+033165X0120Y0120     S2      
327NNAME10304       U2    -J30        A01X+022144Y+033465X0120Y0120     S2      
327GND              U2    -L30        A01X+022144Y+033165X0120Y0120     S2      
327NNAME10344       U2    -H30        A01X+022144Y+033765X0120Y0120     S2      
327GND              U2    -H29        A01X+021868Y+033765X0120Y0120     S2      
327N/C              U2    -H26        A01X+021362Y+033615X0120Y0120     S2      
327GND              U2    -K26        A01X+021362Y+033315X0120Y0120     S2      
327N/C              U2    -L26        A01X+021362Y+033015X0120Y0120     S2      
327N/C              U2    -G26        A01X+021362Y+033915X0120Y0120     S2      
327NNAME10106       U2    -D26        A01X+021285Y+034486X0120Y0120     S2      
327NNAME10345       U2    -E28        A01X+021774Y+034254X0120Y0120     S2      
327GND              U2    -E30        A01X+022050Y+034254X0120Y0120     S2      
327GND              U2    -E32        A01X+022593Y+034198X0120Y0120     S2      
327P1V8_NODE1       U2    -L32        A01X+022650Y+033015X0120Y0120     S2      
327GND              U2    -K32        A01X+022650Y+033315X0120Y0120     S2      
327NNAME10346       U2    -H32        A01X+022650Y+033615X0120Y0120     S2      
327NNAME10306       U2    -G32        A01X+022650Y+033915X0120Y0120     S2      
327GND              U2    -D32        A01X+022527Y+034469X0120Y0120     S2      
317GND              VIA   -     D0100PA00X+021713Y+033621               S3      
317GND              VIA   -     D0100PA00X+021707Y+033954               S3      
317GND              VIA   -     D0100PA00X+021713Y+033321               S3      
317GND              VIA   -     D0100PA00X+022301Y+034424               S3      
317NNAME10344       VIA   -     D0100PA00X+022317Y+033884               S3      
317NNAME10304       VIA   -     D0100PA00X+022291Y+033316               S3      
317NNAME10346       VIA   -     D0100PA00X+022500Y+033462               S3      
317NNAME10306       VIA   -     D0100PA00X+022310Y+033624               S3      
317NNAME10309       VIA   -     D0100PA00X+022128Y+034058               S3      
327GND              C91   -2          A10X+021445Y+034952X0280Y0320     S1      
327GND              U2    -A30        A01X+022228Y+035059X0100Y0135     S2      
327GND              U2    -A27        A01X+021588Y+035059X0100Y0135     S2      
327NNAME10347       U2    -B30        A01X+022090Y+034819X0120Y0120     S2      
327NNAME10106       U2    -B26        A01X+021305Y+034863X0120Y0120     S2      
327NNAME10348       U2    -B28        A01X+021725Y+034818X0120Y0120     S2      
327GND              U2    -B32        A01X+022495Y+034884X0120Y0120     S2      
327NNAME10305       U2    -D28        A01X+021738Y+034528X0120Y0120     S2      
327NNAME10349       U2    -D30        A01X+022088Y+034528X0120Y0120     S2      
327NNAME10350       U2    -C31        A01X+022329Y+034664X0120Y0120     S2      
327GND              U2    -C27        A01X+021497Y+034662X0120Y0120     S2      
317GND              VIA   -     D0100PA00X+022806Y+035284               S3      
317GND              VIA   -     D0100PA00X+022278Y+035307               S3      
317GND              VIA   -     D0100PA00X+021489Y+035291               S3      
317NNAME10344       VIA   -     D0100PA00X+022297Y+035613               S3      
317NNAME10348       VIA   -     D0100PA00X+021466Y+035621               S1      
327NNAME10346       VIA   -           A10X+022383Y+035903X0260Y0260     S1      
327NNAME10309       VIA   -           A10X+022128Y+035026X0260Y0260     S1      
317NNAME10345       VIA   -     D0100PA00X+021401Y+036270               S1      
327NNAME10347       VIA   -           A01X+022177Y+037378X0300Y0300     S2      
327NNAME10351       VIA   -           A10X+021669Y+037443X0260Y0260     S1      
317NNAME10350       VIA   -     D0100PA00X+022223Y+036403               S1      
317NNAME10352       VIA   -     D0100PA00X+022775Y+036801               S1      
327NNAME10353       VIA   -           A10X+022069Y+037086X0260Y0260     S1      
327NNAME10354       VIA   -           A10X+022476Y+037413X0260Y0260     S1      
327NNAME10349       VIA   -           A01X+021782Y+036867X0300Y0300     S2      
327GND              R54   -2          A10X+022069Y+038227X0180Y0200R090 S1      
327NNAME10353       R54   -1          A10X+022069Y+037912X0180Y0200R090 S1      
327P1V8_NODE1       R53   -2          A10X+021669Y+038227X0180Y0200R090 S1      
327NNAME10351       R53   -1          A10X+021669Y+037912X0180Y0200R090 S1      
327NNAME10348       R83   -2          A01X+021273Y+037917X0180Y0200R090 S2      
327GND              R83   -1          A01X+021273Y+038232X0180Y0200R090 S2      
327NNAME10346       R81   -2          A10X+021269Y+037912X0180Y0200R270 S1      
327GND              R81   -1          A10X+021269Y+038227X0180Y0200R270 S1      
327NNAME10345       R80   -2          A01X+021673Y+037917X0180Y0200R090 S2      
327GND              R80   -1          A01X+021673Y+038232X0180Y0200R090 S2      
327NNAME10349       R497  -2          A01X+022073Y+037917X0180Y0200R090 S2      
327GND              R497  -1          A01X+022073Y+038232X0180Y0200R090 S2      
327NNAME10347       R82   -2          A01X+022473Y+037917X0180Y0200R090 S2      
327GND              R82   -1          A01X+022473Y+038232X0180Y0200R090 S2      
327P3V3_NODE1       R140  -2          A10X+022469Y+038227X0180Y0200R090 S1      
327NNAME10354       R140  -1          A10X+022469Y+037912X0180Y0200R090 S1      
317GND              VIA   -     D0100PA00X+022356Y+038511               S3      
317GND              VIA   -     D0100PA00X+021401Y+038517               S3      
317GND              VIA   -     D0100PA00X+022144Y+039066               S3      
317P3V3_NODE1       VIA   -     D0100PA00X+022411Y+038803               S3      
317NNAME10308       VIA   -     D0100PA00X+021479Y+038860               S1      
317NNAME10307       VIA   -     D0100PA00X+021809Y+039089               S1      
317P1V8_NODE1       VIA   -     D0100PA00X+021663Y+038499               S3      
327NNAME10313       R196  -2          A01X+022123Y+039669X0180Y0200R270 S2      
327P3V3_NODE1       R196  -1          A01X+022123Y+039354X0180Y0200R270 S2      
327NNAME10312       R197  -2          A01X+022523Y+039669X0180Y0200R270 S2      
327P3V3_NODE1       R197  -1          A01X+022523Y+039354X0180Y0200R270 S2      
317NNAME10310       VIA   -     D0100PA00X+021512Y+039965               S1      
317NNAME10311       VIA   -     D0100PA00X+021441Y+039554               S1      
317NNAME10312       VIA   -     D0100PA00X+022309Y+040170               S1      
317P1V8_NODE1       VIA   -     D0100PA00X+021371Y+040224               S3      
327P3V3_STB_NODE1   PL2   -2          A01X+022285Y+042778X0848Y1300     S2      
317P3V3_STB_NODE1   VIA   -     D0100PA00X+022473Y+041800               S3      
317P3V3_STB_NODE1   VIA   -     D0100PA00X+022141Y+043656               S3      
317P3V3_STB_NODE1   VIA   -     D0100PA00X+022782Y+044268               S3      
317P3V3_STB_NODE1   VIA   -     D0100PA00X+021848Y+044255               S3      
317P3V3_STB_NODE1   VIA   -     D0100PA00X+022186Y+044230               S3      
317P3V3_STB_NODE1   VIA   -     D0100PA00X+022502Y+044247               S3      
327BMC_ROMD4        R344  -2          A01X+022395Y+046997X0180Y0200R270 S2      
327P3V3_NODE1       R344  -1          A01X+022395Y+046682X0180Y0200R270 S2      
327NNAME10355       OSC3  -3          A01X+021804Y+046940X0480Y0560R090 S2      
327GND              OSC3  -2          A01X+021804Y+046271X0480Y0560R090 S2      
317GND              VIA   -     D0100PA00X+022628Y+046070               S3      
317GND              VIA   -     D0100PA00X+021399Y+046605               S3      
317P3V3_NODE1       VIA   -     D0100PA00X+022824Y+046368               S3      
317P3V3_NODE1       VIA   -     D0100PA00X+022395Y+046355               S3      
327GND              C297  -2          A10X+021271Y+048643X0180Y0200R090 S1      
327NNAME10316       C297  -1          A10X+021271Y+048328X0180Y0200R090 S1      
327GND              C295  -2          A10X+021671Y+048643X0180Y0200R090 S1      
327NNAME10316       C295  -1          A10X+021671Y+048328X0180Y0200R090 S1      
327P3V3_NODE1       L13   -2          A01X+021401Y+047615X0280Y0320R270 S2      
327NNAME10356       L16   -1          A10X+022773Y+048616X0280Y0320R090 S1      
327P3V3_NODE1       L16   -2          A10X+022193Y+048616X0280Y0320R090 S1      
327NNAME10357       R312  -2          A01X+021964Y+047931X0180Y0200R270 S2      
327NNAME10355       R312  -1          A01X+021964Y+047616X0180Y0200R270 S2      
317P3V3_NODE1       VIA   -     D0100PA00X+021281Y+047905               S3      
317P3V3_NODE1       VIA   -     D0100PA00X+021541Y+047925               S3      
317NNAME10357       VIA   -     D0100PA00X+022242Y+047993               S1      
317NNAME10355       VIA   -     D0100PA00X+021804Y+047385               S1      
317PECIVDD          VIA   -     D0100PA00X+022379Y+047664               S3      
317BMC_ROMD4        VIA   -     D0100PA00X+022626Y+047258               S1      
327NNAME10357       U14   -AB22       A01X+022576Y+049787X0145Y0145R270 S2      
327N/C              U14   -AB21       A01X+022576Y+050102X0145Y0145R270 S2      
327GND              C265  -2          A10X+021713Y+050285X0180Y0200R180 S1      
327NNAME10358       C265  -1          A10X+022028Y+050285X0180Y0200R180 S1      
327NNAME10358       L15   -1          A10X+021871Y+049825X0280Y0320R180 S1      
327P3V3_NODE1       L15   -2          A10X+021871Y+049245X0280Y0320R180 S1      
327GND              R294  -2          A10X+022419Y+049810X0180Y0200R180 S1      
327NNAME10359       R294  -1          A10X+022734Y+049810X0180Y0200R180 S1      
317GND              VIA   -     D0100PA00X+021621Y+048885               S3      
317GND              VIA   -     D0100PA00X+021321Y+048885               S3      
317GND              VIA   -     D0100PA00X+022421Y+049493               S3      
317P3V3_NODE1       VIA   -     D0100PA00X+021931Y+048935               S3      
317P3V3_NODE1       VIA   -     D0100PA00X+022221Y+048935               S3      
317NNAME10359       VIA   -     D0100PA00X+022728Y+050259               S1      
327NNAME10358       VIA   -           A10X+021321Y+049835X0260Y0260R090 S1      
317NNAME10356       VIA   -     D0100PA00X+022421Y+049185               S1      
327N/C              U14   -AB20       A01X+022576Y+050417X0145Y0145R270 S2      
327NNAME10358       U14   -AB19       A01X+022576Y+050732X0145Y0145R270 S2      
327NNAME10143       U14   -AB18       A01X+022576Y+051047X0145Y0145R270 S2      
327NNAME10211       U14   -AB17       A01X+022576Y+051362X0145Y0145R270 S2      
327NNAME10210       U14   -AB16       A01X+022576Y+051677X0145Y0145R270 S2      
327GND              C266  -2          A10X+021713Y+050685X0180Y0200R180 S1      
327NNAME10358       C266  -1          A10X+022028Y+050685X0180Y0200R180 S1      
327GND              C267  -2          A10X+021713Y+051085X0180Y0200R180 S1      
327NNAME10358       C267  -1          A10X+022028Y+051085X0180Y0200R180 S1      
327GND              C288  -2          A10X+022453Y+051187X0180Y0200R180 S1      
327NNAME10317       C288  -1          A10X+022768Y+051187X0180Y0200R180 S1      
327NNAME10360       R257  -2          A10X+022778Y+051585X0180Y0200     S1      
327GND              R257  -1          A10X+022463Y+051585X0180Y0200     S1      
317GND              VIA   -     D0100PA00X+021463Y+051649               S3      
317GND              VIA   -     D0100PA00X+022733Y+050574               S3      
317GND              VIA   -     D0100PA00X+022733Y+050889               S3      
317NNAME10214       VIA   -     D0100PA00X+021761Y+051635               S1      
317NNAME10358       VIA   -     D0100PA00X+022371Y+050535               S3      
327NNAME10214       U14   -AB15       A01X+022576Y+051992X0145Y0145R270 S2      
327NNAME10146       U14   -AB14       A01X+022576Y+052307X0145Y0145R270 S2      
327NNAME10153       U14   -AB13       A01X+022576Y+052622X0145Y0145R270 S2      
327NNAME10222       U14   -AB12       A01X+022576Y+052937X0145Y0145R270 S2      
327NNAME10225       U14   -AB11       A01X+022576Y+053252X0145Y0145R270 S2      
327NNAME10109       C204  -1          A10X+021457Y+052147X0180Y0200R180 S1      
327NNAME10109       C205  -2          A10X+021887Y+052109X0180Y0200R270 S1      
327GND              C205  -1          A10X+021887Y+052424X0180Y0200R270 S1      
317GND              VIA   -     D0100PA00X+021656Y+052890               S3      
317NNAME10153       VIA   -     D0100PA00X+021933Y+052882               S1      
327NNAME10109       VIA   -           A10X+022691Y+052805X0260Y0260R090 S1      
317NNAME10146       VIA   -     D0100PA00X+022338Y+052332               S1      
317NNAME10221       VIA   -     D0100PA00X+021412Y+052858               S3      
327NNAME10063       VIA   -           A10X+022509Y+053436X0260Y0260R090 S1      
327NNAME10160       U14   -AB10       A01X+022576Y+053567X0145Y0145R270 S2      
327NNAME10231       U14   -AB9        A01X+022576Y+053882X0145Y0145R270 S2      
327NNAME10232       U14   -AB8        A01X+022576Y+054197X0145Y0145R270 S2      
327N/C              U14   -AB7        A01X+022576Y+054512X0145Y0145R270 S2      
327N/C              U14   -AB6        A01X+022576Y+054827X0145Y0145R270 S2      
327NNAME10063       C271  -1          A10X+022503Y+054105X0280Y0320     S1      
327GND              C271  -2          A10X+022503Y+054685X0280Y0320     S1      
317NNAME10233       VIA   -     D0100PA00X+021875Y+054384               S3      
317NNAME10231       VIA   -     D0100PA00X+021595Y+054420               S1      
327N/C              U14   -AB5        A01X+022576Y+055142X0145Y0145R270 S2      
327N/C              U14   -AB4        A01X+022576Y+055457X0145Y0145R270 S2      
327N/C              U14   -AB3        A01X+022576Y+055772X0145Y0145R270 S2      
327N/C              U14   -AB2        A01X+022576Y+056086X0145Y0145R270 S2      
327N/C              U14   -AB1        A01X+022576Y+056401X0145Y0145R270 S2      
317GND              VIA   -     D0100PA00X+022159Y+056337               S3      
317GND              VIA   -     D0100PA00X+022356Y+056148               S3      
317NNAME10046       VIA   -     D0100PA00X+021895Y+056559               S1      
327NNAME10045       R675  -2          A10X+021969Y+057423X0180Y0200R180 S1      
327NNAME10361       R675  -1          A10X+022284Y+057423X0180Y0200R180 S1      
327NNAME10046       R670  -2          A10X+021969Y+057012X0180Y0200R180 S1      
327NNAME10362       R670  -1          A10X+022284Y+057012X0180Y0200R180 S1      
317GND              VIA   -     D0100PA00X+022345Y+057809               S3      
317GND              VIA   -     D0100PA00X+021659Y+057085               S3      
317GND              VIA   -     D0100PA00X+022043Y+058027               S3      
317NNAME10363       VIA   -     D0100PA00X+022710Y+058092               S1      
327NNAME10362       VIA   -           A10X+022784Y+056691X0260Y0260     S1      
327NNAME10275       C392  -2          A01X+021238Y+059696X0180Y0200     S2      
327NNAME10188       C392  -1          A01X+021553Y+059696X0180Y0200     S2      
327GND              R315  -1          A01X+022043Y+058382X0280Y0320R270 S2      
327NNAME10363       R315  -2          A01X+022623Y+058382X0280Y0320R270 S2      
317GND              VIA   -     D0100PA00X+021886Y+059309               S3      
317NNAME10318       VIA   -     D0100PA00X+022510Y+059745               S3      
317NNAME10188       VIA   -     D0100PA00X+021996Y+059637               S1      
327NNAME10318       U36   -1          A01X+022427Y+060263X0220Y0680     S2      
327NNAME10274       C391  -2          A01X+021238Y+060096X0180Y0200     S2      
327NNAME10189       C391  -1          A01X+021553Y+060096X0180Y0200     S2      
317GND              VIA   -     D0100PA00X+021930Y+060481               S3      
317NNAME10189       VIA   -     D0100PA00X+021996Y+060137               S1      
327P3V3_NODE1       U36   -8          A01X+022427Y+062343X0220Y0680     S2      
327P3V3_NODE1       R596  -1          A01X+021245Y+062198X0180Y0200     S2      
327GND              R558  -1          A01X+021245Y+062598X0180Y0200     S2      
317GND              VIA   -     D0100PA00X+021570Y+062598               S1      
317P3V3_NODE1       VIA   -     D0100PA00X+021560Y+062198               S3      
327GND              C517  -2          A01X+021245Y+062998X0180Y0200R180 S2      
327GND              C519  -2          A01X+021245Y+063798X0180Y0200R180 S2      
327GND              C518  -2          A01X+021245Y+063398X0180Y0200R180 S2      
327GND              C390  -2          A01X+022113Y+063909X0180Y0200R270 S2      
327P3V3_NODE1       C390  -1          A01X+022113Y+063594X0180Y0200R270 S2      
327P3V3_NODE1       R553  -2          A01X+022518Y+063909X0180Y0200R270 S2      
327NNAME10364       R553  -1          A01X+022518Y+063594X0180Y0200R270 S2      
317GND              VIA   -     D0100PA00X+021599Y+063398               S3      
317GND              VIA   -     D0100PA00X+021611Y+063798               S1      
317GND              VIA   -     D0100PA00X+021595Y+062998               S3      
317GND              VIA   -     D0100PA00X+022113Y+064236               S3      
317NNAME10364       VIA   -     D0100PA00X+022829Y+062989               S1      
317P3V3_NODE1       VIA   -     D0100PA00X+021831Y+063594               S3      
317P3V3_NODE1       VIA   -     D0100PA00X+022518Y+064261               S3      
327GND              C620  -2          A01X+021923Y+067177X0180Y0200     S2      
327P3V3_NODE1       C620  -1          A01X+022238Y+067177X0180Y0200     S2      
317GND              VIA   -     D0100PA00X+021577Y+067199               S3      
317PSU3_DC_OK       VIA   -     D0100PA00X+021824Y+067443               S1      
317P3V3_NODE1       VIA   -     D0100PA00X+022524Y+067177               S3      
317TACKOVER_EN      VIA   -     D0100PA00X+021264Y+066560               S3      
327GND              U63   -12         A10X+022894Y+068008X0140Y0590R090 S1      
327PSU2_DC_OK       U63   -11         A10X+022894Y+068264X0140Y0590R090 S1      
327PSU1_DC_OK       U63   -10         A10X+022894Y+068520X0140Y0590R090 S1      
327PSU6_AC_OK       U63   -9          A10X+022894Y+068776X0140Y0590R090 S1      
327PSU5_AC_OK       U63   -8          A10X+022894Y+069032X0140Y0590R090 S1      
327GND              U86   -3          A01X+022699Y+068800X0180Y0520R180 S2      
327PSU3_DC_OK       U86   -4          A01X+022699Y+067836X0180Y0520R180 S2      
327N/C              U89   -1          A01X+022085Y+068800X0180Y0520R180 S2      
327NNAME10280       U89   -2          A01X+021711Y+068800X0180Y0520R180 S2      
327GND              U89   -3          A01X+021337Y+068800X0180Y0520R180 S2      
327PSU4_DC_OK       U89   -4          A01X+021337Y+067836X0180Y0520R180 S2      
327P3V3_NODE1       U89   -5          A01X+022085Y+067836X0180Y0520R180 S2      
317GND              VIA   -     D0100PA00X+022429Y+068008               S3      
317GND              VIA   -     D0100PA00X+022436Y+068437               S3      
317GND              VIA   -     D0100PA00X+021337Y+069215               S3      
317PSU5_AC_OK       VIA   -     D0100PA00X+022406Y+069032               S3      
317PSU6_AC_OK       VIA   -     D0100PA00X+022434Y+068776               S3      
327PSU4_AC_OK       U63   -7          A10X+022894Y+069288X0140Y0590R090 S1      
327PSU3_AC_OK       U63   -6          A10X+022894Y+069544X0140Y0590R090 S1      
327PSU2_AC_OK       U63   -5          A10X+022894Y+069800X0140Y0590R090 S1      
327PSU1_AC_OK       U63   -4          A10X+022894Y+070055X0140Y0590R090 S1      
327N21700864        U63   -3          A10X+022894Y+070311X0140Y0590R090 S1      
327N21699710        U63   -2          A10X+022894Y+070567X0140Y0590R090 S1      
327PSU_DC_OK_N      U98   -D          A01X+021544Y+069956X0400Y0500R180 S2      
327NNAME10280       U98   -G          A01X+021944Y+070836X0400Y0500R180 S2      
327GND              U95   -S          A01X+022594Y+070836X0400Y0500R180 S2      
317PSU3_AC_OK       VIA   -     D0100PA00X+022371Y+069544               S3      
317PSU4_AC_OK       VIA   -     D0100PA00X+022058Y+069288               S3      
317PSU1_AC_OK       VIA   -     D0100PA00X+022374Y+070055               S3      
317PSU2_AC_OK       VIA   -     D0100PA00X+022134Y+069800               S3      
327PCA9535_INT_N    U63   -1          A10X+022894Y+070823X0140Y0590R090 S1      
317GND              VIA   -     D0100PA00X+022661Y+071348               S3      
317PSU_ALERT_N      VIA   -     D0100PA00X+021753Y+071531               S1      
317I2C_PSU1_SCL     VIA   -     D0100PA00X+022132Y+072070               S1      
317I2C_PSU1_SDA     VIA   -     D0100PA00X+021331Y+071906               S1      
317NNAME10280       VIA   -     D0100PA00X+022271Y+071371               S1      
317NNAME10365       VIA   -     D0100PA00X+021682Y+072330               S1      
317NNAME10366       VIA   -     D0100PA00X+022765Y+072079               S3      
317NNAME10367       VIA   -     D0100PA00X+022441Y+071997               S3      
327GND              C688  -2          A10X+022594Y+072758X0180Y0200R270 S1      
327NNAME10368       C688  -1          A10X+022594Y+073073X0180Y0200R270 S1      
327GND              C673  -2          A10X+021244Y+073908X0180Y0200R270 S1      
327GND              C691  -2          A10X+022144Y+073908X0180Y0200R270 S1      
327GND              C715  -2          A01X+022144Y+073908X0180Y0200R090 S2      
327GND              C670  -2          A10X+021694Y+073073X0180Y0200R090 S1      
327NNAME10365       C670  -1          A10X+021694Y+072758X0180Y0200R090 S1      
327GND              C712  -2          A01X+022594Y+072758X0180Y0200R090 S2      
327NNAME10369       C712  -1          A01X+022594Y+073073X0180Y0200R090 S2      
327GND              C587  -2          A01X+021244Y+073908X0180Y0200R090 S2      
327GND              C589  -2          A01X+021694Y+073908X0180Y0200R090 S2      
327I2C_PSU1_R_SDA   R818  -2          A01X+021244Y+073073X0180Y0200R270 S2      
327I2C_PSU1_SDA     R818  -1          A01X+021244Y+072758X0180Y0200R270 S2      
327NNAME10368       R925  -1          A10X+022594Y+073908X0180Y0200R090 S1      
327NNAME10365       R907  -1          A10X+021694Y+073908X0180Y0200R090 S1      
327NNAME10369       R949  -1          A01X+022594Y+073908X0180Y0200R270 S2      
327NNAME10325       R910  -2          A10X+021244Y+073073X0180Y0200R090 S1      
327NNAME10370       R910  -1          A10X+021244Y+072758X0180Y0200R090 S1      
327NNAME10326       R928  -2          A10X+022144Y+073073X0180Y0200R090 S1      
327NNAME10366       R928  -1          A10X+022144Y+072758X0180Y0200R090 S1      
327NNAME10371       R952  -2          A01X+022144Y+073073X0180Y0200R270 S2      
327NNAME10367       R952  -1          A01X+022144Y+072758X0180Y0200R270 S2      
327I2C_PSU1_R_SCL   R820  -2          A01X+021694Y+073073X0180Y0200R270 S2      
327I2C_PSU1_SCL     R820  -1          A01X+021694Y+072758X0180Y0200R270 S2      
317GND              VIA   -     D0100PA00X+021694Y+073606               S3      
317GND              VIA   -     D0100PA00X+022144Y+073593               S3      
317GND              VIA   -     D0100PA00X+022594Y+072406               S3      
317NNAME10368       VIA   -     D0100PA00X+022594Y+073367               S3      
317NNAME10369       VIA   -     D0100PA00X+022594Y+073644               S3      
327NNAME10325       C673  -1          A10X+021244Y+074223X0180Y0200R270 S1      
327NNAME10326       C691  -1          A10X+022144Y+074223X0180Y0200R270 S1      
327NNAME10371       C715  -1          A01X+022144Y+074223X0180Y0200R090 S2      
327I2C_PSU1_R_SDA   C587  -1          A01X+021244Y+074223X0180Y0200R090 S2      
327I2C_PSU1_R_SCL   C589  -1          A01X+021694Y+074223X0180Y0200R090 S2      
327NNAME10372       R925  -2          A10X+022594Y+074223X0180Y0200R090 S1      
327NNAME10324       R907  -2          A10X+021694Y+074223X0180Y0200R090 S1      
327NNAME10373       R949  -2          A01X+022594Y+074223X0180Y0200R270 S2      
327NNAME10372       VIA   -           A10X+021952Y+077082X0260Y0260     S1      
327NNAME10326       VIA   -           A10X+021416Y+077963X0260Y0260     S1      
327NNAME10374       VIA   -           A10X+022625Y+078592X0260Y0260     S1      
317NNAME10371       VIA   -     D0100PA00X+021827Y+078566               S1      
317NNAME10373       VIA   -     D0100PA00X+022096Y+077856               S1      
317NNAME10375       VIA   -     D0100PA00X+022667Y+077330               S1      
327NNAME10372       J35   -A40        A10X+021659Y+080787X0300Y1660R180 S1      
327GND              J35   -A39        A10X+022053Y+080787X0300Y1660R180 S1      
327NNAME10374       J35   -A38        A10X+022447Y+080787X0300Y1660R180 S1      
327NNAME10376       J35   -A37        A10X+022841Y+080787X0300Y1660R180 S1      
327NNAME10371       J35   -B40        A01X+021659Y+080787X0300Y1660R180 S2      
327NNAME10373       J35   -B39        A01X+022053Y+080787X0300Y1660R180 S2      
327NNAME10375       J35   -B38        A01X+022447Y+080787X0300Y1660R180 S2      
327NNAME10377       J35   -B37        A01X+022841Y+080787X0300Y1660R180 S2      
317GND              VIA   -     D0100PA00X+022053Y+078870               S3      
317GND              VIA   -     D0100PA00X+022053Y+079170               S3      
317GND              VIA   -     D0100PA00X+021266Y+079170               S3      
317GND              VIA   -     D0100PA00X+021266Y+078870               S3      
327GND              PC79  -2          A01X+024515Y+001389X0950Y1110R270 S2      
317GND              VIA   -     D0100PA00X+024199Y+002122               S3      
317GND              VIA   -     D0100PA00X+022999Y+002122               S3      
327PV_VDDR_NODE1    PC79  -1          A01X+024515Y+003908X0950Y1110R270 S2      
317PV_VDDR_NODE1    VIA   -     D0100PA00X+024229Y+004550               S3      
317PV_VDDR_NODE1    VIA   -     D0100PA00X+023029Y+004550               S3      
327GND              PC84  -2          A01X+023131Y+006244X0440Y0540R270 S2      
327PV_VDDR_NODE1    PC84  -1          A01X+023131Y+005496X0440Y0540R270 S2      
327GND              PC82  -2          A01X+023931Y+006244X0440Y0540R270 S2      
327PV_VDDR_NODE1    PC82  -1          A01X+023931Y+005496X0440Y0540R270 S2      
317PV_VDDR_NODE1    VIA   -     D0100PA00X+022931Y+005110               S3      
317PV_VDDR_NODE1    VIA   -     D0100PA00X+023329Y+005105               S3      
317PV_VDDR_NODE1    VIA   -     D0100PA00X+023731Y+005098               S3      
317PV_VDDR_NODE1    VIA   -     D0100PA00X+024131Y+005098               S3      
317GND              VIA   -     D0100PA00X+023760Y+006632               S3      
317GND              VIA   -     D0100PA00X+024160Y+006632               S3      
317GND              VIA   -     D0100PA00X+022960Y+006632               S3      
317GND              VIA   -     D0100PA00X+023360Y+006632               S3      
327NNAME10378       J2    -71         A01X+024154Y+008248X0150Y0810     S2      
327NNAME10379       J2    -69         A01X+023917Y+008248X0150Y0810     S2      
327GND              J2    -67         A01X+023681Y+008248X0150Y0810     S2      
327NNAME10337       J2    -65         A01X+023445Y+008248X0150Y0810     S2      
327NNAME10287       J2    -63         A01X+023209Y+008248X0150Y0810     S2      
327GND              J2    -61         A01X+022973Y+008248X0150Y0810     S2      
317GND              VIA   -     D0100PA00X+023636Y+009393               S3      
317GND              VIA   -     D0100PA00X+023681Y+008870               S3      
317GND              VIA   -     D0100PA00X+022973Y+008872               S3      
317NNAME10337       VIA   -     D0100PA00X+023511Y+009131               S3      
317NNAME10287       VIA   -     D0100PA00X+023101Y+009155               S3      
317NNAME10378       VIA   -     D0100PA00X+024337Y+008877               S1      
317NNAME10379       VIA   -     D0100PA00X+023956Y+009208               S1      
317GND              VIA   -     D0100PA00X+024373Y+010306               S3      
317GND              VIA   -     D0100PA00X+024036Y+010876               S3      
317GND              VIA   -     D0100PA00X+023950Y+010093               S3      
317GND              VIA   -     D0100PA00X+023191Y+010573               S3      
317GND              VIA   -     D0100PA00X+023519Y+009691               S3      
317NNAME10288       VIA   -     D0100PA00X+023064Y+010850               S3      
317NNAME10331       VIA   -     D0100PA00X+023424Y+010016               S3      
317NNAME10327       VIA   -     D0100PA00X+023308Y+009482               S1      
317NNAME10289       VIA   -     D0100PA00X+023777Y+010361               S3      
317NNAME10380       VIA   -     D0100PA00X+024291Y+010616               S1      
327NNAME10380       J2    -72         A01X+024272Y+011476X0150Y0810     S2      
327GND              J2    -70         A01X+024036Y+011476X0150Y0810     S2      
327NNAME10289       J2    -68         A01X+023799Y+011476X0150Y0810     S2      
327NNAME10288       J2    -66         A01X+023563Y+011476X0150Y0810     S2      
327GND              J2    -64         A01X+023327Y+011476X0150Y0810     S2      
327NNAME10293       J2    -62         A01X+023091Y+011476X0150Y0810     S2      
327NNAME10290       J2    -60         A01X+022854Y+011476X0150Y0810     S2      
317GND              VIA   -     D0100PA00X+023327Y+012174               S3      
317NNAME10293       VIA   -     D0100PA00X+023314Y+012580               S1      
317PV_VDDR_NODE1    VIA   -     D0100PA00X+023075Y+016081               S3      
317PV_VDDR_NODE1    VIA   -     D0100PA00X+023065Y+016457               S3      
317PV_VDDR_NODE1    VIA   -     D0100PA00X+023089Y+016942               S3      
317PV_VDDR_NODE1    VIA   -     D0100PA00X+023100Y+017338               S3      
317PV_VDDR_NODE1    VIA   -     D0100PA00X+023010Y+018739               S3      
317PV_VDDR_NODE1    VIA   -     D0100PA00X+023014Y+019724               S3      
327NNAME10381       R33   -2          A10X+023000Y+021690X0180Y0200     S1      
327NNAME10381       R32   -2          A10X+023000Y+022090X0180Y0200     S1      
317NNAME10382       VIA   -     D0100PA00X+023295Y+023405               S1      
327NNAME10332       VIA   -           A10X+022813Y+022583X0200Y0040R270 S1      
327NNAME10383       R35   -1          A10X+024206Y+024223X0180Y0200     S1      
327NNAME10383       R34   -1          A10X+024206Y+024623X0180Y0200     S1      
327PV_VDDR_NODE1    U2    -BM36       A01X+023341Y+025021X0120Y0120     S2      
327PV_VDDR_NODE1    U2    -BM40       A01X+024173Y+025022X0120Y0120     S2      
327NNAME10384       U2    -BM34       A01X+022856Y+024998X0120Y0120     S2      
327NNAME10385       U2    -BP37       A01X+023442Y+024626X0100Y0135     S2      
327NNAME10386       U2    -BP40       A01X+024082Y+024626X0100Y0135     S2      
327NNAME10387       U2    -BN37       A01X+023580Y+024866X0120Y0120     S2      
327NNAME10388       U2    -BN39       A01X+023944Y+024866X0120Y0120     S2      
327NNAME10382       U2    -BN35       A01X+023175Y+024801X0120Y0120     S2      
327PV_VDDR_NODE1    U2    -BP34       A01X+022876Y+024626X0100Y0135     S2      
317NNAME10387       VIA   -     D0100PA00X+023671Y+024404               S1      
317NNAME10389       VIA   -     D0100PA00X+024246Y+023759               S1      
317NNAME10390       VIA   -     D0100PA00X+023765Y+024972               S1      
317NNAME10332       VIA   -     D0100PA00X+023171Y+024364               S3      
317NNAME10381       VIA   -     D0100PA00X+023171Y+024024               S1      
327NNAME10334       VIA   -           A10X+023032Y+024943X0260Y0260R180 S1      
327PV_VDDR_NODE1    R1044 -2          A10X+022875Y+026572X0180Y0200R090 S1      
327NNAME10341       R1044 -1          A10X+022875Y+026257X0180Y0200R090 S1      
327NNAME10390       U2    -BL39       A01X+023932Y+025157X0120Y0120     S2      
327NNAME10391       U2    -BL37       A01X+023582Y+025157X0120Y0120     S2      
327NNAME10392       U2    -BG41       A01X+024308Y+026070X0120Y0120     S2      
327N29180194        U2    -BH41       A01X+024308Y+025770X0120Y0120     S2      
327PV_VDDR_NODE1    U2    -BE41       A01X+024308Y+026370X0120Y0120     S2      
327PV_VDDR_NODE1    U2    -BE34       A01X+023020Y+026370X0120Y0120     S2      
327NNAME10334       U2    -BH34       A01X+023020Y+025770X0120Y0120     S2      
327NNAME10340       U2    -BG34       A01X+023020Y+026070X0120Y0120     S2      
327NNAME10393       U2    -BF38       A01X+023802Y+026220X0120Y0120     S2      
327PV_VDDR_NODE1    U2    -BD38       A01X+023802Y+026520X0120Y0120     S2      
327NNAME10383       U2    -BF37       A01X+023526Y+026220X0120Y0120     S2      
327PV_VDDR_NODE1    U2    -BD37       A01X+023526Y+026520X0120Y0120     S2      
327NNAME10332       U2    -BG37       A01X+023526Y+025920X0120Y0120     S2      
327NNAME10381       U2    -BG38       A01X+023802Y+025920X0120Y0120     S2      
327NNAME10394       U2    -BL35       A01X+023143Y+025216X0120Y0120     S2      
327GND              U2    -BK36       A01X+023353Y+025506X0120Y0120     S2      
327PV_VDDR_NODE1    U2    -BK35       A01X+023077Y+025487X0120Y0120     S2      
327PV_VDDR_NODE1    U2    -BK39       A01X+023896Y+025431X0120Y0120     S2      
327PV_VDDR_NODE1    U2    -BK37       A01X+023620Y+025431X0120Y0120     S2      
327NNAME10389       U2    -BK40       A01X+024169Y+025483X0120Y0120     S2      
327NNAME10395       U2    -BL34       A01X+022876Y+025298X0120Y0120     S2      
327PV_VDDR_NODE1    U2    -BE32       A01X+022744Y+026370X0120Y0120     S2      
327NNAME10335       U2    -BH32       A01X+022744Y+025770X0120Y0120     S2      
327NNAME10341       U2    -BG32       A01X+022744Y+026070X0120Y0120     S2      
317GND              VIA   -     D0100PA00X+023175Y+026514               S3      
317GND              VIA   -     D0100PA00X+023957Y+025764               S3      
317NNAME10392       VIA   -     D0100PA00X+024161Y+026220               S3      
317NNAME10244       VIA   -     D0100PA00X+023957Y+026664               S3      
317N29180194        VIA   -     D0100PA00X+024161Y+025920               S3      
317NNAME10391       VIA   -     D0100PA00X+023759Y+025275               S3      
317PV_VDDR_NODE1    VIA   -     D0100PA00X+024161Y+026520               S3      
317PV_VDDR_NODE1    VIA   -     D0100PA00X+023379Y+026670               S3      
317PV_VDDR_NODE1    VIA   -     D0100PA00X+023379Y+025770               S3      
317PV_VDDR_NODE1    VIA   -     D0100PA00X+023390Y+025277               S3      
317NNAME10393       VIA   -     D0100PA00X+023957Y+026364               S3      
317NNAME10383       VIA   -     D0100PA00X+023379Y+026370               S3      
327NNAME10383       VIA   -           A10X+023659Y+025889X0200Y0040R090 S1      
317NNAME10340       VIA   -     D0100PA00X+023175Y+026214               S3      
327NNAME10340       VIA   -           A10X+022850Y+025638X0260Y0260     S1      
317NNAME10332       VIA   -     D0100PA00X+023379Y+026070               S3      
317NNAME10381       VIA   -     D0100PA00X+023957Y+026064               S3      
317NNAME10334       VIA   -     D0100PA00X+023175Y+025914               S3      
327GND              C62   -2          A10X+023791Y+027769X0180Y0200R090 S1      
327NNAME10396       C62   -1          A10X+023791Y+027454X0180Y0200R090 S1      
327GND              C107  -2          A10X+024153Y+027804X0180Y0200R270 S1      
327P1V05_NODE1      C107  -1          A10X+024153Y+028119X0180Y0200R270 S1      
327NNAME10396       L5    -2          A10X+023406Y+027454X0180Y0200R270 S1      
327P1V05_NODE1      L5    -1          A10X+023406Y+027769X0180Y0200R270 S1      
327NNAME10021       PJ8   -2          A10X+023072Y+027784X0180Y0200R270 S1      
327P1V05_NODE1      PJ8   -1          A10X+023072Y+028099X0200Y0400     S1      
327GND              U2    -AU34       A01X+022992Y+027952X0150Y0150     S2      
327P1V05_NODE1      U2    -AU38       A01X+023622Y+027952X0150Y0150     S2      
327P1V05_NODE1      U2    -AU36       A01X+023307Y+027952X0150Y0150     S2      
327P1V05_NODE1      U2    -AU41       A01X+024252Y+027952X0150Y0150     S2      
327P1V05_NODE1      U2    -AU39       A01X+023937Y+027952X0150Y0150     S2      
327GND              U2    -AW38       A01X+023662Y+027677X0120Y0120     S2      
327GND              U2    -AW34       A01X+023020Y+027570X0120Y0120     S2      
327GND              U2    -AW41       A01X+024308Y+027570X0120Y0120     S2      
327GND              U2    -AW36       A01X+023307Y+027677X0120Y0120     S2      
327GND              U2    -AW39       A01X+023937Y+027677X0120Y0120     S2      
327NNAME10397       U2    -BB41       A01X+024308Y+026970X0120Y0120     S2      
327NNAME10397       U2    -BA41       A01X+024308Y+027270X0120Y0120     S2      
327NNAME10296       U2    -BA34       A01X+023020Y+027270X0120Y0120     S2      
327NNAME10296       U2    -BB34       A01X+023020Y+026970X0120Y0120     S2      
327NNAME10244       U2    -BC38       A01X+023802Y+026820X0120Y0120     S2      
327GND              U2    -BC37       A01X+023526Y+026820X0120Y0120     S2      
327GND              U2    -BA37       A01X+023526Y+027120X0120Y0120     S2      
327NNAME10396       U2    -BA38       A01X+023802Y+027120X0120Y0120     S2      
327NNAME10396       U2    -AY38       A01X+023802Y+027420X0120Y0120     S2      
327GND              U2    -AY37       A01X+023526Y+027420X0120Y0120     S2      
327NNAME10398       U2    -BD41       A01X+024308Y+026670X0120Y0120     S2      
327GND              U2    -BD34       A01X+023020Y+026670X0120Y0120     S2      
327NNAME10342       U2    -AW32       A01X+022744Y+027570X0120Y0120     S2      
327NNAME10342       U2    -BA32       A01X+022744Y+027270X0120Y0120     S2      
327GND              U2    -BB32       A01X+022744Y+026970X0120Y0120     S2      
327GND              U2    -BD32       A01X+022744Y+026670X0120Y0120     S2      
317GND              VIA   -     D0100PA00X+024091Y+027474               S3      
317GND              VIA   -     D0100PA00X+023379Y+026970               S3      
317P1V05_NODE1      VIA   -     D0100PA00X+023465Y+028110               S3      
317P1V05_NODE1      VIA   -     D0100PA00X+023787Y+028113               S3      
327NNAME10396       VIA   -           A10X+023662Y+027019X0260Y0260R180 S1      
317NNAME10396       VIA   -     D0100PA00X+023957Y+026964               S3      
317NNAME10296       VIA   -     D0100PA00X+023212Y+027159               S3      
317NNAME10397       VIA   -     D0100PA00X+024161Y+027120               S3      
317NNAME10398       VIA   -     D0100PA00X+024161Y+026820               S3      
317NNAME10038       VIA   -     D0100PA00X+022882Y+027420               S3      
317NNAME10021       VIA   -     D0100PA00X+023165Y+027424               S3      
327GND              C128  -2          A10X+023479Y+028693X0180Y0200R090 S1      
327P1V05_NODE1      C128  -1          A10X+023479Y+028378X0180Y0200R090 S1      
327P1V05_NODE1      C52   -1          A10X+023511Y+029743X0180Y0200R090 S1      
327GND              C127  -2          A10X+023479Y+029068X0180Y0200R270 S1      
327P1V05_NODE1      C127  -1          A10X+023479Y+029383X0180Y0200R270 S1      
327GND              C123  -2          A10X+022841Y+029123X0180Y0200R270 S1      
327P1V05_NODE1      C123  -1          A10X+022841Y+029438X0180Y0200R270 S1      
327GND              C43   -2          A10X+022844Y+028741X0180Y0200R090 S1      
327P1V05_NODE1      C43   -1          A10X+022844Y+028426X0180Y0200R090 S1      
327P1V05_NODE1      U2    -AT34       A01X+022992Y+028267X0150Y0150     S2      
327GND              U2    -AT38       A01X+023622Y+028267X0150Y0150     S2      
327GND              U2    -AT36       A01X+023307Y+028267X0150Y0150     S2      
327GND              U2    -AT41       A01X+024252Y+028267X0150Y0150     S2      
327GND              U2    -AT39       A01X+023937Y+028267X0150Y0150     S2      
327P1V05_NODE1      U2    -AJ34       A01X+022992Y+029527X0150Y0150     S2      
327GND              U2    -AL34       A01X+022992Y+029212X0150Y0150     S2      
327P1V05_NODE1      U2    -AM34       A01X+022992Y+028897X0150Y0150     S2      
327GND              U2    -AP34       A01X+022992Y+028582X0150Y0150     S2      
327P1V05_NODE1      U2    -AP38       A01X+023622Y+028582X0150Y0150     S2      
327P1V05_NODE1      U2    -AM38       A01X+023622Y+028897X0150Y0150     S2      
327GND              U2    -AL38       A01X+023622Y+029212X0150Y0150     S2      
327P1V05_NODE1      U2    -AJ38       A01X+023622Y+029527X0150Y0150     S2      
327P1V05_NODE1      U2    -AP36       A01X+023307Y+028582X0150Y0150     S2      
327GND              U2    -AM36       A01X+023307Y+028897X0150Y0150     S2      
327P1V05_NODE1      U2    -AL36       A01X+023307Y+029212X0150Y0150     S2      
327GND              U2    -AJ36       A01X+023307Y+029527X0150Y0150     S2      
327P1V05_NODE1      U2    -AP41       A01X+024252Y+028582X0150Y0150     S2      
327P1V05_NODE1      U2    -AM41       A01X+024252Y+028897X0150Y0150     S2      
327GND              U2    -AL41       A01X+024252Y+029212X0150Y0150     S2      
327P1V05_NODE1      U2    -AJ41       A01X+024252Y+029527X0150Y0150     S2      
327P1V05_NODE1      U2    -AP39       A01X+023937Y+028582X0150Y0150     S2      
327GND              U2    -AM39       A01X+023937Y+028897X0150Y0150     S2      
327P1V05_NODE1      U2    -AL39       A01X+023937Y+029212X0150Y0150     S2      
327GND              U2    -AJ39       A01X+023937Y+029527X0150Y0150     S2      
317GND              VIA   -     D0100PA00X+023780Y+029055               S3      
317GND              VIA   -     D0100PA00X+023780Y+028425               S3      
317GND              VIA   -     D0100PA00X+023150Y+028740               S3      
317P1V05_NODE1      VIA   -     D0100PA00X+023145Y+029058               S3      
317P1V05_NODE1      VIA   -     D0100PA00X+023776Y+029369               S3      
317P1V05_NODE1      VIA   -     D0100PA00X+023780Y+028740               S3      
317P1V05_NODE1      VIA   -     D0100PA00X+024095Y+029055               S3      
317P1V05_NODE1      VIA   -     D0100PA00X+024095Y+028740               S3      
317P1V05_NODE1      VIA   -     D0100PA00X+023150Y+028425               S3      
317P1V05_NODE1      VIA   -     D0100PA00X+023150Y+029685               S3      
317P1V05_NODE1      VIA   -     D0100PA00X+023150Y+029370               S3      
317NNAME10311       VIA   -     D0100PA00X+024095Y+029685               S3      
327NNAME10399       VIA   -           A10X+024057Y+029381X0260Y0260R180 S1      
327P1V05_NODE1      C98   -1          A10X+023502Y+031304X0180Y0200R090 S1      
327P1V05_NODE1      C100  -1          A10X+024031Y+031240X0180Y0200R090 S1      
327GND              C102  -2          A10X+023160Y+030316X0180Y0200R270 S1      
327P1V05_NODE1      C102  -1          A10X+023160Y+030631X0180Y0200R270 S1      
327GND              C52   -2          A10X+023511Y+030058X0180Y0200R090 S1      
327P1V05_NODE1      U2    -AG34       A01X+022992Y+029842X0150Y0150     S2      
327GND              U2    -AF34       A01X+022992Y+030157X0150Y0150     S2      
327NNAME10310       U2    -AF38       A01X+023622Y+030157X0150Y0150     S2      
327GND              U2    -AG38       A01X+023622Y+029842X0150Y0150     S2      
327P1V05_NODE1      U2    -AF36       A01X+023307Y+030157X0150Y0150     S2      
327P1V05_NODE1      U2    -AG36       A01X+023307Y+029842X0150Y0150     S2      
327NNAME10400       U2    -AF41       A01X+024252Y+030157X0150Y0150     S2      
327NNAME10399       U2    -AG41       A01X+024252Y+029842X0150Y0150     S2      
327GND              U2    -AF39       A01X+023937Y+030157X0150Y0150     S2      
327NNAME10311       U2    -AG39       A01X+023937Y+029842X0150Y0150     S2      
327GND              U2    -AD34       A01X+022992Y+030472X0150Y0150     S2      
327P1V05_NODE1      U2    -AC34       A01X+022992Y+030787X0150Y0150     S2      
327P1V05_NODE1      U2    -AA34       A01X+022992Y+031102X0150Y0150     S2      
327P1V05_NODE1      U2    -AA38       A01X+023622Y+031102X0150Y0150     S2      
327NNAME10307       U2    -AC38       A01X+023622Y+030787X0150Y0150     S2      
327GND              U2    -AD38       A01X+023622Y+030472X0150Y0150     S2      
327GND              U2    -AA36       A01X+023307Y+031102X0150Y0150     S2      
327P1V05_NODE1      U2    -AC36       A01X+023307Y+030787X0150Y0150     S2      
327GND              U2    -AD36       A01X+023307Y+030472X0150Y0150     S2      
327P1V05_NODE1      U2    -AA41       A01X+024252Y+031102X0150Y0150     S2      
327NNAME10401       U2    -AC41       A01X+024252Y+030787X0150Y0150     S2      
327NNAME10402       U2    -AD41       A01X+024252Y+030472X0150Y0150     S2      
327GND              U2    -AA39       A01X+023937Y+031102X0150Y0150     S2      
327GND              U2    -AC39       A01X+023937Y+030787X0150Y0150     S2      
327NNAME10308       U2    -AD39       A01X+023937Y+030472X0150Y0150     S2      
317GND              VIA   -     D0100PA00X+023780Y+030000               S3      
317GND              VIA   -     D0100PA00X+023150Y+030945               S3      
317P1V05_NODE1      VIA   -     D0100PA00X+023150Y+030000               S3      
317P1V05_NODE1      VIA   -     D0100PA00X+023780Y+031260               S3      
317P1V05_NODE1      VIA   -     D0100PA00X+023150Y+031260               S3      
317P1V05_NODE1      VIA   -     D0100PA00X+024095Y+030945               S3      
317NNAME10308       VIA   -     D0100PA00X+023780Y+030315               S3      
317NNAME10310       VIA   -     D0100PA00X+023465Y+030315               S3      
317NNAME10307       VIA   -     D0100PA00X+023780Y+030630               S3      
317NNAME10401       VIA   -     D0100PA00X+024093Y+030626               S1      
317NNAME10399       VIA   -     D0100PA00X+024095Y+030000               S3      
317NNAME10400       VIA   -     D0100PA00X+024095Y+030315               S3      
327GND              C46   -2          A10X+023102Y+031662X0180Y0200     S1      
327GND              C40   -2          A10X+023802Y+032412X0180Y0200     S1      
327P3V3_NODE1       C40   -1          A10X+023487Y+032412X0180Y0200     S1      
327GND              C41   -2          A10X+023802Y+032012X0180Y0200     S1      
327P3V3_NODE1       C41   -1          A10X+023487Y+032012X0180Y0200     S1      
327GND              C98   -2          A10X+023502Y+031619X0180Y0200R090 S1      
327GND              C100  -2          A10X+024031Y+031555X0180Y0200R090 S1      
327NNAME10403       R98   -1          A10X+023552Y+032941X0180Y0200R090 S1      
327GND              U2    -T41        A01X+024214Y+032115X0120Y0120     S2      
327P1V8_SUS_NODE1   U2    -N41        A01X+024214Y+032715X0120Y0120     S2      
327P1V8_SUS_NODE1   U2    -P41        A01X+024214Y+032415X0120Y0120     S2      
327P3V3_NODE1       U2    -T36        A01X+023307Y+032008X0120Y0120     S2      
327GND              U2    -T39        A01X+023937Y+032008X0120Y0120     S2      
327GND              U2    -T37        A01X+023583Y+032008X0120Y0120     S2      
327GND              U2    -R38        A01X+023708Y+032265X0120Y0120     S2      
327P3V3_NODE1       U2    -R37        A01X+023432Y+032265X0120Y0120     S2      
327P3V3_NODE1       U2    -P37        A01X+023432Y+032565X0120Y0120     S2      
327GND              U2    -P38        A01X+023708Y+032565X0120Y0120     S2      
327NNAME10403       U2    -M38        A01X+023708Y+032865X0120Y0120     S2      
327P3V3_NODE1       U2    -M37        A01X+023432Y+032865X0120Y0120     S2      
327GND              U2    -T34        A01X+022926Y+032115X0120Y0120     S2      
327NNAME10343       U2    -P34        A01X+022926Y+032415X0120Y0120     S2      
327GND              U2    -N34        A01X+022926Y+032715X0120Y0120     S2      
327GND              U2    -W34        A01X+022992Y+031417X0150Y0150     S2      
327GND              U2    -V34        A01X+022992Y+031732X0150Y0150     S2      
327GND              U2    -V38        A01X+023622Y+031732X0150Y0150     S2      
327GND              U2    -W38        A01X+023622Y+031417X0150Y0150     S2      
327P3V3_NODE1       U2    -V36        A01X+023307Y+031732X0150Y0150     S2      
327P1V05_NODE1      U2    -W36        A01X+023307Y+031417X0150Y0150     S2      
327GND              U2    -V41        A01X+024252Y+031732X0150Y0150     S2      
327GND              U2    -W41        A01X+024252Y+031417X0150Y0150     S2      
327GND              U2    -V39        A01X+023937Y+031732X0150Y0150     S2      
327P1V05_NODE1      U2    -W39        A01X+023937Y+031417X0150Y0150     S2      
317GND              VIA   -     D0100PA00X+024126Y+031912               S3      
317P3V3_NODE1       VIA   -     D0100PA00X+023157Y+032174               S3      
317P3V3_NODE1       VIA   -     D0100PA00X+023278Y+032710               S3      
327NNAME10343       VIA   -           A10X+022843Y+032147X0260Y0260     S1      
317NNAME10343       VIA   -     D0100PA00X+023073Y+032565               S3      
327NNAME10403       VIA   -           A10X+023025Y+032862X0260Y0260     S1      
317NNAME10403       VIA   -     D0100PA00X+023855Y+032715               S3      
317P1V8_SUS_NODE1   VIA   -     D0100PA00X+024037Y+032896               S3      
317P1V8_SUS_NODE1   VIA   -     D0100PA00X+024051Y+032552               S3      
327GND              C76   -2          A10X+024361Y+033644X0180Y0200R090 S1      
327P1V8_SUS_NODE1   C76   -1          A10X+024361Y+033329X0180Y0200R090 S1      
327GND              R98   -2          A10X+023552Y+033256X0180Y0200R090 S1      
327GND              U2    -E34        A01X+022995Y+034198X0120Y0120     S2      
327NNAME10404       U2    -E36        A01X+023274Y+034202X0120Y0120     S2      
327NNAME10405       U2    -E40        A01X+024089Y+034178X0120Y0120     S2      
327NNAME10406       U2    -H41        A01X+024214Y+033615X0120Y0120     S2      
327GND              U2    -K41        A01X+024214Y+033315X0120Y0120     S2      
327P1V8_SUS_NODE1   U2    -L41        A01X+024214Y+033015X0120Y0120     S2      
327NNAME10407       U2    -G41        A01X+024214Y+033915X0120Y0120     S2      
327NNAME10408       U2    -H37        A01X+023432Y+033765X0120Y0120     S2      
327N/C              U2    -H38        A01X+023708Y+033765X0120Y0120     S2      
327GND              U2    -L38        A01X+023708Y+033165X0120Y0120     S2      
327NNAME10409       U2    -J38        A01X+023708Y+033465X0120Y0120     S2      
327GND              U2    -L37        A01X+023432Y+033165X0120Y0120     S2      
327NNAME10354       U2    -J37        A01X+023432Y+033465X0120Y0120     S2      
327GND              U2    -L34        A01X+022926Y+033015X0120Y0120     S2      
327GND              U2    -K34        A01X+022926Y+033315X0120Y0120     S2      
327NNAME10351       U2    -H34        A01X+022926Y+033615X0120Y0120     S2      
327NNAME10353       U2    -G34        A01X+022926Y+033915X0120Y0120     S2      
327NNAME10410       U2    -D33        A01X+022794Y+034387X0120Y0120     S2      
327GND              U2    -D41        A01X+024299Y+034469X0120Y0120     S2      
327NNAME10411       U2    -D35        A01X+023057Y+034486X0120Y0120     S2      
327GND              U2    -E37        A01X+023547Y+034254X0120Y0120     S2      
327NNAME10412       U2    -E39        A01X+023822Y+034254X0120Y0120     S2      
317GND              VIA   -     D0100PA00X+024069Y+034420               S3      
317GND              VIA   -     D0100PA00X+023306Y+033994               S3      
317GND              VIA   -     D0100PA00X+023073Y+033165               S3      
317NNAME10409       VIA   -     D0100PA00X+023855Y+033315               S3      
317NNAME10351       VIA   -     D0100PA00X+023073Y+033455               S3      
317NNAME10413       VIA   -     D0100PA00X+024060Y+033464               S3      
317NNAME10407       VIA   -     D0100PA00X+024022Y+033801               S3      
317NNAME10353       VIA   -     D0100PA00X+023114Y+033823               S3      
317NNAME10406       VIA   -     D0100PA00X+023856Y+033614               S3      
317NNAME10354       VIA   -     D0100PA00X+023277Y+033321               S3      
317NNAME10408       VIA   -     D0100PA00X+023280Y+033618               S3      
327NNAME10408       VIA   -           A10X+023287Y+034295X0260Y0260     S1      
317NNAME10405       VIA   -     D0100PA00X+023929Y+034043               S3      
327NNAME10409       R59   -1          A10X+023864Y+036080X0180Y0200R090 S1      
327GND              U2    -A33        A01X+022794Y+035059X0100Y0135     S2      
327GND              U2    -A39        A01X+024001Y+035059X0100Y0135     S2      
327GND              U2    -A36        A01X+023361Y+035059X0100Y0135     S2      
327NNAME10352       U2    -C33        A01X+022814Y+034687X0120Y0120     S2      
327NNAME10414       U2    -B39        A01X+023863Y+034819X0120Y0120     S2      
327NNAME10415       U2    -B41        A01X+024268Y+034884X0120Y0120     S2      
327NNAME10416       U2    -B35        A01X+023078Y+034863X0120Y0120     S2      
327GND              U2    -B37        A01X+023498Y+034818X0120Y0120     S2      
327NNAME10417       U2    -C36        A01X+023270Y+034662X0120Y0120     S2      
327GND              U2    -D37        A01X+023511Y+034528X0120Y0120     S2      
327GND              U2    -D39        A01X+023861Y+034528X0120Y0120     S2      
327NNAME10418       U2    -C40        A01X+024101Y+034664X0120Y0120     S2      
317GND              VIA   -     D0100PA00X+023370Y+035396               S3      
317GND              VIA   -     D0100PA00X+023808Y+035599               S3      
327NNAME10409       VIA   -           A10X+023522Y+034828X0260Y0260     S1      
327NNAME10406       VIA   -           A10X+024024Y+035296X0260Y0260     S1      
317NNAME10411       VIA   -     D0100PA00X+022842Y+035686               S1      
317NNAME10404       VIA   -     D0100PA00X+023364Y+035708               S1      
327NNAME10405       VIA   -           A10X+024118Y+034768X0260Y0260     S1      
327NNAME10419       R61   -1          A10X+024091Y+037715X0180Y0200     S1      
327NNAME10420       R59   -2          A10X+023864Y+036395X0180Y0200R090 S1      
317NNAME10410       VIA   -     D0100PA00X+023001Y+037330               S1      
327NNAME10418       VIA   -           A01X+024122Y+037460X0300Y0300     S2      
317NNAME10412       VIA   -     D0100PA00X+023758Y+036958               S1      
317NNAME10416       VIA   -     D0100PA00X+023314Y+036707               S1      
317NNAME10415       VIA   -     D0100PA00X+024308Y+036838               S1      
317NNAME10417       VIA   -     D0100PA00X+023126Y+036222               S1      
327NNAME10414       VIA   -           A01X+023708Y+036411X0300Y0300     S2      
327GND              R55   -2          A01X+023273Y+038232X0180Y0200R270 S2      
327NNAME10410       R55   -1          A01X+023273Y+037917X0180Y0200R270 S2      
327P1V8_NODE1       R47   -2          A01X+022873Y+038232X0180Y0200R270 S2      
327NNAME10350       R47   -1          A01X+022873Y+037917X0180Y0200R270 S2      
327NNAME10407       R62   -2          A10X+023669Y+037912X0180Y0200R270 S1      
327NNAME10421       R62   -1          A10X+023669Y+038227X0180Y0200R270 S1      
327NNAME10406       R60   -2          A10X+023269Y+037762X0180Y0200R270 S1      
327NNAME10422       R60   -1          A10X+023269Y+038077X0180Y0200R270 S1      
327GND              R56   -2          A01X+023673Y+038232X0180Y0200R270 S2      
327NNAME10352       R56   -1          A01X+023673Y+037917X0180Y0200R270 S2      
327GND              R1093 -1          A01X+024263Y+038796X0180Y0200R180 S2      
327GND              R52   -2          A01X+024073Y+038232X0180Y0200R270 S2      
327NNAME10416       R52   -1          A01X+024073Y+037917X0180Y0200R270 S2      
327NNAME10423       R63   -1          A10X+024160Y+038120X0180Y0200     S1      
317GND              VIA   -     D0100PA00X+024394Y+039089               S3      
317GND              VIA   -     D0100PA00X+023669Y+038523               S3      
317GND              VIA   -     D0100PA00X+023217Y+038881               S3      
317P1V8_NODE1       VIA   -     D0100PA00X+022873Y+038523               S3      
317NNAME10424       VIA   -     D0100PA00X+024145Y+039215               S3      
317NNAME10421       VIA   -     D0100PA00X+023641Y+038772               S3      
317NNAME10422       VIA   -     D0100PA00X+023122Y+039142               S3      
317NNAME10423       VIA   -     D0100PA00X+023955Y+039053               S3      
317P3V3_NODE1       VIA   -     D0100PA00X+023923Y+039329               S3      
317NNAME10419       VIA   -     D0100PA00X+023643Y+039347               S1      
317NNAME10425       VIA   -     D0100PA00X+023265Y+039601               S3      
327GND              PC133 -2          A01X+024013Y+041826X0440Y0540R180 S2      
327P3V3_STB_NODE1   PC133 -1          A01X+023265Y+041826X0440Y0540R180 S2      
317P3V3_STB_NODE1   VIA   -     D0100PA00X+022891Y+042456               S3      
317P3V3_STB_NODE1   VIA   -     D0100PA00X+022871Y+041653               S3      
317P3V3_STB_NODE1   VIA   -     D0100PA00X+022871Y+041953               S3      
327GND              PC16  -2          A01X+024020Y+043414X0440Y0540R180 S2      
327P3V3_STB_NODE1   PC16  -1          A01X+023272Y+043414X0440Y0540R180 S2      
327GND              PC18  -2          A01X+023808Y+043994X0180Y0200R180 S2      
327P3V3_STB_NODE1   PC18  -1          A01X+023493Y+043994X0180Y0200R180 S2      
327GND              PC17  -2          A01X+024020Y+042614X0440Y0540R180 S2      
327P3V3_STB_NODE1   PC17  -1          A01X+023272Y+042614X0440Y0540R180 S2      
317GND              VIA   -     D0100PA00X+024060Y+044005               S3      
317P3V3_STB_NODE1   VIA   -     D0100PA00X+023187Y+043951               S3      
317P3V3_STB_NODE1   VIA   -     D0100PA00X+022891Y+043356               S3      
317P3V3_STB_NODE1   VIA   -     D0100PA00X+022891Y+042756               S3      
317P3V3_STB_NODE1   VIA   -     D0100PA00X+022891Y+043656               S3      
317P3V3_STB_NODE1   VIA   -     D0100PA00X+023189Y+044225               S3      
327BMC_ROMD3        R343  -2          A01X+022824Y+046992X0180Y0200R270 S2      
327P3V3_NODE1       R343  -1          A01X+022824Y+046677X0180Y0200R270 S2      
327BMC_ROMA16       R332  -2          A10X+023532Y+047027X0180Y0200R090 S1      
327P3V3_NODE1       R332  -1          A10X+023532Y+046712X0180Y0200R090 S1      
327BMC_ROMA6        R322  -2          A01X+024201Y+046658X0180Y0200R090 S2      
327P3V3_NODE1       R322  -1          A01X+024201Y+046973X0180Y0200R090 S2      
327BMC_ROMA1        R317  -2          A01X+023761Y+046658X0180Y0200R090 S2      
327P3V3_NODE1       R317  -1          A01X+023761Y+046973X0180Y0200R090 S2      
327BMC_ROMD1        R341  -2          A01X+023331Y+046658X0180Y0200R090 S2      
327P3V3_NODE1       R341  -1          A01X+023331Y+046973X0180Y0200R090 S2      
327BMC_ROMA3        R319  -2          A10X+024198Y+046658X0180Y0200R270 S1      
327P3V3_NODE1       R319  -1          A10X+024198Y+046973X0180Y0200R270 S1      
317P3V3_NODE1       VIA   -     D0100PA00X+023532Y+046436               S3      
317BMC_ROMD1        VIA   -     D0100PA00X+023146Y+046259               S1      
317BMC_ROMA6        VIA   -     D0100PA00X+024347Y+046029               S1      
317BMC_ROMA1        VIA   -     D0100PA00X+023843Y+046034               S1      
327PECIVDD          VIA   -           A10X+022882Y+046778X0260Y0260     S1      
327BMC_ROMA7        R323  -2          A01X+024191Y+047813X0180Y0200R270 S2      
327P3V3_NODE1       R323  -1          A01X+024191Y+047498X0180Y0200R270 S2      
327BMC_ROMA2        R318  -2          A01X+023761Y+047813X0180Y0200R270 S2      
327P3V3_NODE1       R318  -1          A01X+023761Y+047498X0180Y0200R270 S2      
327BMC_ROMD0        R340  -2          A01X+023331Y+047813X0180Y0200R270 S2      
327P3V3_NODE1       R340  -1          A01X+023331Y+047498X0180Y0200R270 S2      
327BMC_ROMD2        R342  -2          A10X+024191Y+047813X0180Y0200R090 S1      
327P3V3_NODE1       R342  -1          A10X+024191Y+047498X0180Y0200R090 S1      
317P3V3_NODE1       VIA   -     D0100PA00X+023331Y+047255               S3      
317P3V3_NODE1       VIA   -     D0100PA00X+023761Y+047245               S3      
317P3V3_NODE1       VIA   -     D0100PA00X+024191Y+047255               S3      
327BMC_ROMD2        VIA   -           A10X+023970Y+048691X0260Y0260R090 S1      
317BMC_ROMD0        VIA   -     D0100PA00X+023421Y+048095               S1      
327BMC_ROMA2        VIA   -           A01X+023931Y+048275X0300Y0300     S2      
317BMC_ROMD3        VIA   -     D0100PA00X+022860Y+047968               S1      
327N/C              U14   -AA22       A01X+022891Y+049787X0145Y0145R270 S2      
327N/C              U14   -AA21       A01X+022891Y+050102X0145Y0145R270 S2      
327N/C              U14   -Y22        A01X+023205Y+049787X0145Y0145R270 S2      
327N/C              U14   -Y21        A01X+023205Y+050102X0145Y0145R270 S2      
327N/C              U14   -W22        A01X+023520Y+049787X0145Y0145R270 S2      
327N/C              U14   -W21        A01X+023520Y+050102X0145Y0145R270 S2      
327N/C              U14   -V22        A01X+023835Y+049787X0145Y0145R270 S2      
327N/C              U14   -V21        A01X+023835Y+050102X0145Y0145R270 S2      
327BMC_ROMD3        U14   -U22        A01X+024150Y+049787X0145Y0145R270 S2      
327BMC_ROMD4        U14   -U21        A01X+024150Y+050102X0145Y0145R270 S2      
327GND              C269  -2          A10X+022869Y+049418X0180Y0200R090 S1      
327NNAME10356       C269  -1          A10X+022869Y+049103X0180Y0200R090 S1      
317NNAME10209       VIA   -     D0100PA00X+023363Y+050259               S3      
317NNAME10316       VIA   -     D0100PA00X+023048Y+050259               S3      
317BMC_ROMD2        VIA   -     D0100PA00X+024308Y+050259               S3      
327BMC_ROMA16       VIA   -           A10X+023491Y+048965X0260Y0260R090 S1      
327BMC_ROMA3        VIA   -           A10X+023691Y+049445X0260Y0260R090 S1      
327NNAME10360       VIA   -           A10X+023609Y+050087X0260Y0260     S1      
327BMC_ROMA0        VIA   -           A10X+024250Y+049630X0260Y0260     S1      
327NNAME10359       U14   -AA20       A01X+022891Y+050417X0145Y0145R270 S2      
327GND              U14   -AA19       A01X+022891Y+050732X0145Y0145R270 S2      
327GND              U14   -AA18       A01X+022891Y+051047X0145Y0145R270 S2      
327NNAME10142       U14   -AA17       A01X+022891Y+051362X0145Y0145R270 S2      
327NNAME10213       U14   -AA16       A01X+022891Y+051677X0145Y0145R270 S2      
327NNAME10316       U14   -Y20        A01X+023205Y+050417X0145Y0145R270 S2      
327GND              U14   -Y19        A01X+023205Y+050732X0145Y0145R270 S2      
327NNAME10317       U14   -Y18        A01X+023205Y+051047X0145Y0145R270 S2      
327NNAME10140       U14   -Y17        A01X+023205Y+051362X0145Y0145R270 S2      
327NNAME10147       U14   -Y16        A01X+023205Y+051677X0145Y0145R270 S2      
327NNAME10209       U14   -W20        A01X+023520Y+050417X0145Y0145R270 S2      
327NNAME10316       U14   -W19        A01X+023520Y+050732X0145Y0145R270 S2      
327P3V3_NODE1       U14   -W18        A01X+023520Y+051047X0145Y0145R270 S2      
327NNAME10217       U14   -W17        A01X+023520Y+051362X0145Y0145R270 S2      
327NNAME10145       U14   -W16        A01X+023520Y+051677X0145Y0145R270 S2      
327N/C              U14   -V20        A01X+023835Y+050417X0145Y0145R270 S2      
327PECIVDD          U14   -V19        A01X+023835Y+050732X0145Y0145R270 S2      
327GND              U14   -V18        A01X+023835Y+051047X0145Y0145R270 S2      
327NNAME10356       U14   -V17        A01X+023835Y+051362X0145Y0145R270 S2      
327NNAME10360       U14   -V16        A01X+023835Y+051677X0145Y0145R270 S2      
327N/C              U14   -U20        A01X+024150Y+050417X0145Y0145R270 S2      
327N/C              U14   -U19        A01X+024150Y+050732X0145Y0145R270 S2      
327N/C              U14   -U18        A01X+024150Y+051047X0145Y0145R270 S2      
327GND              C270  -2          A10X+024299Y+051147X0180Y0200     S1      
327NNAME10356       C270  -1          A10X+023984Y+051147X0180Y0200     S1      
327GND              C268  -2          A10X+024302Y+051545X0180Y0200     S1      
327NNAME10356       C268  -1          A10X+023987Y+051545X0180Y0200     S1      
317GND              VIA   -     D0100PA00X+023048Y+050574               S3      
317GND              VIA   -     D0100PA00X+023678Y+050889               S3      
317NNAME10144       VIA   -     D0100PA00X+023678Y+051834               S3      
317P3V3_NODE1       VIA   -     D0100PA00X+023363Y+050889               S3      
317NNAME10145       VIA   -     D0100PA00X+023363Y+051519               S3      
317NNAME10147       VIA   -     D0100PA00X+023048Y+051519               S3      
317NNAME10215       VIA   -     D0100PA00X+023363Y+051834               S3      
317NNAME10356       VIA   -     D0100PA00X+023678Y+051204               S3      
317BMC_ROMA16       VIA   -     D0100PA00X+024308Y+050889               S3      
317NNAME10317       VIA   -     D0100PA00X+023048Y+050889               S3      
317NNAME10360       VIA   -     D0100PA00X+023678Y+051519               S3      
317NNAME10218       VIA   -     D0100PA00X+023048Y+051834               S3      
317NNAME10140       VIA   -     D0100PA00X+023048Y+051204               S3      
317NNAME10217       VIA   -     D0100PA00X+023363Y+051204               S3      
317NNAME10063       VIA   -     D0100PA00X+023993Y+051834               S3      
327NNAME10212       U14   -AA15       A01X+022891Y+051992X0145Y0145R270 S2      
327NNAME10216       U14   -AA14       A01X+022891Y+052307X0145Y0145R270 S2      
327NNAME10151       U14   -AA13       A01X+022891Y+052622X0145Y0145R270 S2      
327NNAME10221       U14   -AA12       A01X+022891Y+052937X0145Y0145R270 S2      
327NNAME10226       U14   -AA11       A01X+022891Y+053252X0145Y0145R270 S2      
327NNAME10218       U14   -Y15        A01X+023205Y+051992X0145Y0145R270 S2      
327NNAME10148       U14   -Y14        A01X+023205Y+052307X0145Y0145R270 S2      
327NNAME10150       U14   -Y13        A01X+023205Y+052622X0145Y0145R270 S2      
327NNAME10265       U14   -Y12        A01X+023205Y+052937X0145Y0145R270 S2      
327NNAME10161       U14   -Y11        A01X+023205Y+053252X0145Y0145R270 S2      
327NNAME10215       U14   -W15        A01X+023520Y+051992X0145Y0145R270 S2      
327NNAME10149       U14   -W14        A01X+023520Y+052307X0145Y0145R270 S2      
327NNAME10155       U14   -W13        A01X+023520Y+052622X0145Y0145R270 S2      
327NNAME10224       U14   -W12        A01X+023520Y+052937X0145Y0145R270 S2      
327NNAME10159       U14   -W11        A01X+023520Y+053252X0145Y0145R270 S2      
327NNAME10144       U14   -V15        A01X+023835Y+051992X0145Y0145R270 S2      
327NNAME10154       U14   -V14        A01X+023835Y+052307X0145Y0145R270 S2      
327NNAME10109       U14   -V13        A01X+023835Y+052622X0145Y0145R270 S2      
327NNAME10157       U14   -V12        A01X+023835Y+052937X0145Y0145R270 S2      
327NNAME10223       U14   -V11        A01X+023835Y+053252X0145Y0145R270 S2      
327NNAME10063       U14   -U15        A01X+024150Y+051992X0145Y0145R270 S2      
327NNAME10063       U14   -U14        A01X+024150Y+052307X0145Y0145R270 S2      
327NNAME10317       U14   -U13        A01X+024150Y+052622X0145Y0145R270 S2      
327NNAME10317       U14   -U12        A01X+024150Y+052937X0145Y0145R270 S2      
327NNAME10063       U14   -U11        A01X+024150Y+053252X0145Y0145R270 S2      
327NNAME10317       C289  -1          A10X+024323Y+052774X0180Y0200     S1      
327NNAME10063       C273  -2          A10X+024324Y+051971X0180Y0200R180 S1      
327NNAME10063       C275  -2          A10X+024323Y+052373X0180Y0200R180 S1      
327NNAME10063       C272  -1          A10X+024328Y+053178X0180Y0200     S1      
317NNAME10149       VIA   -     D0100PA00X+023363Y+052149               S3      
317NNAME10223       VIA   -     D0100PA00X+023678Y+053409               S3      
317NNAME10224       VIA   -     D0100PA00X+023363Y+052779               S3      
317NNAME10161       VIA   -     D0100PA00X+023048Y+053409               S3      
317NNAME10154       VIA   -     D0100PA00X+023678Y+052149               S3      
317NNAME10157       VIA   -     D0100PA00X+023678Y+052779               S3      
317NNAME10155       VIA   -     D0100PA00X+023363Y+052464               S3      
317NNAME10109       VIA   -     D0100PA00X+023678Y+052464               S3      
317NNAME10150       VIA   -     D0100PA00X+023048Y+052464               S3      
317NNAME10159       VIA   -     D0100PA00X+023363Y+053409               S3      
317NNAME10317       VIA   -     D0100PA00X+023993Y+052779               S3      
317NNAME10317       VIA   -     D0100PA00X+023993Y+052464               S3      
317NNAME10265       VIA   -     D0100PA00X+023048Y+052779               S3      
317NNAME10148       VIA   -     D0100PA00X+023048Y+052149               S3      
317NNAME10063       VIA   -     D0100PA00X+023993Y+053409               S3      
317NNAME10063       VIA   -     D0100PA00X+023993Y+052149               S3      
327NNAME10158       U14   -AA10       A01X+022891Y+053567X0145Y0145R270 S2      
327NNAME10233       U14   -AA9        A01X+022891Y+053882X0145Y0145R270 S2      
327NNAME10230       U14   -AA8        A01X+022891Y+054197X0145Y0145R270 S2      
327N/C              U14   -AA7        A01X+022891Y+054512X0145Y0145R270 S2      
327N/C              U14   -AA6        A01X+022891Y+054827X0145Y0145R270 S2      
327NNAME10162       U14   -Y10        A01X+023205Y+053567X0145Y0145R270 S2      
327NNAME10164       U14   -Y9         A01X+023205Y+053882X0145Y0145R270 S2      
327NNAME10166       U14   -Y8         A01X+023205Y+054197X0145Y0145R270 S2      
327N/C              U14   -Y7         A01X+023205Y+054512X0145Y0145R270 S2      
327N/C              U14   -Y6         A01X+023205Y+054827X0145Y0145R270 S2      
327NNAME10227       U14   -W10        A01X+023520Y+053567X0145Y0145R270 S2      
327NNAME10165       U14   -W9         A01X+023520Y+053882X0145Y0145R270 S2      
327NNAME10167       U14   -W8         A01X+023520Y+054197X0145Y0145R270 S2      
327N/C              U14   -W7         A01X+023520Y+054512X0145Y0145R270 S2      
327N/C              U14   -W6         A01X+023520Y+054827X0145Y0145R270 S2      
327NNAME10228       U14   -V10        A01X+023835Y+053567X0145Y0145R270 S2      
327NNAME10229       U14   -V9         A01X+023835Y+053882X0145Y0145R270 S2      
327NNAME10163       U14   -V8         A01X+023835Y+054197X0145Y0145R270 S2      
327N/C              U14   -V7         A01X+023835Y+054512X0145Y0145R270 S2      
327N/C              U14   -V6         A01X+023835Y+054827X0145Y0145R270 S2      
327NNAME10063       U14   -U10        A01X+024150Y+053567X0145Y0145R270 S2      
327P3V3_NODE1       U14   -U9         A01X+024150Y+053882X0145Y0145R270 S2      
327P3V3_NODE1       U14   -U8         A01X+024150Y+054197X0145Y0145R270 S2      
327NNAME10063       C274  -1          A10X+024327Y+053579X0180Y0200     S1      
327P3V3_NODE1       C244  -1          A10X+024238Y+054396X0180Y0200     S1      
327P3V3_NODE1       C280  -1          A10X+024342Y+053979X0180Y0200     S1      
317NNAME10167       VIA   -     D0100PA00X+023363Y+054354               S3      
317P3V3_NODE1       VIA   -     D0100PA00X+023993Y+054039               S3      
317P3V3_NODE1       VIA   -     D0100PA00X+023993Y+054354               S3      
327P3V3_NODE1       VIA   -           A10X+024047Y+054917X0260Y0260R090 S1      
317NNAME10229       VIA   -     D0100PA00X+023678Y+054039               S3      
317NNAME10228       VIA   -     D0100PA00X+023678Y+053724               S3      
317NNAME10162       VIA   -     D0100PA00X+023048Y+053724               S3      
317NNAME10166       VIA   -     D0100PA00X+023048Y+054354               S3      
317NNAME10164       VIA   -     D0100PA00X+023048Y+054039               S3      
317NNAME10165       VIA   -     D0100PA00X+023363Y+054039               S3      
317NNAME10163       VIA   -     D0100PA00X+023678Y+054354               S3      
317NNAME10227       VIA   -     D0100PA00X+023363Y+053724               S3      
317NNAME10063       VIA   -     D0100PA00X+023993Y+053724               S3      
327N/C              U14   -AA5        A01X+022891Y+055142X0145Y0145R270 S2      
327N/C              U14   -AA4        A01X+022891Y+055457X0145Y0145R270 S2      
327N/C              U14   -AA3        A01X+022891Y+055772X0145Y0145R270 S2      
327N/C              U14   -AA2        A01X+022891Y+056086X0145Y0145R270 S2      
327N/C              U14   -AA1        A01X+022891Y+056401X0145Y0145R270 S2      
327N/C              U14   -Y5         A01X+023205Y+055142X0145Y0145R270 S2      
327N/C              U14   -Y4         A01X+023205Y+055457X0145Y0145R270 S2      
327N/C              U14   -Y3         A01X+023205Y+055772X0145Y0145R270 S2      
327N/C              U14   -Y2         A01X+023205Y+056086X0145Y0145R270 S2      
327N/C              U14   -Y1         A01X+023205Y+056401X0145Y0145R270 S2      
327N/C              U14   -W5         A01X+023520Y+055142X0145Y0145R270 S2      
327N/C              U14   -W4         A01X+023520Y+055457X0145Y0145R270 S2      
327N/C              U14   -W3         A01X+023520Y+055772X0145Y0145R270 S2      
327N/C              U14   -W2         A01X+023520Y+056086X0145Y0145R270 S2      
327N/C              U14   -W1         A01X+023520Y+056401X0145Y0145R270 S2      
327N/C              U14   -V5         A01X+023835Y+055142X0145Y0145R270 S2      
327N/C              U14   -V4         A01X+023835Y+055457X0145Y0145R270 S2      
327N/C              U14   -V3         A01X+023835Y+055772X0145Y0145R270 S2      
327N/C              U14   -V2         A01X+023835Y+056086X0145Y0145R270 S2      
327N/C              U14   -V1         A01X+023835Y+056401X0145Y0145R270 S2      
327N/C              U14   -U5         A01X+024150Y+055142X0145Y0145R270 S2      
327N/C              U14   -U4         A01X+024150Y+055457X0145Y0145R270 S2      
327N/C              U14   -U3         A01X+024150Y+055772X0145Y0145R270 S2      
327NNAME10361       U14   -U2         A01X+024150Y+056086X0145Y0145R270 S2      
327N/C              U14   -U1         A01X+024150Y+056401X0145Y0145R270 S2      
327NNAME10029       VIA   -           A10X+024283Y+056425X0260Y0260     S1      
317NNAME10426       VIA   -     D0100PA00X+024308Y+055928               S3      
317NNAME10362       VIA   -     D0100PA00X+024308Y+055298               S3      
317NNAME10361       VIA   -     D0100PA00X+023531Y+056636               S1      
327GND              R292  -2          A10X+024051Y+057803X0180Y0200R090 S1      
327NNAME10027       R292  -1          A10X+024051Y+057488X0180Y0200R090 S1      
327GND              R291  -2          A10X+023621Y+057803X0180Y0200R090 S1      
327NNAME10029       R291  -1          A10X+023621Y+057488X0180Y0200R090 S1      
327GND              R290  -2          A10X+023181Y+057803X0180Y0200R090 S1      
327NNAME10030       R290  -1          A10X+023181Y+057488X0180Y0200R090 S1      
317GND              VIA   -     D0100PA00X+023121Y+056628               S3      
317GND              VIA   -     D0100PA00X+024292Y+057654               S3      
327NNAME10030       VIA   -           A10X+023209Y+057050X0260Y0260     S1      
327NNAME10027       VIA   -           A10X+024193Y+057026X0260Y0260R090 S1      
317NNAME10043       VIA   -     D0100PA00X+024321Y+057402               S3      
327NNAME10426       C262  -1          A01X+023895Y+058363X0280Y0320R090 S2      
327GND              C262  -2          A01X+023315Y+058363X0280Y0320R090 S2      
327NNAME10426       R314  -1          A01X+023885Y+058933X0280Y0320R090 S2      
327P3V3_NODE1       R314  -2          A01X+023305Y+058933X0280Y0320R090 S2      
317GND              VIA   -     D0100PA00X+023927Y+059713               S3      
317GND              VIA   -     D0100PA00X+022981Y+058363               S3      
317LAN1_NVM_SO_R    VIA   -     D0100PA00X+022927Y+059768               S1      
317LAN1_NVM_WP_N    VIA   -     D0100PA00X+024283Y+059742               S1      
317P3V3_NODE1       VIA   -     D0100PA00X+023437Y+059324               S1      
317NNAME10426       VIA   -     D0100PA00X+024280Y+058975               S1      
327GND              U36   -4          A01X+023927Y+060263X0220Y0680     S2      
327LAN1_NVM_WP_N    U36   -3          A01X+023427Y+060263X0220Y0680     S2      
327LAN1_NVM_SO_R    U36   -2          A01X+022927Y+060263X0220Y0680     S2      
327NNAME10364       U36   -7          A01X+022927Y+062343X0220Y0680     S2      
327LAN1_NVM_SK_R    U36   -6          A01X+023427Y+062343X0220Y0680     S2      
327LAN1_NVM_SI_R    U36   -5          A01X+023927Y+062343X0220Y0680     S2      
317LAN1_NVM_SI_R    VIA   -     D0100PA00X+023678Y+062874               S1      
327LAN1_NVM_SI_R    R547  -2          A01X+022920Y+063594X0180Y0200R090 S2      
327NNAME10268       R547  -1          A01X+022920Y+063909X0180Y0200R090 S2      
327NNAME10427       Q36   -D          A01X+023807Y+063342X0320Y0360R180 S2      
327NNAME10428       Q36   -S          A01X+023433Y+064130X0320Y0360R180 S2      
327NNAME10429       Q36   -G          A01X+024181Y+064130X0320Y0360R180 S2      
317NNAME10268       VIA   -     D0100PA00X+022920Y+064218               S1      
317NNAME10427       VIA   -     D0100PA00X+024369Y+063225               S1      
317NNAME10429       VIA   -     D0100PA00X+023842Y+064215               S1      
317NNAME10428       VIA   -     D0100PA00X+023450Y+063769               S3      
317P5V_NODE1        VIA   -     D0100PA00X+024374Y+063651               S3      
327GND              C846  -2          A01X+022958Y+064935X0180Y0200R270 S2      
327NNAME10428       C846  -1          A01X+022958Y+064620X0180Y0200R270 S2      
327NNAME10428       R1236 -2          A01X+023745Y+064620X0180Y0200R090 S2      
327GND              R1236 -1          A01X+023745Y+064935X0180Y0200R090 S2      
327P3V3_STB_NODE1   R1109 -2          A01X+024167Y+064925X0180Y0200R270 S2      
327NNAME10429       R1109 -1          A01X+024167Y+064610X0180Y0200R270 S2      
327P3V3_STB_NODE1   R1108 -2          A01X+023358Y+064935X0180Y0200R270 S2      
327NNAME10428       R1108 -1          A01X+023358Y+064620X0180Y0200R270 S2      
317GND              VIA   -     D0100PA00X+022958Y+065267               S1      
317GND              VIA   -     D0100PA00X+023745Y+065276               S1      
317P3V3_STB_NODE1   VIA   -     D0100PA00X+024167Y+065256               S3      
317P3V3_STB_NODE1   VIA   -     D0100PA00X+023358Y+065252               S3      
327GND              C616  -2          A01X+023302Y+067167X0180Y0200     S2      
327P3V3_NODE1       C616  -1          A01X+023617Y+067167X0180Y0200     S2      
317GND              VIA   -     D0100PA00X+024360Y+067177               S1      
317GND              VIA   -     D0100PA00X+022990Y+067167               S1      
317P3V3_NODE1       VIA   -     D0100PA00X+023917Y+067167               S3      
327N/C              U86   -1          A01X+023447Y+068800X0180Y0520R180 S2      
327NNAME10323       U86   -2          A01X+023073Y+068800X0180Y0520R180 S2      
327P3V3_NODE1       U86   -5          A01X+023447Y+067836X0180Y0520R180 S2      
327GND              U88   -3          A01X+024049Y+068800X0180Y0520R180 S2      
327PSU2_DC_OK       U88   -4          A01X+024049Y+067836X0180Y0520R180 S2      
317PSU2_DC_OK       VIA   -     D0100PA00X+023728Y+067961               S1      
327N21700864        R686  -2          A10X+024135Y+070315X0180Y0200R180 S1      
327PSU_DC_OK_N      U95   -D          A01X+022994Y+069956X0400Y0500R180 S2      
327NNAME10323       U95   -G          A01X+023394Y+070836X0400Y0500R180 S2      
327PSU_DC_OK_N      U97   -D          A01X+024444Y+069956X0400Y0500R180 S2      
327GND              U97   -S          A01X+024044Y+070836X0400Y0500R180 S2      
317GND              VIA   -     D0100PA00X+024049Y+069268               S3      
327N21700864        VIA   -           A10X+023668Y+070067X0260Y0260     S1      
317PSU_DC_OK_N      VIA   -     D0100PA00X+023908Y+069625               S3      
317PSU_DC_OK_N      VIA   -     D0100PA00X+023395Y+069740               S3      
317PCA9535_INT_N    VIA   -     D0100PA00X+023612Y+070417               S3      
317GND              VIA   -     D0100PA00X+023835Y+071247               S3      
317NNAME10322       VIA   -     D0100PA00X+024268Y+071234               S1      
317NNAME10323       VIA   -     D0100PA00X+023496Y+071406               S1      
317NNAME10430       VIA   -     D0100PA00X+023921Y+072004               S3      
317NNAME10431       VIA   -     D0100PA00X+023491Y+072082               S1      
327GND              C679  -2          A10X+023944Y+073908X0180Y0200R270 S1      
327GND              C706  -2          A01X+023494Y+072758X0180Y0200R090 S2      
327NNAME10432       C706  -1          A01X+023494Y+073073X0180Y0200R090 S2      
327GND              C685  -2          A10X+023044Y+073908X0180Y0200R270 S1      
327GND              C703  -2          A01X+023944Y+073908X0180Y0200R090 S2      
327GND              C682  -2          A10X+023494Y+072758X0180Y0200R270 S1      
327NNAME10433       C682  -1          A10X+023494Y+073073X0180Y0200R270 S1      
327GND              C709  -2          A01X+023044Y+073908X0180Y0200R090 S2      
327NNAME10434       R916  -2          A10X+023944Y+073073X0180Y0200R090 S1      
327NNAME10430       R916  -1          A10X+023944Y+072758X0180Y0200R090 S1      
327NNAME10374       R922  -2          A10X+023044Y+073073X0180Y0200R090 S1      
327NNAME10431       R922  -1          A10X+023044Y+072758X0180Y0200R090 S1      
327NNAME10435       R940  -2          A01X+023944Y+073073X0180Y0200R270 S2      
327NNAME10436       R940  -1          A01X+023944Y+072758X0180Y0200R270 S2      
327NNAME10432       R943  -1          A01X+023494Y+073908X0180Y0200R270 S2      
327NNAME10375       R946  -2          A01X+023044Y+073073X0180Y0200R270 S2      
327NNAME10437       R946  -1          A01X+023044Y+072758X0180Y0200R270 S2      
327NNAME10433       R919  -1          A10X+023494Y+073908X0180Y0200R090 S1      
317GND              VIA   -     D0100PA00X+024390Y+072466               S3      
317GND              VIA   -     D0100PA00X+023944Y+073614               S3      
317GND              VIA   -     D0100PA00X+023044Y+073641               S3      
317GND              VIA   -     D0100PA00X+023494Y+072433               S3      
317NNAME10433       VIA   -     D0100PA00X+023494Y+073336               S3      
317NNAME10438       VIA   -     D0100PA00X+024394Y+073641               S3      
317NNAME10436       VIA   -     D0100PA00X+023950Y+073352               S3      
317NNAME10437       VIA   -     D0100PA00X+023044Y+072424               S3      
317NNAME10432       VIA   -     D0100PA00X+023494Y+073639               S3      
327NNAME10434       C679  -1          A10X+023944Y+074223X0180Y0200R270 S1      
327NNAME10374       C685  -1          A10X+023044Y+074223X0180Y0200R270 S1      
327NNAME10435       C703  -1          A01X+023944Y+074223X0180Y0200R090 S2      
327NNAME10375       C709  -1          A01X+023044Y+074223X0180Y0200R090 S2      
327NNAME10377       R943  -2          A01X+023494Y+074223X0180Y0200R270 S2      
327NNAME10376       R919  -2          A10X+023494Y+074223X0180Y0200R090 S1      
327NNAME10434       VIA   -           A10X+023847Y+077007X0260Y0260     S1      
317NNAME10435       VIA   -     D0100PA00X+023618Y+078652               S1      
317NNAME10439       VIA   -     D0100PA00X+024223Y+077480               S1      
327NNAME10376       VIA   -           A10X+023146Y+078017X0260Y0260     S1      
317NNAME10377       VIA   -     D0100PA00X+023401Y+077290               S1      
327NNAME10440       VIA   -           A10X+024008Y+077991X0260Y0260     S1      
327NNAME10434       J35   -A36        A10X+023234Y+080787X0300Y1660R180 S1      
327NNAME10440       J35   -A35        A10X+023628Y+080787X0300Y1660R180 S1      
327GND              J35   -A34        A10X+024022Y+080787X0300Y1660R180 S1      
327T1_NODE4_EN_R    J35   -A33        A10X+024415Y+080787X0300Y1660R180 S1      
327GND              J35   -B36        A01X+023234Y+080787X0300Y1660R180 S2      
327NNAME10435       J35   -B35        A01X+023628Y+080787X0300Y1660R180 S2      
327NNAME10439       J35   -B34        A01X+024022Y+080787X0300Y1660R180 S2      
327NNAME10441       J35   -B33        A01X+024415Y+080787X0300Y1660R180 S2      
317GND              VIA   -     D0100PA00X+024022Y+078870               S3      
317GND              VIA   -     D0100PA00X+024022Y+079170               S3      
317GND              VIA   -     D0100PA00X+023234Y+079170               S3      
317GND              VIA   -     D0100PA00X+023234Y+078870               S3      
317GND              VIA   -     D0100PA00X+024999Y+002122               S3      
317GND              VIA   -     D0100PA00X+024599Y+002122               S3      
317GND              VIA   -     D0100PA00X+025727Y+002933               S3      
317GND              VIA   -     D0100PA00X+025830Y+002229               S1      
317PV_VDDR_NODE1    VIA   -     D0100PA00X+025029Y+004550               S3      
317PV_VDDR_NODE1    VIA   -     D0100PA00X+024629Y+004550               S3      
327GND              PC78  -2          A01X+025351Y+006021X0180Y0200R270 S2      
327PV_VDDR_NODE1    PC78  -1          A01X+025351Y+005706X0180Y0200R270 S2      
327GND              PC81  -2          A01X+024731Y+006244X0440Y0540R270 S2      
327PV_VDDR_NODE1    PC81  -1          A01X+024731Y+005496X0440Y0540R270 S2      
317P5V_NODE1        VIA   -     D0100PA00X+025810Y+005369               S3      
317P5V_NODE1        VIA   -     D0100PA00X+025750Y+005612               S3      
317PV_VDDR_NODE1    VIA   -     D0100PA00X+024531Y+005087               S3      
317PV_VDDR_NODE1    VIA   -     D0100PA00X+024930Y+005086               S3      
317PV_VDDR_NODE1    VIA   -     D0100PA00X+025349Y+005374               S3      
317GND              VIA   -     D0100PA00X+025381Y+006324               S3      
317GND              VIA   -     D0100PA00X+024560Y+006632               S3      
317GND              VIA   -     D0100PA00X+024960Y+006632               S3      
327NNAME10442       J2    -77         A01X+025807Y+008248X0150Y0810     S2      
327NNAME10443       J2    -75         A01X+025571Y+008248X0150Y0810     S2      
327GND              J2    -73         A01X+025335Y+008248X0150Y0810     S2      
317GND              VIA   -     D0100PA00X+024607Y+009220               S3      
317GND              VIA   -     D0100PA00X+025657Y+009410               S3      
317GND              VIA   -     D0100PA00X+024787Y+010582               S3      
317NNAME10444       VIA   -     D0100PA00X+025268Y+010587               S1      
317NNAME10442       VIA   -     D0100PA00X+025356Y+009504               S1      
317PD_NODE1_DM8     VIA   -     D0100PA00X+025613Y+009935               S1      
317NNAME10443       VIA   -     D0100PA00X+024856Y+009504               S1      
327PV_VDDR_NODE1    C172  -1          A10X+025441Y+011758X0280Y0320R270 S1      
327PD_NODE1_DM8     R204  -2          A10X+025825Y+011060X0180Y0200     S1      
327GND              R204  -1          A10X+025510Y+011060X0180Y0200     S1      
327GND              J2    -78         A01X+025925Y+011476X0150Y0810     S2      
327PD_NODE1_DM8     J2    -76         A01X+025689Y+011476X0150Y0810     S2      
327NNAME10445       J2    -74         A01X+025453Y+011476X0150Y0810     S2      
317GND              VIA   -     D0100PA00X+025903Y+012373               S3      
317GND              VIA   -     D0100PA00X+025944Y+012077               S3      
317NNAME10445       VIA   -     D0100PA00X+024945Y+011431               S1      
327NNAME10338       VIA   -           A01X+025396Y+013593X0300Y0300     S2      
327NNAME10336       VIA   -           A01X+024718Y+016311X0300Y0300     S2      
327NNAME10395       VIA   -           A01X+025308Y+018226X0300Y0300     S2      
327PV_VDDR_NODE1    VIA   -           A10X+024497Y+017686X0260Y0260     S1      
327NNAME10394       VIA   -           A01X+025564Y+019277X0300Y0300     S2      
327PV_VDDR_NODE1    VIA   -           A10X+024600Y+019788X0260Y0260     S1      
317NNAME10446       VIA   -     D0100PA00X+025529Y+022671               S3      
317NNAME10447       VIA   -     D0100PA00X+025422Y+023058               S1      
317NNAME10448       VIA   -     D0100PA00X+025649Y+022247               S1      
317NNAME10449       VIA   -     D0100PA00X+025418Y+023452               S3      
327GND              C120  -2          A10X+025826Y+024590X0180Y0200R270 S1      
327PV_VDDR_NODE1    C120  -1          A10X+025826Y+024905X0180Y0200R270 S1      
327NNAME10393       R35   -2          A10X+024521Y+024223X0180Y0200     S1      
327NNAME10393       R34   -2          A10X+024521Y+024623X0180Y0200     S1      
327N29180194        R27   -2          A10X+025084Y+024693X0180Y0200R180 S1      
327PV_VDDR_NODE1    R27   -1          A10X+025399Y+024693X0180Y0200R180 S1      
327GND              R31   -2          A10X+025402Y+025112X0180Y0200     S1      
327N29180194        R31   -1          A10X+025087Y+025112X0180Y0200     S1      
327PV_VDDR_NODE1    U2    -BM45       A01X+025114Y+025021X0120Y0120     S2      
327NNAME10450       U2    -BP46       A01X+025215Y+024626X0100Y0135     S2      
327NNAME10451       U2    -BN46       A01X+025352Y+024866X0120Y0120     S2      
327NNAME10452       U2    -BN44       A01X+024947Y+024801X0120Y0120     S2      
327NNAME10453       U2    -BP43       A01X+024648Y+024626X0100Y0135     S2      
327PV_VDDR_NODE1    U2    -BM43       A01X+024628Y+024998X0120Y0120     S2      
327NNAME10454       U2    -BN41       A01X+024364Y+024822X0120Y0120     S2      
327NNAME10455       U2    -BP49       A01X+025855Y+024626X0100Y0135     S2      
327NNAME10456       U2    -BN48       A01X+025717Y+024866X0120Y0120     S2      
317NNAME10450       VIA   -     D0100PA00X+025795Y+023692               S3      
317NNAME10452       VIA   -     D0100PA00X+025442Y+024041               S1      
327NNAME10393       VIA   -           A10X+024412Y+025097X0200Y0040R270 S1      
327GND              C119  -2          A10X+025240Y+026216X0180Y0200R270 S1      
327PV_VDDR_NODE1    C119  -1          A10X+025240Y+026531X0180Y0200R270 S1      
327GND              C14   -2          A10X+025402Y+025512X0180Y0200     S1      
327N29180194        C14   -1          A10X+025087Y+025512X0180Y0200     S1      
327PV_VDDR_NODE1    R1040 -2          A10X+024463Y+026620X0180Y0200R090 S1      
327NNAME10457       R1040 -1          A10X+024463Y+026305X0180Y0200R090 S1      
327NNAME10448       U2    -BL46       A01X+025355Y+025157X0120Y0120     S2      
327NNAME10458       U2    -BL41       A01X+024385Y+025199X0120Y0120     S2      
327GND              U2    -BG46       A01X+025366Y+025920X0120Y0120     S2      
327NNAME10459       U2    -BG45       A01X+025090Y+025920X0120Y0120     S2      
327PV_VDDR_NODE1    U2    -BD45       A01X+025090Y+026520X0120Y0120     S2      
327NNAME10460       U2    -BF45       A01X+025090Y+026220X0120Y0120     S2      
327GND              U2    -BD46       A01X+025366Y+026520X0120Y0120     S2      
327GND              U2    -BF46       A01X+025366Y+026220X0120Y0120     S2      
327NNAME10449       U2    -BL44       A01X+024916Y+025216X0120Y0120     S2      
327NNAME10446       U2    -BK45       A01X+025126Y+025506X0120Y0120     S2      
327PV_VDDR_NODE1    U2    -BK44       A01X+024850Y+025487X0120Y0120     S2      
327PV_VDDR_NODE1    U2    -BK46       A01X+025393Y+025431X0120Y0120     S2      
327NNAME10447       U2    -BL43       A01X+024648Y+025298X0120Y0120     S2      
327NNAME10461       U2    -BG42       A01X+024584Y+026070X0120Y0120     S2      
327NNAME10457       U2    -BH42       A01X+024584Y+025770X0120Y0120     S2      
327PV_VDDR_NODE1    U2    -BE42       A01X+024584Y+026370X0120Y0120     S2      
327GND              U2    -BK42       A01X+024447Y+025487X0120Y0120     S2      
327NNAME10462       U2    -BL48       A01X+025705Y+025157X0120Y0120     S2      
327NNAME10442       U2    -BE49       A01X+025872Y+026370X0120Y0120     S2      
327NNAME10444       U2    -BH49       A01X+025872Y+025770X0120Y0120     S2      
327NNAME10443       U2    -BG49       A01X+025872Y+026070X0120Y0120     S2      
327GND              U2    -BK48       A01X+025669Y+025431X0120Y0120     S2      
317GND              VIA   -     D0100PA00X+025521Y+026064               S3      
317GND              VIA   -     D0100PA00X+025536Y+026656               S3      
317NNAME10457       VIA   -     D0100PA00X+024739Y+025914               S3      
317NNAME10444       VIA   -     D0100PA00X+025655Y+025688               S3      
317NNAME10460       VIA   -     D0100PA00X+024943Y+026370               S3      
317NNAME10459       VIA   -     D0100PA00X+024943Y+026070               S3      
317NNAME10442       VIA   -     D0100PA00X+025692Y+026261               S3      
317NNAME10461       VIA   -     D0100PA00X+024739Y+026214               S3      
327N29180194        VIA   -           A10X+024453Y+025871X0260Y0260     S1      
317NNAME10443       VIA   -     D0100PA00X+025725Y+025920               S3      
317PV_VDDR_NODE1    VIA   -     D0100PA00X+025952Y+025236               S3      
317PV_VDDR_NODE1    VIA   -     D0100PA00X+024943Y+025770               S3      
317PV_VDDR_NODE1    VIA   -     D0100PA00X+024647Y+025544               S3      
327GND              C124  -2          A10X+024695Y+027804X0180Y0200R270 S1      
327P1V05_NODE1      C124  -1          A10X+024695Y+028119X0180Y0200R270 S1      
327GND              C105  -2          A10X+025094Y+027799X0180Y0200R180 S1      
327P1V05_NODE1      C105  -1          A10X+025409Y+027799X0180Y0200R180 S1      
327GND              C132  -2          A10X+024863Y+027402X0180Y0200R090 S1      
327NNAME10397       C132  -1          A10X+024863Y+027087X0180Y0200R090 S1      
327GND              C131  -2          A10X+024448Y+027388X0180Y0200R090 S1      
327NNAME10397       C131  -1          A10X+024448Y+027073X0180Y0200R090 S1      
327NNAME10397       L10   -2          A10X+025226Y+027229X0180Y0200R090 S1      
327PV_VDDR_NODE1    L10   -1          A10X+025226Y+026914X0180Y0200R090 S1      
327P1V05_NODE1      U2    -AU42       A01X+024567Y+027952X0150Y0150     S2      
327P1V05_NODE1      U2    -AU44       A01X+024882Y+027952X0150Y0150     S2      
327P1V05_NODE1      U2    -AU46       A01X+025197Y+027952X0150Y0150     S2      
327P1V05_NODE1      U2    -AU47       A01X+025483Y+027952X0120Y0120     S2      
327P1V05_NODE1      U2    -AW47       A01X+025473Y+027677X0120Y0120     S2      
327P1V05_NODE1      U2    -AW46       A01X+025197Y+027677X0120Y0120     S2      
327GND              U2    -AW44       A01X+024882Y+027677X0120Y0120     S2      
327GND              U2    -AY45       A01X+025090Y+027420X0120Y0120     S2      
327GND              U2    -AY46       A01X+025366Y+027420X0120Y0120     S2      
327GND              U2    -BA46       A01X+025366Y+027120X0120Y0120     S2      
327GND              U2    -BA45       A01X+025090Y+027120X0120Y0120     S2      
327GND              U2    -BC45       A01X+025090Y+026820X0120Y0120     S2      
327GND              U2    -BC46       A01X+025366Y+026820X0120Y0120     S2      
327GND              U2    -AW42       A01X+024584Y+027570X0120Y0120     S2      
327GND              U2    -BB42       A01X+024584Y+026970X0120Y0120     S2      
327GND              U2    -BA42       A01X+024584Y+027270X0120Y0120     S2      
327NNAME10463       U2    -BD42       A01X+024584Y+026670X0120Y0120     S2      
327GND              U2    -AT48       A01X+025689Y+028188X0120Y0120     S2      
327GND              U2    -AW49       A01X+025872Y+027570X0120Y0120     S2      
327GND              U2    -BA49       A01X+025872Y+027270X0120Y0120     S2      
327NNAME10378       U2    -BB49       A01X+025872Y+026970X0120Y0120     S2      
327NNAME10380       U2    -BD49       A01X+025872Y+026670X0120Y0120     S2      
317GND              VIA   -     D0100PA00X+025705Y+027961               S3      
317GND              VIA   -     D0100PA00X+025521Y+027276               S3      
317GND              VIA   -     D0100PA00X+024411Y+027800               S3      
317P1V05_NODE1      VIA   -     D0100PA00X+024410Y+028110               S3      
317P1V05_NODE1      VIA   -     D0100PA00X+025423Y+028162               S3      
317P1V05_NODE1      VIA   -     D0100PA00X+025040Y+028110               S3      
317NNAME10463       VIA   -     D0100PA00X+024739Y+026814               S3      
317NNAME10378       VIA   -     D0100PA00X+025725Y+027120               S3      
317NNAME10380       VIA   -     D0100PA00X+025725Y+026820               S3      
327GND              C130  -2          A10X+025052Y+029401X0180Y0200     S1      
327P1V05_NODE1      C130  -1          A10X+024737Y+029401X0180Y0200     S1      
327GND              C106  -2          A10X+025610Y+029263X0180Y0200R090 S1      
327P1V05_NODE1      C106  -1          A10X+025610Y+028948X0180Y0200R090 S1      
327GND              C101  -2          A10X+025294Y+028440X0180Y0200R180 S1      
327P1V05_NODE1      C101  -1          A10X+025609Y+028440X0180Y0200R180 S1      
327GND              C122  -2          A10X+024702Y+028491X0180Y0200R270 S1      
327P1V05_NODE1      C122  -1          A10X+024702Y+028806X0180Y0200R270 S1      
327GND              U2    -AJ47       A01X+025529Y+029521X0120Y0120     S2      
327GND              U2    -AN47       A01X+025529Y+028694X0120Y0120     S2      
327GND              U2    -AT42       A01X+024567Y+028267X0150Y0150     S2      
327P1V05_NODE1      U2    -AP42       A01X+024567Y+028582X0150Y0150     S2      
327GND              U2    -AM42       A01X+024567Y+028897X0150Y0150     S2      
327P1V05_NODE1      U2    -AL42       A01X+024567Y+029212X0150Y0150     S2      
327GND              U2    -AJ42       A01X+024567Y+029527X0150Y0150     S2      
327GND              U2    -AT44       A01X+024882Y+028267X0150Y0150     S2      
327GND              U2    -AT46       A01X+025197Y+028267X0150Y0150     S2      
327P1V05_NODE1      U2    -AP44       A01X+024882Y+028582X0150Y0150     S2      
327GND              U2    -AM44       A01X+024882Y+028897X0150Y0150     S2      
327GND              U2    -AL44       A01X+024882Y+029212X0150Y0150     S2      
327P1V05_NODE1      U2    -AJ44       A01X+024882Y+029527X0150Y0150     S2      
327GND              U2    -AJ46       A01X+025197Y+029527X0150Y0150     S2      
327GND              U2    -AL46       A01X+025197Y+029212X0150Y0150     S2      
327GND              U2    -AM46       A01X+025197Y+028897X0150Y0150     S2      
327P1V05_NODE1      U2    -AP46       A01X+025197Y+028582X0150Y0150     S2      
327P1V05_NODE1      U2    -AR48       A01X+025689Y+028463X0120Y0120     S2      
327NNAME10464       U2    -AH48       A01X+025689Y+029752X0120Y0120     S2      
327P1V05_NODE1      U2    -AL49       A01X+025839Y+029245X0120Y0120     S2      
327GND              U2    -AM49       A01X+025839Y+028970X0120Y0120     S2      
327P1V05_NODE1      U2    -AL47       A01X+025563Y+029245X0120Y0120     S2      
327GND              U2    -AM47       A01X+025563Y+028970X0120Y0120     S2      
317GND              VIA   -     D0100PA00X+025040Y+029685               S3      
317GND              VIA   -     D0100PA00X+025361Y+029377               S3      
317GND              VIA   -     D0100PA00X+025040Y+029055               S3      
317GND              VIA   -     D0100PA00X+024410Y+028425               S3      
317GND              VIA   -     D0100PA00X+025040Y+028425               S3      
317GND              VIA   -     D0100PA00X+024410Y+029370               S3      
317P1V05_NODE1      VIA   -     D0100PA00X+024411Y+029051               S3      
317P1V05_NODE1      VIA   -     D0100PA00X+025745Y+028712               S3      
317P1V05_NODE1      VIA   -     D0100PA00X+024410Y+028740               S3      
317P1V05_NODE1      VIA   -     D0100PA00X+025040Y+028740               S3      
317P1V05_NODE1      VIA   -     D0100PA00X+025355Y+029055               S3      
317P1V05_NODE1      VIA   -     D0100PA00X+024725Y+029685               S3      
317P1V05_NODE1      VIA   -     D0100PA00X+024410Y+029685               S3      
317NNAME10464       VIA   -     D0100PA00X+025838Y+029598               S3      
327GND              C68   -2          A10X+024825Y+031010X0180Y0200R270 S1      
327PV_VCCP_NODE1    C68   -1          A10X+024825Y+031325X0180Y0200R270 S1      
327GND              C81   -2          A10X+025225Y+031010X0180Y0200R270 S1      
327PV_VCCP_NODE1    C81   -1          A10X+025225Y+031325X0180Y0200R270 S1      
327PV_VCCP_NODE1    C83   -1          A10X+024436Y+031265X0180Y0200R090 S1      
327GND              C47   -2          A10X+025045Y+029935X0180Y0200     S1      
327P1V05_NODE1      C47   -1          A10X+024730Y+029935X0180Y0200     S1      
327GND              U2    -AE47       A01X+025529Y+030258X0120Y0120     S2      
327GND              U2    -AA47       A01X+025529Y+031085X0120Y0120     S2      
327GND              U2    -AF42       A01X+024567Y+030157X0150Y0150     S2      
327NNAME10465       U2    -AG42       A01X+024567Y+029842X0150Y0150     S2      
327GND              U2    -AA42       A01X+024567Y+031102X0150Y0150     S2      
327NNAME10466       U2    -AC42       A01X+024567Y+030787X0150Y0150     S2      
327GND              U2    -AD42       A01X+024567Y+030472X0150Y0150     S2      
327GND              U2    -AF44       A01X+024882Y+030157X0150Y0150     S2      
327GND              U2    -AG44       A01X+024882Y+029842X0150Y0150     S2      
327GND              U2    -AG46       A01X+025197Y+029842X0150Y0150     S2      
327GND              U2    -AF46       A01X+025197Y+030157X0150Y0150     S2      
327PV_VCCP_NODE1    U2    -AA44       A01X+024882Y+031102X0150Y0150     S2      
327PV_VCCP_NODE1    U2    -AC44       A01X+024882Y+030787X0150Y0150     S2      
327GND              U2    -AD44       A01X+024882Y+030472X0150Y0150     S2      
327GND              U2    -AD46       A01X+025197Y+030472X0150Y0150     S2      
327GND              U2    -AC46       A01X+025197Y+030787X0150Y0150     S2      
327PV_VCCP_NODE1    U2    -AA46       A01X+025197Y+031102X0150Y0150     S2      
327NNAME10467       U2    -AG48       A01X+025689Y+030027X0120Y0120     S2      
327NNAME10468       U2    -AD49       A01X+025839Y+030534X0120Y0120     S2      
327NNAME10469       U2    -AC49       A01X+025839Y+030809X0120Y0120     S2      
327NNAME10470       U2    -AD47       A01X+025563Y+030534X0120Y0120     S2      
327NNAME10471       U2    -AC47       A01X+025563Y+030809X0120Y0120     S2      
327PV_VCCP_NODE1    U2    -Y48        A01X+025689Y+031316X0120Y0120     S2      
317GND              VIA   -     D0100PA00X+025433Y+029873               S3      
317GND              VIA   -     D0100PA00X+024725Y+030315               S3      
317GND              VIA   -     D0100PA00X+024412Y+030939               S3      
317NNAME10470       VIA   -     D0100PA00X+025401Y+030682               S3      
317NNAME10402       VIA   -     D0100PA00X+024412Y+030319               S3      
317NNAME10471       VIA   -     D0100PA00X+025706Y+030964               S3      
317NNAME10465       VIA   -     D0100PA00X+024410Y+030000               S3      
327NNAME10465       VIA   -           A10X+025698Y+029930X0260Y0260     S1      
327NNAME10466       VIA   -           A10X+025047Y+030580X0260Y0260     S1      
317NNAME10466       VIA   -     D0100PA00X+024725Y+030630               S3      
317NNAME10467       VIA   -     D0100PA00X+025742Y+030353               S3      
317PV_VCCP_NODE1    VIA   -     D0100PA00X+025859Y+031156               S3      
327GND              C66   -2          A10X+025622Y+031856X0180Y0200R090 S1      
327PV_VCCP_NODE1    C66   -1          A10X+025622Y+031541X0180Y0200R090 S1      
327GND              C77   -2          A10X+025123Y+032186X0180Y0200R270 S1      
327P1V8_SUS_NODE1   C77   -1          A10X+025123Y+032501X0180Y0200R270 S1      
327GND              C83   -2          A10X+024436Y+031580X0180Y0200R090 S1      
327P1V8_SUS_NODE1   C75   -1          A10X+024420Y+032620X0280Y0320R180 S1      
327GND              C75   -2          A10X+024420Y+032040X0280Y0320R180 S1      
327P3V3_RTC_NODE1   U2    -T44        A01X+024882Y+032008X0120Y0120     S2      
327GND              U2    -T45        A01X+025158Y+032008X0120Y0120     S2      
327P3V3_RTC_NODE1   U2    -M44        A01X+024996Y+032865X0120Y0120     S2      
327P3V3_RTC_NODE1   U2    -P44        A01X+024996Y+032565X0120Y0120     S2      
327P3V3_RTC_NODE1   U2    -R44        A01X+024996Y+032265X0120Y0120     S2      
327NNAME10472       U2    -M46        A01X+025272Y+032865X0120Y0120     S2      
327NNAME10473       U2    -P46        A01X+025272Y+032565X0120Y0120     S2      
327GND              U2    -R46        A01X+025272Y+032265X0120Y0120     S2      
327P3V3_SUS_NODE1   U2    -T42        A01X+024490Y+032115X0120Y0120     S2      
327P3V3_SUS_NODE1   U2    -N42        A01X+024490Y+032715X0120Y0120     S2      
327P3V3_SUS_NODE1   U2    -P42        A01X+024490Y+032415X0120Y0120     S2      
327GND              U2    -V42        A01X+024567Y+031732X0150Y0150     S2      
327P1V05_NODE1      U2    -W42        A01X+024567Y+031417X0150Y0150     S2      
327GND              U2    -V44        A01X+024882Y+031732X0150Y0150     S2      
327PV_VCCP_NODE1    U2    -W44        A01X+024882Y+031417X0150Y0150     S2      
327PV_VCCP_NODE1    U2    -W46        A01X+025197Y+031417X0150Y0150     S2      
327GND              U2    -V46        A01X+025197Y+031732X0150Y0150     S2      
327PV_VCCP_NODE1    U2    -W48        A01X+025689Y+031591X0120Y0120     S2      
327NNAME10474       U2    -T48        A01X+025778Y+032115X0120Y0120     S2      
327NNAME10474       U2    -P48        A01X+025778Y+032415X0120Y0120     S2      
327NNAME10475       U2    -N48        A01X+025778Y+032715X0120Y0120     S2      
327NNAME10474       U2    -T47        A01X+025512Y+032008X0120Y0120     S2      
317GND              VIA   -     D0100PA00X+024728Y+031573               S3      
317P3V3_NODE1       VIA   -     D0100PA00X+024729Y+032769               S3      
317NNAME10473       VIA   -     D0100PA00X+025463Y+032472               S3      
317NNAME10475       VIA   -     D0100PA00X+025500Y+032978               S3      
317NNAME10474       VIA   -     D0100PA00X+025628Y+032265               S3      
327P1V8_SUS_NODE1   VIA   -           A10X+025121Y+032965X0260Y0260     S1      
317P3V3_RTC_NODE1   VIA   -     D0100PA00X+024779Y+032291               S3      
317NNAME10472       VIA   -     D0100PA00X+025491Y+032721               S3      
317PV_VCCP_NODE1    VIA   -     D0100PA00X+025040Y+031571               S3      
317PV_VCCP_NODE1    VIA   -     D0100PA00X+025371Y+031567               S3      
327P1V8_SUS_NODE1   C74   -1          A10X+025172Y+033533X0280Y0320     S1      
327GND              C74   -2          A10X+025172Y+034113X0280Y0320     S1      
327GND              U2    -E41        A01X+024366Y+034198X0120Y0120     S2      
327GND              U2    -E43        A01X+024768Y+034198X0120Y0120     S2      
327GND              U2    -E45        A01X+025047Y+034205X0120Y0120     S2      
327NNAME10476       U2    -J44        A01X+024996Y+033465X0120Y0120     S2      
327GND              U2    -L44        A01X+024996Y+033165X0120Y0120     S2      
327GND              U2    -H44        A01X+024996Y+033765X0120Y0120     S2      
327NNAME10477       U2    -J46        A01X+025272Y+033465X0120Y0120     S2      
327GND              U2    -L46        A01X+025272Y+033165X0120Y0120     S2      
327NNAME10478       U2    -H46        A01X+025272Y+033765X0120Y0120     S2      
327NNAME10413       U2    -H42        A01X+024490Y+033615X0120Y0120     S2      
327GND              U2    -K42        A01X+024490Y+033315X0120Y0120     S2      
327P3V3_SUS_NODE1   U2    -L42        A01X+024490Y+033015X0120Y0120     S2      
327NNAME10479       U2    -G42        A01X+024490Y+033915X0120Y0120     S2      
327NNAME10480       U2    -D42        A01X+024567Y+034387X0120Y0120     S2      
327NNAME10481       U2    -D44        A01X+024830Y+034486X0120Y0120     S2      
327GND              U2    -E46        A01X+025320Y+034254X0120Y0120     S2      
327GND              U2    -L48        A01X+025778Y+033015X0120Y0120     S2      
327CPLD_ROW_LATCH   U2    -K48        A01X+025778Y+033315X0120Y0120     S2      
327NNAME10482       U2    -H48        A01X+025778Y+033615X0120Y0120     S2      
327GND              U2    -G48        A01X+025778Y+033915X0120Y0120     S2      
327N/C              U2    -E49        A01X+025862Y+034178X0120Y0120     S2      
327N/C              U2    -E48        A01X+025595Y+034254X0120Y0120     S2      
317GND              VIA   -     D0100PA00X+024851Y+033921               S3      
317GND              VIA   -     D0100PA00X+025482Y+033244               S3      
317GND              VIA   -     D0100PA00X+025047Y+034438               S3      
317GND              VIA   -     D0100PA00X+024569Y+034122               S3      
317GND              VIA   -     D0100PA00X+024722Y+033305               S3      
317GND              VIA   -     D0100PA00X+025501Y+033832               S3      
317NNAME10479       VIA   -     D0100PA00X+024669Y+033736               S3      
317NNAME10477       VIA   -     D0100PA00X+025512Y+033524               S3      
317P3V3_SUS_NODE1   VIA   -     D0100PA00X+024703Y+033051               S3      
327GND              U2    -A42        A01X+024567Y+035059X0100Y0135     S2      
327GND              U2    -A45        A01X+025133Y+035059X0100Y0135     S2      
327NNAME10483       U2    -C42        A01X+024587Y+034687X0120Y0120     S2      
327NNAME10484       U2    -B44        A01X+024851Y+034863X0120Y0120     S2      
327GND              U2    -B46        A01X+025271Y+034818X0120Y0120     S2      
327NNAME10485       U2    -C45        A01X+025043Y+034662X0120Y0120     S2      
327GND              U2    -D46        A01X+025283Y+034528X0120Y0120     S2      
327NNAME10486       U2    -A48        A01X+025773Y+035059X0100Y0135     S2      
327NNAME10487       U2    -B48        A01X+025636Y+034819X0120Y0120     S2      
327NNAME10488       U2    -C49        A01X+025874Y+034664X0120Y0120     S2      
327N/C              U2    -D48        A01X+025633Y+034528X0120Y0120     S2      
317GND              VIA   -     D0100PA00X+025133Y+035286               S3      
317GND              VIA   -     D0100PA00X+025944Y+035429               S3      
317GND              VIA   -     D0100PA00X+024627Y+035586               S3      
317NNAME10485       VIA   -     D0100PA00X+025149Y+035713               S1      
317NNAME10487       VIA   -     D0100PA00X+025659Y+035901               S3      
327NNAME10413       VIA   -           A10X+024641Y+034895X0260Y0260     S1      
327NNAME10407       VIA   -           A10X+024526Y+035847X0260Y0260     S1      
327NNAME10472       VIA   -           A10X+025882Y+034969X0260Y0260     S1      
327NNAME10413       R61   -2          A10X+024406Y+037715X0180Y0200     S1      
327NNAME10479       VIA   -           A10X+024941Y+036853X0260Y0260     S1      
317NNAME10480       VIA   -     D0100PA00X+024460Y+036354               S1      
327NNAME10487       VIA   -           A10X+025633Y+037101X0260Y0260     S1      
327NNAME10476       VIA   -           A01X+025625Y+036463X0300Y0300     S2      
327NNAME10475       VIA   -           A10X+025445Y+036499X0260Y0260     S1      
327NNAME10481       VIA   -           A01X+025723Y+037436X0300Y0300     S2      
327NNAME10477       VIA   -           A10X+025113Y+037372X0260Y0260     S1      
327NNAME10483       VIA   -           A01X+025186Y+037354X0300Y0300     S2      
327NNAME10489       C825  -1          A01X+025661Y+038796X0280Y0320R090 S2      
327P1V8_SUS_NODE1   C825  -2          A01X+025081Y+038796X0280Y0320R090 S2      
327P1V8_SUS_NODE1   R1093 -2          A01X+024578Y+038796X0180Y0200R180 S2      
327NNAME10424       R70   -2          A10X+024869Y+038893X0180Y0200R270 S1      
327P3V3_NODE1       R70   -1          A10X+024869Y+039208X0180Y0200R270 S1      
327NNAME10477       R66   -2          A10X+024869Y+037912X0180Y0200R270 S1      
327NNAME10424       R66   -1          A10X+024869Y+038227X0180Y0200R270 S1      
327NNAME10475       R88   -2          A10X+025269Y+037912X0180Y0200R270 S1      
327GND              R88   -1          A10X+025269Y+038227X0180Y0200R270 S1      
327NNAME10479       R63   -2          A10X+024475Y+038120X0180Y0200     S1      
327NNAME10418       R57   -2          A01X+024473Y+037917X0180Y0200R090 S2      
327NNAME10425       R57   -1          A01X+024473Y+038232X0180Y0200R090 S2      
327NNAME10415       R104  -2          A01X+024873Y+037917X0180Y0200R090 S2      
327GND              R104  -1          A01X+024873Y+038232X0180Y0200R090 S2      
327NNAME10490       R58   -2          A01X+025273Y+038232X0180Y0200R270 S2      
327NNAME10480       R58   -1          A01X+025273Y+037917X0180Y0200R270 S2      
327NNAME10487       R75   -2          A10X+025869Y+038890X0180Y0200R270 S1      
327P3V3_SUS_NODE1   R75   -1          A10X+025869Y+039205X0180Y0200R270 S1      
327NNAME10475       R86   -2          A10X+025669Y+037912X0180Y0200R270 S1      
327P3V3_NODE1       R86   -1          A10X+025669Y+038227X0180Y0200R270 S1      
327NNAME10483       R68   -2          A01X+025673Y+037917X0180Y0200R090 S2      
327P3V3_NODE1       R68   -1          A01X+025673Y+038232X0180Y0200R090 S2      
327NNAME10489       Q29   -4          A01X+025438Y+039246X0140Y0200     S2      
327P1V8_SUS_NODE1   Q29   -3          A01X+025182Y+039246X0140Y0200     S2      
327P1V8_SUS_NODE1   Q29   -2          A01X+024927Y+039246X0140Y0200     S2      
327P1V8_SUS_NODE1   Q29   -1          A01X+024671Y+039246X0140Y0200     S2      
317GND              VIA   -     D0100PA00X+025066Y+038478               S3      
317P3V3_NODE1       VIA   -     D0100PA00X+025653Y+038490               S3      
317P1V8_SUS_NODE1   VIA   -     D0100PA00X+024707Y+038540               S3      
317P1V8_SUS_NODE1   VIA   -     D0100PA00X+024455Y+038532               S3      
317NNAME10490       VIA   -     D0100PA00X+025376Y+038526               S3      
327P1V8_STB_NODE1   Q29   -5          A01X+025055Y+039798X1264Y0898     S2      
317P1V8_STB_NODE1   VIA   -     D0100PA00X+024780Y+040603               S3      
317P1V8_STB_NODE1   VIA   -     D0100PA00X+025030Y+040603               S3      
317P1V8_STB_NODE1   VIA   -     D0100PA00X+025280Y+040603               S3      
317P1V8_STB_NODE1   VIA   -     D0100PA00X+024530Y+040603               S3      
327P3V3_STB_NODE1   R1113 -2          A01X+025480Y+042093X0180Y0200R090 S2      
327NNAME10491       R1113 -1          A01X+025480Y+042408X0180Y0200R090 S2      
327P3V3_STB_NODE1   R1112 -2          A01X+025880Y+042093X0180Y0200R090 S2      
327NNAME10492       R1112 -1          A01X+025880Y+042408X0180Y0200R090 S2      
317GND              VIA   -     D0100PA00X+024420Y+041961               S3      
317GND              VIA   -     D0100PA00X+024420Y+041701               S3      
317P3V3_STB_NODE1   VIA   -     D0100PA00X+025880Y+041759               S3      
317P3V3_STB_NODE1   VIA   -     D0100PA00X+025480Y+041773               S3      
327NNAME10493       Q38   -D          A01X+025855Y+043832X0320Y0360     S2      
327NNAME10491       Q38   -G          A01X+025481Y+043045X0320Y0360     S2      
317GND              VIA   -     D0100PA00X+024420Y+042761               S3      
317GND              VIA   -     D0100PA00X+024420Y+042501               S3      
317GND              VIA   -     D0100PA00X+024420Y+043301               S3      
317GND              VIA   -     D0100PA00X+024420Y+043561               S3      
317NNAME10491       VIA   -     D0100PA00X+025481Y+042702               S1      
327NNAME10493       R1111 -2          A01X+025848Y+044359X0180Y0200R180 S2      
327P5V_STB_NODE1    R1111 -1          A01X+025533Y+044359X0180Y0200R180 S2      
317P5V_STB_NODE1    VIA   -     D0100PA00X+025267Y+044359               S3      
327BMC_ROMA4        R320  -2          A10X+025131Y+046608X0180Y0200R270 S1      
327P3V3_NODE1       R320  -1          A10X+025131Y+046923X0180Y0200R270 S1      
327BMC_ROMA18       R334  -2          A10X+025551Y+046598X0180Y0200R270 S1      
327P3V3_NODE1       R334  -1          A10X+025551Y+046913X0180Y0200R270 S1      
327BMC_ROMA10       R326  -2          A01X+025131Y+046608X0180Y0200R090 S2      
327P3V3_NODE1       R326  -1          A01X+025131Y+046923X0180Y0200R090 S2      
327BMC_ROMA22       R338  -2          A01X+025551Y+046598X0180Y0200R090 S2      
327P3V3_NODE1       R338  -1          A01X+025551Y+046913X0180Y0200R090 S2      
317BMC_ROMA10       VIA   -     D0100PA00X+024647Y+046489               S1      
317BMC_ROMA22       VIA   -     D0100PA00X+025178Y+046088               S1      
317BMC_ROMA15       VIA   -     D0100PA00X+025757Y+046151               S1      
327BMC_ROMA20       R336  -2          A01X+024611Y+047813X0180Y0200R270 S2      
327P3V3_NODE1       R336  -1          A01X+024611Y+047498X0180Y0200R270 S2      
327BMC_ROMA5        R321  -2          A10X+025131Y+047813X0180Y0200R090 S1      
327P3V3_NODE1       R321  -1          A10X+025131Y+047498X0180Y0200R090 S1      
327BMC_ROMA21       R337  -2          A10X+025551Y+047813X0180Y0200R090 S1      
327P3V3_NODE1       R337  -1          A10X+025551Y+047498X0180Y0200R090 S1      
327BMC_ROMA15       R331  -2          A01X+025551Y+047813X0180Y0200R270 S2      
327P3V3_NODE1       R331  -1          A01X+025551Y+047498X0180Y0200R270 S2      
327BMC_ROMA11       R327  -2          A01X+025131Y+047813X0180Y0200R270 S2      
327P3V3_NODE1       R327  -1          A01X+025131Y+047498X0180Y0200R270 S2      
327BMC_ROMA0        R316  -2          A10X+024609Y+047818X0180Y0200R090 S1      
327P3V3_NODE1       R316  -1          A10X+024609Y+047503X0180Y0200R090 S1      
317P3V3_NODE1       VIA   -     D0100PA00X+025551Y+047225               S3      
317P3V3_NODE1       VIA   -     D0100PA00X+024611Y+047247               S3      
317P3V3_NODE1       VIA   -     D0100PA00X+025131Y+047255               S3      
327BMC_ROMA20       VIA   -           A01X+024972Y+048321X0300Y0300     S2      
327BMC_ROMA7        VIA   -           A01X+024439Y+048376X0300Y0300     S2      
327BMC_ROMA11       VIA   -           A01X+025506Y+048364X0300Y0300     S2      
327BMC_ROMA5        VIA   -           A10X+024651Y+048675X0260Y0260     S1      
327BMC_ROMA17       VIA   -           A10X+025500Y+048576X0260Y0260     S1      
327BMC_ROMD0        U14   -T22        A01X+024465Y+049787X0145Y0145R270 S2      
327BMC_ROMD1        U14   -T21        A01X+024465Y+050102X0145Y0145R270 S2      
327BMC_ROMA2        U14   -R22        A01X+024780Y+049787X0145Y0145R270 S2      
327BMC_ROMA1        U14   -R21        A01X+024780Y+050102X0145Y0145R270 S2      
327BMC_ROMA7        U14   -P22        A01X+025095Y+049787X0145Y0145R270 S2      
327BMC_ROMA6        U14   -P21        A01X+025095Y+050102X0145Y0145R270 S2      
327BMC_ROMA20       U14   -N22        A01X+025410Y+049787X0145Y0145R270 S2      
327N/C              U14   -N21        A01X+025410Y+050102X0145Y0145R270 S2      
327BMC_ROMA11       U14   -M22        A01X+025725Y+049787X0145Y0145R270 S2      
327BMC_ROMA10       U14   -M21        A01X+025725Y+050102X0145Y0145R270 S2      
327BMC_ROMA21       VIA   -           A10X+025032Y+049347X0260Y0260     S1      
317BMC_ROMA21       VIA   -     D0100PA00X+025252Y+050259               S3      
327BMC_ROMA8        VIA   -           A10X+025681Y+049615X0260Y0260R090 S1      
327BMC_ROMA4        VIA   -           A10X+024451Y+049135X0260Y0260R090 S1      
327BMC_ROMA9        VIA   -           A10X+025481Y+049115X0260Y0260R090 S1      
317BMC_ROMA9        VIA   -     D0100PA00X+025567Y+050259               S3      
317BMC_ROMA5        VIA   -     D0100PA00X+024937Y+050259               S3      
327BMC_ROMA18       VIA   -           A10X+024861Y+049835X0260Y0260R090 S1      
317BMC_ROMA0        VIA   -     D0100PA00X+024622Y+050259               S3      
327BMC_ROMD2        U14   -T20        A01X+024465Y+050417X0145Y0145R270 S2      
327N/C              U14   -T19        A01X+024465Y+050732X0145Y0145R270 S2      
327BMC_ROMA16       U14   -T18        A01X+024465Y+051047X0145Y0145R270 S2      
327BMC_ROMA0        U14   -R20        A01X+024780Y+050417X0145Y0145R270 S2      
327N/C              U14   -R19        A01X+024780Y+050732X0145Y0145R270 S2      
327N/C              U14   -R18        A01X+024780Y+051047X0145Y0145R270 S2      
327NNAME10317       U14   -R17        A01X+024780Y+051362X0145Y0145R270 S2      
327BMC_ROMA5        U14   -P20        A01X+025095Y+050417X0145Y0145R270 S2      
327BMC_ROMA4        U14   -P19        A01X+025095Y+050732X0145Y0145R270 S2      
327BMC_ROMA3        U14   -P18        A01X+025095Y+051047X0145Y0145R270 S2      
327NNAME10317       U14   -P17        A01X+025095Y+051362X0145Y0145R270 S2      
327BMC_ROMA21       U14   -N20        A01X+025410Y+050417X0145Y0145R270 S2      
327BMC_ROMA18       U14   -N19        A01X+025410Y+050732X0145Y0145R270 S2      
327BMC_ROMA17       U14   -N18        A01X+025410Y+051047X0145Y0145R270 S2      
327P3V3_NODE1       U14   -N17        A01X+025410Y+051362X0145Y0145R270 S2      
327BMC_ROMA9        U14   -M20        A01X+025725Y+050417X0145Y0145R270 S2      
327BMC_ROMA8        U14   -M19        A01X+025725Y+050732X0145Y0145R270 S2      
327BMC_ROMA19       U14   -M18        A01X+025725Y+051047X0145Y0145R270 S2      
327P3V3_NODE1       U14   -M17        A01X+025725Y+051362X0145Y0145R270 S2      
327P3V3_NODE1       C253  -1          A10X+025505Y+051634X0180Y0200R090 S1      
327NNAME10317       C293  -1          A10X+025021Y+051678X0180Y0200R090 S1      
327P3V3_NODE1       C254  -1          A10X+025900Y+051636X0180Y0200R090 S1      
327BMC_ROMA12       R328  -2          A10X+025875Y+050942X0180Y0200R270 S1      
327P3V3_NODE1       R328  -1          A10X+025875Y+051257X0180Y0200R270 S1      
317GND              VIA   -     D0100PA00X+024561Y+051718               S3      
317P3V3_NODE1       VIA   -     D0100PA00X+025567Y+051204               S3      
317P3V3_NODE1       VIA   -     D0100PA00X+025252Y+051204               S3      
317BMC_ROMA19       VIA   -     D0100PA00X+025567Y+050889               S3      
317BMC_ROMA8        VIA   -     D0100PA00X+025567Y+050574               S3      
317BMC_ROMA4        VIA   -     D0100PA00X+024937Y+050574               S3      
317BMC_ROMA3        VIA   -     D0100PA00X+024937Y+050889               S3      
317BMC_ROMA18       VIA   -     D0100PA00X+025252Y+050574               S3      
317BMC_ROMA17       VIA   -     D0100PA00X+025252Y+050889               S3      
317NNAME10317       VIA   -     D0100PA00X+024937Y+051204               S3      
317NNAME10317       VIA   -     D0100PA00X+024622Y+051204               S3      
327GND              U14   -P14        A01X+025095Y+052307X0145Y0145R270 S2      
327GND              U14   -P13        A01X+025095Y+052622X0145Y0145R270 S2      
327GND              U14   -P12        A01X+025095Y+052937X0145Y0145R270 S2      
327GND              U14   -P11        A01X+025095Y+053252X0145Y0145R270 S2      
327GND              U14   -N14        A01X+025410Y+052307X0145Y0145R270 S2      
327GND              U14   -N13        A01X+025410Y+052622X0145Y0145R270 S2      
327GND              U14   -N12        A01X+025410Y+052937X0145Y0145R270 S2      
327GND              U14   -N11        A01X+025410Y+053252X0145Y0145R270 S2      
327GND              U14   -M14        A01X+025725Y+052307X0145Y0145R270 S2      
327GND              U14   -M13        A01X+025725Y+052622X0145Y0145R270 S2      
327GND              U14   -M12        A01X+025725Y+052937X0145Y0145R270 S2      
327GND              U14   -M11        A01X+025725Y+053252X0145Y0145R270 S2      
327GND              C289  -2          A10X+024638Y+052774X0180Y0200     S1      
327GND              C273  -1          A10X+024639Y+051971X0180Y0200R180 S1      
327GND              C275  -1          A10X+024638Y+052373X0180Y0200R180 S1      
327GND              C272  -2          A10X+024643Y+053178X0180Y0200     S1      
327GND              C253  -2          A10X+025505Y+051949X0180Y0200R090 S1      
327GND              C293  -2          A10X+025021Y+051993X0180Y0200R090 S1      
327GND              C254  -2          A10X+025900Y+051951X0180Y0200R090 S1      
317GND              VIA   -     D0100PA00X+025252Y+052779               S3      
317GND              VIA   -     D0100PA00X+025252Y+052464               S3      
317GND              VIA   -     D0100PA00X+025567Y+053409               S3      
317GND              VIA   -     D0100PA00X+025252Y+053409               S3      
317GND              VIA   -     D0100PA00X+024937Y+053409               S3      
317GND              VIA   -     D0100PA00X+025567Y+052464               S3      
317GND              VIA   -     D0100PA00X+025567Y+052779               S3      
317GND              VIA   -     D0100PA00X+024937Y+052779               S3      
317GND              VIA   -     D0100PA00X+024937Y+052464               S3      
327GND              VIA   -           A10X+025897Y+052646X0260Y0260R090 S1      
327NNAME10317       U14   -R6         A01X+024780Y+054827X0145Y0145R270 S2      
327GND              U14   -P10        A01X+025095Y+053567X0145Y0145R270 S2      
327GND              U14   -P9         A01X+025095Y+053882X0145Y0145R270 S2      
327NNAME10317       U14   -P6         A01X+025095Y+054827X0145Y0145R270 S2      
327GND              U14   -N10        A01X+025410Y+053567X0145Y0145R270 S2      
327GND              U14   -N9         A01X+025410Y+053882X0145Y0145R270 S2      
327P3V3_NODE1       U14   -N6         A01X+025410Y+054827X0145Y0145R270 S2      
327GND              U14   -M10        A01X+025725Y+053567X0145Y0145R270 S2      
327GND              U14   -M9         A01X+025725Y+053882X0145Y0145R270 S2      
327P3V3_NODE1       U14   -M6         A01X+025725Y+054827X0145Y0145R270 S2      
327GND              C274  -2          A10X+024642Y+053579X0180Y0200     S1      
327GND              C244  -2          A10X+024553Y+054396X0180Y0200     S1      
327GND              C280  -2          A10X+024657Y+053979X0180Y0200     S1      
327GND              C250  -2          A10X+025329Y+054691X0180Y0200R180 S1      
327P3V3_NODE1       C250  -1          A10X+025644Y+054691X0180Y0200R180 S1      
327GND              C251  -2          A10X+025327Y+054289X0180Y0200R180 S1      
327P3V3_NODE1       C251  -1          A10X+025642Y+054289X0180Y0200R180 S1      
327GND              C287  -2          A10X+024937Y+054393X0180Y0200R270 S1      
327NNAME10317       C287  -1          A10X+024937Y+054708X0180Y0200R270 S1      
317GND              VIA   -     D0100PA00X+025567Y+053724               S3      
317GND              VIA   -     D0100PA00X+024937Y+053724               S3      
317GND              VIA   -     D0100PA00X+025252Y+053724               S3      
317GND              VIA   -     D0100PA00X+025567Y+054039               S3      
317GND              VIA   -     D0100PA00X+024937Y+054039               S3      
317GND              VIA   -     D0100PA00X+025252Y+054039               S3      
317P3V3_NODE1       VIA   -     D0100PA00X+025252Y+054984               S3      
317P3V3_NODE1       VIA   -     D0100PA00X+025567Y+054984               S3      
317NNAME10317       VIA   -     D0100PA00X+024937Y+054984               S3      
327N/C              U14   -T5         A01X+024465Y+055142X0145Y0145R270 S2      
327NNAME10362       U14   -T4         A01X+024465Y+055457X0145Y0145R270 S2      
327NNAME10426       U14   -T3         A01X+024465Y+055772X0145Y0145R270 S2      
327NNAME10043       U14   -T2         A01X+024465Y+056086X0145Y0145R270 S2      
327NNAME10042       U14   -T1         A01X+024465Y+056401X0145Y0145R270 S2      
327GND              U14   -R5         A01X+024780Y+055142X0145Y0145R270 S2      
327NNAME10030       U14   -R4         A01X+024780Y+055457X0145Y0145R270 S2      
327NNAME10029       U14   -R3         A01X+024780Y+055772X0145Y0145R270 S2      
327NNAME10027       U14   -R2         A01X+024780Y+056086X0145Y0145R270 S2      
327NNAME10363       U14   -R1         A01X+024780Y+056401X0145Y0145R270 S2      
327GND              U14   -P5         A01X+025095Y+055142X0145Y0145R270 S2      
327GND              U14   -P4         A01X+025095Y+055457X0145Y0145R270 S2      
327NNAME10494       U14   -P3         A01X+025095Y+055772X0145Y0145R270 S2      
327NNAME10495       U14   -P2         A01X+025095Y+056086X0145Y0145R270 S2      
327NNAME10426       U14   -P1         A01X+025095Y+056401X0145Y0145R270 S2      
327GND              U14   -N5         A01X+025410Y+055142X0145Y0145R270 S2      
327GND              U14   -N4         A01X+025410Y+055457X0145Y0145R270 S2      
327GND              U14   -N3         A01X+025410Y+055772X0145Y0145R270 S2      
327GND              U14   -N2         A01X+025410Y+056086X0145Y0145R270 S2      
327GND              U14   -N1         A01X+025410Y+056401X0145Y0145R270 S2      
327GND              U14   -M5         A01X+025725Y+055142X0145Y0145R270 S2      
327GND              U14   -M4         A01X+025725Y+055457X0145Y0145R270 S2      
327GND              U14   -M3         A01X+025725Y+055772X0145Y0145R270 S2      
327GND              U14   -M2         A01X+025725Y+056086X0145Y0145R270 S2      
327GND              U14   -M1         A01X+025725Y+056401X0145Y0145R270 S2      
327GND              C242  -2          A10X+025181Y+055593X0180Y0200R090 S1      
327P3V3_NODE1       C242  -1          A10X+025181Y+055278X0180Y0200R090 S1      
327GND              C294  -2          A10X+024621Y+055373X0180Y0200R090 S1      
327NNAME10317       C294  -1          A10X+024621Y+055058X0180Y0200R090 S1      
327GND              C258  -2          A10X+025324Y+056185X0180Y0200     S1      
327NNAME10494       C258  -1          A10X+025009Y+056185X0180Y0200     S1      
327GND              C257  -2          A10X+025324Y+056615X0180Y0200     S1      
327NNAME10494       C257  -1          A10X+025009Y+056615X0180Y0200     S1      
317GND              VIA   -     D0100PA00X+025567Y+056558               S3      
317GND              VIA   -     D0100PA00X+025567Y+055298               S3      
317GND              VIA   -     D0100PA00X+025567Y+055613               S3      
317GND              VIA   -     D0100PA00X+025567Y+055928               S3      
317GND              VIA   -     D0100PA00X+025567Y+056243               S3      
317GND              VIA   -     D0100PA00X+024934Y+055298               S3      
317GND              VIA   -     D0100PA00X+024934Y+055613               S3      
317NNAME10029       VIA   -     D0100PA00X+024622Y+055928               S3      
317NNAME10030       VIA   -     D0100PA00X+024622Y+055613               S3      
317NNAME10027       VIA   -     D0100PA00X+024622Y+056243               S3      
317NNAME10494       VIA   -     D0100PA00X+025255Y+055931               S3      
327NNAME10494       L14   -1          A10X+025011Y+057211X0280Y0320     S1      
327P3V3_NODE1       L14   -2          A10X+025011Y+057791X0280Y0320     S1      
317P3V3_NODE1       VIA   -     D0100PA00X+025204Y+058213               S3      
317NNAME10042       VIA   -     D0100PA00X+024586Y+057505               S3      
317NNAME10426       VIA   -     D0100PA00X+024991Y+056865               S3      
327NNAME10494       VIA   -           A10X+025571Y+057438X0260Y0260     S1      
317NNAME10495       VIA   -     D0100PA00X+025968Y+058155               S1      
327GND              C264  -2          A01X+024682Y+058316X0180Y0200R180 S2      
327NNAME10426       C264  -1          A01X+024367Y+058316X0180Y0200R180 S2      
327GND              C263  -2          A01X+024682Y+058716X0180Y0200R180 S2      
327NNAME10426       C263  -1          A01X+024367Y+058716X0180Y0200R180 S2      
327P3V3_NODE1       R555  -2          A01X+024935Y+059638X0180Y0200R180 S2      
327LAN1_NVM_WP_N    R555  -1          A01X+024620Y+059638X0180Y0200R180 S2      
327NNAME10495       R313  -2          A01X+025711Y+058298X0180Y0200R090 S2      
327GND              R313  -1          A01X+025711Y+058613X0180Y0200R090 S2      
317GND              VIA   -     D0100PA00X+024954Y+058716               S3      
317GND              VIA   -     D0100PA00X+025371Y+058613               S3      
317GND              VIA   -     D0100PA00X+024954Y+058316               S3      
317P3V3_NODE1       VIA   -     D0100PA00X+025319Y+059638               S3      
327GND              PC5   -2          A01X+025068Y+060806X0440Y0540     S2      
327P5V_STB_NODE1    PC5   -1          A01X+025816Y+060806X0440Y0540     S2      
327GND              PC7   -2          A01X+025380Y+060226X0180Y0200     S2      
327P5V_STB_NODE1    PC7   -1          A01X+025695Y+060226X0180Y0200     S2      
317GND              VIA   -     D0100PA00X+024664Y+060838               S3      
317GND              VIA   -     D0100PA00X+024664Y+060578               S3      
317GND              VIA   -     D0100PA00X+024964Y+060252               S3      
327GND              PC132 -2          A01X+025070Y+062372X0440Y0540     S2      
327P5V_STB_NODE1    PC132 -1          A01X+025818Y+062372X0440Y0540     S2      
327GND              PC6   -2          A01X+025068Y+061587X0440Y0540     S2      
327P5V_STB_NODE1    PC6   -1          A01X+025816Y+061587X0440Y0540     S2      
317GND              VIA   -     D0100PA00X+024664Y+062438               S3      
317GND              VIA   -     D0100PA00X+024664Y+062178               S3      
317GND              VIA   -     D0100PA00X+024664Y+061638               S3      
317GND              VIA   -     D0100PA00X+024664Y+061378               S3      
317P12V_AUX         VIA   -     D0100PA00X+024901Y+062851               S3      
327P5V_NODE1        C845  -2          A01X+025224Y+064044X0440Y0540R270 S2      
327NNAME10427       C845  -1          A01X+025224Y+063296X0440Y0540R270 S2      
327NNAME10427       R1107 -2          A01X+024631Y+063276X0180Y0200R270 S2      
327P12V_AUX         R1107 -1          A01X+024631Y+062961X0180Y0200R270 S2      
327NNAME10427       Q35   -4          A01X+025886Y+063299X0140Y0200R270 S2      
327P5V_NODE1        Q35   -3          A01X+025886Y+063555X0140Y0200R270 S2      
327P5V_NODE1        Q35   -2          A01X+025886Y+063811X0140Y0200R270 S2      
327P5V_NODE1        Q35   -1          A01X+025886Y+064067X0140Y0200R270 S2      
317P5V_NODE1        VIA   -     D0100PA00X+025180Y+063670               S3      
317P5V_NODE1        VIA   -     D0100PA00X+025477Y+064442               S3      
317P5V_NODE1        VIA   -     D0100PA00X+025430Y+063674               S3      
317P5V_NODE1        VIA   -     D0100PA00X+025646Y+063936               S3      
317P5V_NODE1        VIA   -     D0100PA00X+025217Y+064434               S3      
317P5V_NODE1        VIA   -     D0100PA00X+024908Y+063666               S3      
317P5V_NODE1        VIA   -     D0100PA00X+025651Y+064249               S3      
317P5V_NODE1        VIA   -     D0100PA00X+024655Y+063668               S3      
327P5V_NODE1        R1110 -2          A01X+024629Y+064523X0180Y0200R090 S2      
327GND              R1110 -1          A01X+024629Y+064838X0180Y0200R090 S2      
317GND              VIA   -     D0100PA00X+024946Y+064838               S1      
327GND              C619  -2          A01X+024648Y+067177X0180Y0200     S2      
327P3V3_NODE1       C619  -1          A01X+024963Y+067177X0180Y0200     S2      
317GND              VIA   -     D0100PA00X+025727Y+067177               S1      
317P3V3_NODE1       VIA   -     D0100PA00X+025249Y+067177               S3      
327N/C              U88   -1          A01X+024797Y+068800X0180Y0520R180 S2      
327NNAME10322       U88   -2          A01X+024423Y+068800X0180Y0520R180 S2      
327P3V3_NODE1       U88   -5          A01X+024797Y+067836X0180Y0520R180 S2      
327NNAME10321       U84   -2          A01X+025773Y+068800X0180Y0520R180 S2      
327GND              U84   -3          A01X+025399Y+068800X0180Y0520R180 S2      
327PSU1_DC_OK       U84   -4          A01X+025399Y+067836X0180Y0520R180 S2      
317GND              VIA   -     D0100PA00X+025340Y+069236               S3      
317PSU1_DC_OK       VIA   -     D0100PA00X+024478Y+068252               S1      
327P3V3_NODE1       R686  -1          A10X+024450Y+070315X0180Y0200R180 S1      
327PSU_DC_OK_N      R1014 -2          A01X+025899Y+069395X0180Y0200R180 S2      
327GND              R1014 -1          A01X+025584Y+069395X0180Y0200R180 S2      
327NNAME10322       U97   -G          A01X+024844Y+070836X0400Y0500R180 S2      
327PSU_DC_OK_N      U94   -D          A01X+025894Y+069956X0400Y0500R180 S2      
327GND              U94   -S          A01X+025494Y+070836X0400Y0500R180 S2      
317P3V3_NODE1       VIA   -     D0100PA00X+025080Y+070315               S3      
317PSU_DC_OK_N      VIA   -     D0100PA00X+025145Y+069747               S3      
317T1_NODE2_EN      VIA   -     D0100PA00X+025917Y+070514               S1      
317GND              VIA   -     D0100PA00X+025494Y+071238               S3      
317T2_NODE4_EN      VIA   -     D0100PA00X+025857Y+072298               S1      
317T1_NODE3_EN      VIA   -     D0100PA00X+025531Y+071592               S3      
317NNAME10496       VIA   -     D0100PA00X+024853Y+072183               S3      
317NNAME10370       VIA   -     D0100PA00X+025063Y+071946               S3      
327GND              C631  -2          A10X+024844Y+073908X0180Y0200R270 S1      
327GND              C643  -2          A01X+025744Y+073908X0180Y0200R090 S2      
327GND              C676  -2          A10X+024394Y+072758X0180Y0200R270 S1      
327NNAME10496       C676  -1          A10X+024394Y+073073X0180Y0200R270 S1      
327GND              C694  -2          A01X+025294Y+072758X0180Y0200R090 S2      
327NNAME10497       C694  -1          A01X+025294Y+073073X0180Y0200R090 S2      
327GND              C700  -2          A01X+024394Y+072758X0180Y0200R090 S2      
327NNAME10438       C700  -1          A01X+024394Y+073073X0180Y0200R090 S2      
327GND              C625  -2          A10X+025744Y+073908X0180Y0200R270 S1      
327GND              C697  -2          A01X+024844Y+073908X0180Y0200R090 S2      
327GND              C628  -2          A10X+025294Y+073908X0180Y0200R270 S1      
327T1_NODE2_EN_R    R862  -2          A10X+025744Y+073073X0180Y0200R090 S1      
327T1_NODE2_EN      R862  -1          A10X+025744Y+072758X0180Y0200R090 S1      
327NNAME10441       R934  -2          A01X+024844Y+073073X0180Y0200R270 S2      
327NNAME10498       R934  -1          A01X+024844Y+072758X0180Y0200R270 S2      
327NNAME10496       R913  -1          A10X+024394Y+073908X0180Y0200R090 S1      
327NNAME10497       R931  -1          A01X+025294Y+073908X0180Y0200R270 S2      
327T1_NODE3_EN_R    R865  -2          A10X+025294Y+073073X0180Y0200R090 S1      
327T1_NODE3_EN      R865  -1          A10X+025294Y+072758X0180Y0200R090 S1      
327T1_NODE4_EN_R    R868  -2          A10X+024844Y+073073X0180Y0200R090 S1      
327T1_NODE4_EN      R868  -1          A10X+024844Y+072758X0180Y0200R090 S1      
327T2_NODE4_EN_R    R880  -2          A01X+025744Y+073073X0180Y0200R270 S2      
327T2_NODE4_EN      R880  -1          A01X+025744Y+072758X0180Y0200R270 S2      
327NNAME10438       R937  -1          A01X+024394Y+073908X0180Y0200R270 S2      
317GND              VIA   -     D0100PA00X+025334Y+072473               S3      
317GND              VIA   -     D0100PA00X+024844Y+073616               S3      
317GND              VIA   -     D0100PA00X+025744Y+073604               S3      
317GND              VIA   -     D0100PA00X+025294Y+073632               S3      
317T1_NODE4_EN      VIA   -     D0100PA00X+024877Y+072463               S3      
317NNAME10497       VIA   -     D0100PA00X+025294Y+073357               S3      
327T1_NODE4_EN_R    C631  -1          A10X+024844Y+074223X0180Y0200R270 S1      
327T2_NODE4_EN_R    C643  -1          A01X+025744Y+074223X0180Y0200R090 S2      
327T1_NODE2_EN_R    C625  -1          A10X+025744Y+074223X0180Y0200R270 S1      
327NNAME10441       C697  -1          A01X+024844Y+074223X0180Y0200R090 S2      
327T1_NODE3_EN_R    C628  -1          A10X+025294Y+074223X0180Y0200R270 S1      
327NNAME10440       R913  -2          A10X+024394Y+074223X0180Y0200R090 S1      
327NNAME10499       R931  -2          A01X+025294Y+074223X0180Y0200R270 S2      
327NNAME10439       R937  -2          A01X+024394Y+074223X0180Y0200R270 S2      
327T1_NODE3_EN_R    VIA   -           A10X+024919Y+076976X0260Y0260     S1      
327T1_NODE2_EN_R    VIA   -           A10X+025665Y+077064X0260Y0260     S1      
317T2_NODE4_EN_R    VIA   -     D0100PA00X+025665Y+077834               S1      
317NNAME10441       VIA   -     D0100PA00X+024790Y+077882               S1      
317NNAME10499       VIA   -     D0100PA00X+025247Y+078580               S1      
327T1_NODE4_EN_R    VIA   -           A10X+024491Y+078578X0260Y0260     S1      
327T1_NODE3_EN_R    J35   -A32        A10X+024809Y+080787X0300Y1660R180 S1      
327T1_NODE2_EN_R    J35   -A31        A10X+025203Y+080787X0300Y1660R180 S1      
327T1_NODE1_EN_R    J35   -A30        A10X+025597Y+080787X0300Y1660R180 S1      
327GND              J35   -A29        A10X+025990Y+080787X0300Y1660R180 S1      
327NNAME10499       J35   -B32        A01X+024809Y+080787X0300Y1660R180 S2      
327GND              J35   -B31        A01X+025203Y+080590X0300Y1260R180 S2      
327T2_NODE4_EN_R    J35   -B30        A01X+025597Y+080787X0300Y1660R180 S2      
327T2_NODE3_EN_R    J35   -B29        A01X+025990Y+080787X0300Y1660R180 S2      
317GND              VIA   -     D0100PA00X+025203Y+079170               S3      
327NNAME10500       PR18  -2          A01X+026742Y+001317X0180Y0200R270 S2      
327NNAME10501       PR18  -1          A01X+026742Y+001002X0180Y0200R270 S2      
327GND              PR19  -2          A01X+027142Y+001002X0180Y0200R090 S2      
327NNAME10500       PR19  -1          A01X+027142Y+001317X0180Y0200R090 S2      
327NNAME10502       PJ5   -2          A01X+027497Y+001387X0180Y0200R270 S2      
327NNAME10503       PJ5   -1          A01X+027497Y+001072X0200Y0400R180 S2      
317GND              VIA   -     D0100PA00X+027142Y+000732               S1      
317NNAME10501       VIA   -     D0100PA00X+026296Y+001266               S1      
327GND              PU5   -TH         A01X+027597Y+002538X0670Y0670R090 S2      
327P3V3_NODE1       PU5   -16         A01X+027302Y+003119X0100Y0330     S2      
327NNAME10500       PU5   -5          A01X+027302Y+001957X0100Y0330     S2      
327GND              PU5   -4          A01X+027017Y+002243X0100Y0330R090 S2      
327P3V3_NODE1_SS    PU5   -3          A01X+027017Y+002440X0100Y0330R090 S2      
327NNAME10501       PU5   -2          A01X+027017Y+002636X0100Y0330R090 S2      
327P3V3_NODE1_FB    PU5   -1          A01X+027017Y+002833X0100Y0330R090 S2      
327GND              PC51  -2          A01X+026011Y+002493X0180Y0200     S2      
327NNAME10501       PC51  -1          A01X+026326Y+002493X0180Y0200     S2      
327P3V3_NODE1_SS    PC52  -2          A01X+026329Y+001969X0180Y0200R270 S2      
327GND              PC52  -1          A01X+026329Y+001654X0180Y0200R270 S2      
327GND              PR21  -2          A01X+025967Y+002923X0180Y0200     S2      
327P3V3_NODE1_FB    PR21  -1          A01X+026282Y+002923X0180Y0200     S2      
317GND              VIA   -     D0100PA00X+027366Y+002304               S3      
317GND              VIA   -     D0100PA00X+026858Y+001937               S3      
317GND              VIA   -     D0100PA00X+026593Y+001652               S3      
317GND              VIA   -     D0100PA00X+027365Y+002771               S3      
317P3V3_NODE1_FB    VIA   -     D0100PA00X+026611Y+002923               S1      
317P3V3_NODE1_SS    VIA   -     D0100PA00X+026579Y+002099               S1      
317NNAME10500       VIA   -     D0100PA00X+026881Y+001640               S1      
317NNAME10502       VIA   -     D0100PA00X+027499Y+001640               S1      
327P3V3_NODE1       PC53  -2          A01X+026335Y+003347X0180Y0200R180 S2      
327P3V3_NODE1_FB    PC53  -1          A01X+026020Y+003347X0180Y0200R180 S2      
327GND              PC46  -2          A01X+026848Y+003745X0180Y0200     S2      
327P5V_STB_NODE1    PC46  -1          A01X+027163Y+003745X0180Y0200     S2      
327P3V3_NODE1       PR20  -2          A01X+026335Y+003743X0180Y0200R180 S2      
327P3V3_NODE1_FB    PR20  -1          A01X+026020Y+003743X0180Y0200R180 S2      
317GND              VIA   -     D0100PA00X+026837Y+004078               S3      
317GND              VIA   -     D0100PA00X+026587Y+004078               S3      
317P5V_STB_NODE1    VIA   -     D0100PA00X+027201Y+004055               S3      
317P5V_STB_NODE1    VIA   -     D0100PA00X+027451Y+004055               S3      
327GND              C164  -2          A01X+026799Y+006803X0180Y0200R090 S2      
327PV_VDDR_NODE1    C164  -1          A01X+026799Y+007118X0180Y0200R090 S2      
327GND              C161  -2          A01X+027199Y+006803X0180Y0200R090 S2      
327PV_VDDR_NODE1    C161  -1          A01X+027199Y+007118X0180Y0200R090 S2      
317GND              VIA   -     D0100PA00X+027387Y+006317               S3      
317GND              VIA   -     D0100PA00X+026979Y+006317               S3      
317GND              VIA   -     D0100PA00X+026175Y+007589               S3      
317PV_VDDR_NODE1    VIA   -     D0100PA00X+027458Y+007428               S3      
317PV_VDDR_NODE1    VIA   -     D0100PA00X+026992Y+007432               S3      
317PV_VDDR_NODE1    VIA   -     D0100PA00X+027244Y+007618               S3      
317PV_VDDR_NODE1    VIA   -     D0100PA00X+026808Y+007642               S3      
327GND              C155  -2          A10X+027134Y+008490X0180Y0200R090 S1      
327PV_VDDR_NODE1    C155  -1          A10X+027134Y+008175X0180Y0200R090 S1      
327NNAME10339       J2    -91         A01X+027461Y+008248X0150Y0810     S2      
327NNAME10446       J2    -89         A01X+027225Y+008248X0150Y0810     S2      
327NNAME10448       J2    -87         A01X+026988Y+008248X0150Y0810     S2      
327PV_VDDR_NODE1    J2    -85         A01X+026752Y+008248X0150Y0810     S2      
327NNAME10504       J2    -83         A01X+026516Y+008248X0150Y0810     S2      
327NNAME10505       J2    -81         A01X+026280Y+008248X0150Y0810     S2      
327GND              J2    -79         A01X+026043Y+008248X0150Y0810     S2      
317GND              VIA   -     D0100PA00X+026770Y+008940               S3      
317NNAME10446       VIA   -     D0100PA00X+027225Y+008959               S1      
317NNAME10504       VIA   -     D0100PA00X+026370Y+009385               S1      
317NNAME10448       VIA   -     D0100PA00X+027113Y+009279               S3      
327GND              C170  -2          A10X+026963Y+010029X0180Y0200R270 S1      
327PV_VDDR_NODE1    C170  -1          A10X+026963Y+010344X0180Y0200R270 S1      
317GND              VIA   -     D0100PA00X+026583Y+010257               S3      
317GND              VIA   -     D0100PA00X+026421Y+009691               S3      
317NNAME10333       VIA   -     D0100PA00X+027397Y+009765               S3      
317NNAME10506       VIA   -     D0100PA00X+026247Y+010694               S1      
317NNAME10505       VIA   -     D0100PA00X+026368Y+009990               S3      
317PV_VDDR_NODE1    VIA   -     D0100PA00X+026870Y+010793               S3      
327GND              C142  -2          A10X+026495Y+011415X0180Y0200R270 S1      
327NNAME10507       C142  -1          A10X+026495Y+011730X0180Y0200R270 S1      
327GND              C194  -2          A10X+027295Y+011415X0180Y0200R270 S1      
327NNAME10507       C194  -1          A10X+027295Y+011730X0180Y0200R270 S1      
327GND              C172  -2          A10X+026021Y+011758X0280Y0320R270 S1      
327GND              R203  -2          A10X+026895Y+011415X0180Y0200R270 S1      
327NNAME10507       R203  -1          A10X+026895Y+011730X0180Y0200R270 S1      
327NNAME10336       J2    -90         A01X+027343Y+011476X0150Y0810     S2      
327NNAME10338       J2    -88         A01X+027106Y+011476X0150Y0810     S2      
327PV_VDDR_NODE1    J2    -86         A01X+026870Y+011476X0150Y0810     S2      
327NNAME10507       J2    -84         A01X+026634Y+011476X0150Y0810     S2      
327NNAME10506       J2    -82         A01X+026398Y+011476X0150Y0810     S2      
327NNAME10444       J2    -80         A01X+026162Y+011476X0150Y0810     S2      
317NNAME10507       VIA   -     D0100PA00X+026901Y+012165               S3      
317NNAME10507       VIA   -     D0100PA00X+026498Y+012189               S1      
327NNAME10384       VIA   -           A01X+026707Y+014501X0300Y0300     S2      
327PV_VDDR_NODE1    VIA   -           A10X+026499Y+020568X0260Y0260     S1      
327GND              C114  -2          A10X+026213Y+024589X0180Y0200R270 S1      
327PV_VDDR_NODE1    C114  -1          A10X+026213Y+024904X0180Y0200R270 S1      
327NNAME10508       U2    -BM54       A01X+026887Y+025021X0120Y0120     S2      
327GND              U2    -BP55       A01X+026988Y+024626X0100Y0135     S2      
327NNAME10509       U2    -BN55       A01X+027125Y+024866X0120Y0120     S2      
327NNAME10510       U2    -BN53       A01X+026720Y+024801X0120Y0120     S2      
327PV_VDDR_NODE1    U2    -BM49       A01X+025946Y+025022X0120Y0120     S2      
327NNAME10511       U2    -BM52       A01X+026401Y+024998X0120Y0120     S2      
327GND              U2    -BP52       A01X+026421Y+024626X0100Y0135     S2      
327GND              U2    -BN50       A01X+026137Y+024822X0120Y0120     S2      
317GND              VIA   -     D0100PA00X+026962Y+024324               S3      
317NNAME10512       VIA   -     D0100PA00X+026919Y+024821               S3      
317NNAME10509       VIA   -     D0100PA00X+027224Y+024484               S3      
317NNAME10513       VIA   -     D0100PA00X+027262Y+023865               S3      
317NNAME10451       VIA   -     D0100PA00X+026011Y+024038               S1      
317NNAME10510       VIA   -     D0100PA00X+026712Y+024559               S1      
317NNAME10514       VIA   -     D0100PA00X+027146Y+024135               S3      
317NNAME10511       VIA   -     D0100PA00X+027026Y+023704               S1      
317NNAME10515       VIA   -     D0100PA00X+026619Y+024985               S3      
327NNAME10512       U2    -BL55       A01X+027128Y+025157X0120Y0120     S2      
327GND              U2    -BL50       A01X+026158Y+025199X0120Y0120     S2      
327NNAME10516       U2    -BH57       A01X+027436Y+025770X0120Y0120     S2      
327GND              U2    -BG53       A01X+026654Y+025920X0120Y0120     S2      
327GND              U2    -BD53       A01X+026654Y+026520X0120Y0120     S2      
327GND              U2    -BF53       A01X+026654Y+026220X0120Y0120     S2      
327GND              U2    -BG54       A01X+026930Y+025920X0120Y0120     S2      
327GND              U2    -BG57       A01X+027436Y+026070X0120Y0120     S2      
327NNAME10517       U2    -BE57       A01X+027436Y+026370X0120Y0120     S2      
327GND              U2    -BD54       A01X+026930Y+026520X0120Y0120     S2      
327GND              U2    -BF54       A01X+026930Y+026220X0120Y0120     S2      
327GND              U2    -BK56       A01X+027166Y+025431X0120Y0120     S2      
327GND              U2    -BK53       A01X+026622Y+025487X0120Y0120     S2      
327GND              U2    -BK54       A01X+026899Y+025506X0120Y0120     S2      
327NNAME10515       U2    -BL53       A01X+026689Y+025216X0120Y0120     S2      
327GND              U2    -BK57       A01X+027441Y+025431X0120Y0120     S2      
327GND              U2    -BH50       A01X+026148Y+025770X0120Y0120     S2      
327NNAME10379       U2    -BG50       A01X+026148Y+026070X0120Y0120     S2      
327GND              U2    -BE50       A01X+026148Y+026370X0120Y0120     S2      
327NNAME10506       U2    -BK49       A01X+025942Y+025480X0120Y0120     S2      
327NNAME10505       U2    -BK51       A01X+026220Y+025487X0120Y0120     S2      
327GND              U2    -BL52       A01X+026421Y+025298X0120Y0120     S2      
317GND              VIA   -     D0100PA00X+026702Y+025708               S3      
317GND              VIA   -     D0100PA00X+026303Y+025914               S3      
317GND              VIA   -     D0100PA00X+026507Y+026670               S3      
317GND              VIA   -     D0100PA00X+026303Y+026514               S3      
317GND              VIA   -     D0100PA00X+027181Y+025669               S3      
317GND              VIA   -     D0100PA00X+027190Y+026317               S3      
317NNAME10517       VIA   -     D0100PA00X+027352Y+026585               S1      
317NNAME10506       VIA   -     D0100PA00X+026007Y+026219               S3      
317NNAME10379       VIA   -     D0100PA00X+026327Y+026237               S3      
317NNAME10505       VIA   -     D0100PA00X+026377Y+025646               S1      
317NNAME10516       VIA   -     D0100PA00X+027246Y+025996               S1      
317NNAME10508       VIA   -     D0100PA00X+026926Y+025280               S3      
327GND              C115  -2          A10X+026014Y+027562X0180Y0200R090 S1      
327PV_VDDR_NODE1    C115  -1          A10X+026014Y+027247X0180Y0200R090 S1      
327GND              U2    -BB56       A01X+027189Y+026899X0120Y0120     S2      
327GND              U2    -BB54       A01X+026889Y+026899X0120Y0120     S2      
327GND              U2    -BB53       A01X+026589Y+026899X0120Y0120     S2      
327GND              U2    -AY52       A01X+026439Y+027406X0120Y0120     S2      
327GND              U2    -AW52       A01X+026439Y+027681X0120Y0120     S2      
327GND              U2    -AY53       A01X+026739Y+027406X0120Y0120     S2      
327GND              U2    -AY55       A01X+027039Y+027406X0120Y0120     S2      
327GND              U2    -AY56       A01X+027339Y+027406X0120Y0120     S2      
327GND              U2    -AW53       A01X+026739Y+027681X0120Y0120     S2      
327GND              U2    -AW55       A01X+027039Y+027681X0120Y0120     S2      
327NNAME10518       U2    -AW56       A01X+027339Y+027681X0120Y0120     S2      
327GND              U2    -AT51       A01X+026289Y+028188X0120Y0120     S2      
327GND              U2    -AT50       A01X+025989Y+028188X0120Y0120     S2      
327NNAME10519       U2    -AT53       A01X+026589Y+028188X0120Y0120     S2      
327NNAME10520       U2    -AT54       A01X+026889Y+028188X0120Y0120     S2      
327GND              U2    -AT56       A01X+027189Y+028188X0120Y0120     S2      
327GND              U2    -AW50       A01X+026148Y+027570X0120Y0120     S2      
327GND              U2    -BB50       A01X+026148Y+026970X0120Y0120     S2      
327NNAME10445       U2    -BA50       A01X+026148Y+027270X0120Y0120     S2      
327NNAME10504       U2    -BD50       A01X+026148Y+026670X0120Y0120     S2      
317GND              VIA   -     D0100PA00X+027194Y+027836               S3      
317GND              VIA   -     D0100PA00X+026439Y+028041               S3      
317GND              VIA   -     D0100PA00X+026594Y+027836               S3      
317GND              VIA   -     D0100PA00X+027489Y+027259               S3      
317GND              VIA   -     D0100PA00X+027339Y+028041               S3      
317GND              VIA   -     D0100PA00X+027044Y+027054               S3      
317GND              VIA   -     D0100PA00X+027189Y+027259               S3      
317GND              VIA   -     D0100PA00X+026589Y+027172               S3      
317GND              VIA   -     D0100PA00X+026889Y+027259               S3      
317GND              VIA   -     D0100PA00X+026894Y+027836               S3      
327NNAME10397       VIA   -           A10X+026102Y+028066X0260Y0260     S1      
317NNAME10445       VIA   -     D0100PA00X+026303Y+027114               S3      
317NNAME10504       VIA   -     D0100PA00X+026303Y+026814               S3      
317NNAME10521       VIA   -     D0100PA00X+027344Y+027054               S3      
317NNAME10518       VIA   -     D0100PA00X+027494Y+027836               S3      
317NNAME10520       VIA   -     D0100PA00X+027039Y+028041               S3      
317NNAME10519       VIA   -     D0100PA00X+026739Y+028041               S3      
327GND              U2    -AR51       A01X+026289Y+028463X0120Y0120     S2      
327P1V05_NODE1      U2    -AR50       A01X+025989Y+028463X0120Y0120     S2      
327GND              U2    -AM50       A01X+026139Y+028970X0120Y0120     S2      
327GND              U2    -AL50       A01X+026139Y+029245X0120Y0120     S2      
327GND              U2    -AH51       A01X+026289Y+029752X0120Y0120     S2      
327NNAME10522       U2    -AL52       A01X+026439Y+029245X0120Y0120     S2      
327NNAME10523       U2    -AM52       A01X+026439Y+028970X0120Y0120     S2      
327NNAME10524       U2    -AH50       A01X+025989Y+029752X0120Y0120     S2      
327NNAME10525       U2    -AR53       A01X+026589Y+028463X0120Y0120     S2      
327NNAME10526       U2    -AR54       A01X+026889Y+028463X0120Y0120     S2      
327GND              U2    -AR56       A01X+027189Y+028463X0120Y0120     S2      
327N/C              U2    -AH54       A01X+026889Y+029752X0120Y0120     S2      
327NNAME10527       U2    -AH53       A01X+026589Y+029752X0120Y0120     S2      
327GND              U2    -AL55       A01X+027039Y+029245X0120Y0120     S2      
327GND              U2    -AM55       A01X+027039Y+028970X0120Y0120     S2      
327NNAME10528       U2    -AM53       A01X+026739Y+028970X0120Y0120     S2      
327NNAME10529       U2    -AL53       A01X+026739Y+029245X0120Y0120     S2      
327GND              U2    -AH56       A01X+027189Y+029752X0120Y0120     S2      
327N/C              U2    -AL56       A01X+027339Y+029245X0120Y0120     S2      
327NNAME10530       U2    -AM56       A01X+027339Y+028970X0120Y0120     S2      
317GND              VIA   -     D0100PA00X+026289Y+028823               S3      
317GND              VIA   -     D0100PA00X+026439Y+029605               S3      
317NNAME10527       VIA   -     D0100PA00X+026739Y+029605               S3      
317NNAME10524       VIA   -     D0100PA00X+026146Y+029611               S1      
317NNAME10522       VIA   -     D0100PA00X+026583Y+029399               S3      
317NNAME10529       VIA   -     D0100PA00X+026887Y+029394               S3      
317NNAME10526       VIA   -     D0100PA00X+027044Y+028618               S1      
317NNAME10523       VIA   -     D0100PA00X+026290Y+029385               S3      
317NNAME10528       VIA   -     D0100PA00X+026894Y+029109               S3      
317NNAME10525       VIA   -     D0100PA00X+026577Y+028755               S3      
317NNAME10531       VIA   -     D0100PA00X+027344Y+028618               S3      
317NNAME10530       VIA   -     D0100PA00X+027362Y+029539               S3      
327GND              R101  -2          A10X+026309Y+030699X0180Y0200     S1      
327NNAME10471       R101  -1          A10X+025994Y+030699X0180Y0200     S1      
327GND              U2    -AG51       A01X+026289Y+030027X0120Y0120     S2      
327NNAME10532       U2    -AG50       A01X+025989Y+030027X0120Y0120     S2      
327GND              U2    -AC50       A01X+026139Y+030809X0120Y0120     S2      
327GND              U2    -AD50       A01X+026139Y+030534X0120Y0120     S2      
327NNAME10533       U2    -AD52       A01X+026439Y+030534X0120Y0120     S2      
327NNAME10534       U2    -AC52       A01X+026439Y+030809X0120Y0120     S2      
327NNAME10535       U2    -AG54       A01X+026889Y+030027X0120Y0120     S2      
327N/C              U2    -AG53       A01X+026589Y+030027X0120Y0120     S2      
327GND              U2    -AG56       A01X+027189Y+030027X0120Y0120     S2      
327NNAME10536       U2    -AC53       A01X+026739Y+030809X0120Y0120     S2      
327NNAME10537       U2    -AD53       A01X+026739Y+030534X0120Y0120     S2      
327GND              U2    -AD55       A01X+027039Y+030534X0120Y0120     S2      
327GND              U2    -AC55       A01X+027039Y+030809X0120Y0120     S2      
327NNAME10538       U2    -AD56       A01X+027339Y+030534X0120Y0120     S2      
327NNAME10539       U2    -AC56       A01X+027339Y+030809X0120Y0120     S2      
327GND              U2    -Y51        A01X+026289Y+031316X0120Y0120     S2      
327PV_VCCP_NODE1    U2    -Y50        A01X+025989Y+031316X0120Y0120     S2      
327PV_VCCP_NODE1    U2    -Y53        A01X+026589Y+031316X0120Y0120     S2      
327PV_VCCP_NODE1    U2    -Y54        A01X+026889Y+031316X0120Y0120     S2      
327GND              U2    -Y56        A01X+027189Y+031316X0120Y0120     S2      
317GND              VIA   -     D0100PA00X+027181Y+030331               S3      
317GND              VIA   -     D0100PA00X+027194Y+030964               S3      
317GND              VIA   -     D0100PA00X+026294Y+030964               S3      
317GND              VIA   -     D0100PA00X+026139Y+031169               S3      
317NNAME10469       VIA   -     D0100PA00X+026005Y+030962               S3      
317NNAME10536       VIA   -     D0100PA00X+026894Y+030964               S3      
327NNAME10471       VIA   -           A10X+026830Y+030699X0260Y0260     S1      
317NNAME10534       VIA   -     D0100PA00X+026594Y+030964               S3      
317NNAME10532       VIA   -     D0100PA00X+026192Y+030203               S1      
317NNAME10535       VIA   -     D0100PA00X+026938Y+030274               S3      
317NNAME10533       VIA   -     D0100PA00X+026450Y+030311               S3      
317NNAME10537       VIA   -     D0100PA00X+026694Y+030328               S3      
317NNAME10538       VIA   -     D0100PA00X+027430Y+030341               S3      
317NNAME10468       VIA   -     D0100PA00X+025982Y+030380               S3      
317PV_VCCP_NODE1    VIA   -     D0100PA00X+026727Y+031164               S3      
317PV_VCCP_NODE1    VIA   -     D0100PA00X+026429Y+031169               S3      
317PV_VCCP_NODE1    VIA   -     D0100PA00X+027052Y+031164               S3      
317NNAME10539       VIA   -     D0100PA00X+027483Y+030969               S3      
327GND              C67   -2          A10X+027222Y+031856X0180Y0200R090 S1      
327PV_VCCP_NODE1    C67   -1          A10X+027222Y+031541X0180Y0200R090 S1      
327GND              C65   -2          A10X+026422Y+031856X0180Y0200R090 S1      
327PV_VCCP_NODE1    C65   -1          A10X+026422Y+031541X0180Y0200R090 S1      
327GND              C64   -2          A10X+026022Y+031856X0180Y0200R090 S1      
327PV_VCCP_NODE1    C64   -1          A10X+026022Y+031541X0180Y0200R090 S1      
327GND              C84   -2          A10X+026822Y+031856X0180Y0200R090 S1      
327PV_VCCP_NODE1    C84   -1          A10X+026822Y+031541X0180Y0200R090 S1      
327GND              U2    -W51        A01X+026289Y+031591X0120Y0120     S2      
327PV_VCCP_NODE1    U2    -W50        A01X+025989Y+031591X0120Y0120     S2      
327PV_VCCP_NODE1    U2    -W53        A01X+026589Y+031591X0120Y0120     S2      
327PV_VCCP_NODE1    U2    -W54        A01X+026889Y+031591X0120Y0120     S2      
327GND              U2    -W56        A01X+027189Y+031591X0120Y0120     S2      
327NNAME10540       U2    -T52        A01X+026439Y+032098X0120Y0120     S2      
327GND              U2    -R52        A01X+026439Y+032373X0120Y0120     S2      
327GND              U2    -T55        A01X+027039Y+032098X0120Y0120     S2      
327NNAME10541       U2    -T53        A01X+026739Y+032098X0120Y0120     S2      
327NNAME10269       U2    -T56        A01X+027339Y+032098X0120Y0120     S2      
327GND              U2    -R55        A01X+027039Y+032373X0120Y0120     S2      
327NNAME10542       U2    -R56        A01X+027339Y+032373X0120Y0120     S2      
327GND              U2    -R53        A01X+026739Y+032373X0120Y0120     S2      
327NNAME10543       U2    -M56        A01X+027189Y+032880X0120Y0120     S2      
327NNAME10544       U2    -M52        A01X+026560Y+032865X0120Y0120     S2      
327NNAME10545       U2    -M54        A01X+026889Y+032880X0120Y0120R270 S2      
327GND              U2    -T50        A01X+026054Y+032115X0120Y0120     S2      
327NNAME10026       U2    -P50        A01X+026054Y+032415X0120Y0120     S2      
327N/C              U2    -N50        A01X+026054Y+032715X0120Y0120     S2      
317GND              VIA   -     D0100PA00X+026204Y+032268               S3      
317GND              VIA   -     D0100PA00X+026788Y+032584               S3      
317NNAME10541       VIA   -     D0100PA00X+026532Y+032649               S3      
317NNAME10544       VIA   -     D0100PA00X+027053Y+032575               S3      
317NNAME10540       VIA   -     D0100PA00X+026220Y+032849               S3      
317NNAME10542       VIA   -     D0100PA00X+027297Y+032584               S3      
317NNAME10546       VIA   -     D0100PA00X+027552Y+032584               S3      
317CPLD_ROW_EN      VIA   -     D0100PA00X+026703Y+033015               S3      
317NNAME10026       VIA   -     D0100PA00X+026270Y+032549               S1      
327GND              U2    -G56        A01X+027342Y+033915X0120Y0120     S2      
327NNAME10547       U2    -H56        A01X+027342Y+033615X0120Y0120     S2      
327NNAME10548       U2    -L52        A01X+026560Y+033165X0120Y0120     S2      
327NNAME10549       U2    -L54        A01X+026836Y+033165X0120Y0120     S2      
327GND              U2    -J54        A01X+026836Y+033465X0120Y0120     S2      
327GND              U2    -J52        A01X+026560Y+033465X0120Y0120     S2      
327NNAME10261       U2    -H54        A01X+026836Y+033765X0120Y0120     S2      
327CPU_RSV_1_R      U2    -H52        A01X+026560Y+033765X0120Y0120     S2      
327GND              U2    -L50        A01X+026054Y+033015X0120Y0120     S2      
327CPLD_ROW_EN      U2    -K50        A01X+026054Y+033315X0120Y0120     S2      
327NNAME10550       U2    -H50        A01X+026054Y+033615X0120Y0120     S2      
327GND              U2    -G50        A01X+026054Y+033915X0120Y0120     S2      
327GND              U2    -E50        A01X+026139Y+034198X0120Y0120     S2      
327NNAME10551       U2    -E52        A01X+026541Y+034198X0120Y0120     S2      
327GND              U2    -E54        A01X+026819Y+034205X0120Y0120     S2      
327NNAME10552       U2    -D51        A01X+026340Y+034387X0120Y0120     S2      
327GND              U2    -D50        A01X+026072Y+034469X0120Y0120     S2      
327NNAME10553       U2    -E57        A01X+027368Y+034254X0120Y0120     S2      
327PCIE_SW_P0_ERR   U2    -E55        A01X+027092Y+034254X0120Y0120     S2      
327TP_CPU_D53       U2    -D53        A01X+026603Y+034486X0120Y0120     S2      
317GND              VIA   -     D0100PA00X+026850Y+034418               S3      
317GND              VIA   -     D0100PA00X+026358Y+034090               S3      
317GND              VIA   -     D0100PA00X+027470Y+033380               S3      
317GND              VIA   -     D0100PA00X+027033Y+033580               S3      
317NNAME10261       VIA   -     D0100PA00X+027049Y+033903               S3      
317NNAME10550       VIA   -     D0100PA00X+026402Y+033615               S3      
317NNAME10548       VIA   -     D0100PA00X+026317Y+033179               S1      
317TP_CPU_D53       VIA   -     D0100PA00X+026794Y+033962               S3      
327NNAME10540       VIA   -           A10X+026097Y+034356X0260Y0260     S1      
317NNAME10545       VIA   -     D0100PA00X+027029Y+033054               S3      
317NNAME10543       VIA   -     D0100PA00X+027296Y+033067               S3      
317CPU_RSV_1_R      VIA   -     D0100PA00X+026238Y+033810               S3      
317CPLD_ROW_LATCH   VIA   -     D0100PA00X+026225Y+033450               S3      
317NNAME10549       VIA   -     D0100PA00X+027007Y+033302               S3      
327NNAME10547       VIA   -           A10X+027387Y+033666X0260Y0260     S1      
317NNAME10547       VIA   -     D0100PA00X+027226Y+033422               S3      
317PCIE_SW_P0_ERR   VIA   -     D0100PA00X+027235Y+034090               S3      
327NNAME10554       U2    -A51        A01X+026340Y+035059X0100Y0135     S2      
327GND              U2    -A54        A01X+026906Y+035059X0100Y0135     S2      
327NNAME10555       U2    -C51        A01X+026360Y+034687X0120Y0120     S2      
327GND              U2    -B50        A01X+026041Y+034884X0120Y0120     S2      
327LAN1_DISABLE_N   U2    -B55        A01X+027044Y+034818X0120Y0120     S2      
327NNAME10556       U2    -B57        A01X+027409Y+034819X0120Y0120     S2      
327LAN2_DISABLE_N   U2    -D57        A01X+027406Y+034528X0120Y0120     S2      
327NNAME10557       U2    -D55        A01X+027056Y+034528X0120Y0120     S2      
327GND              U2    -C54        A01X+026816Y+034662X0120Y0120     S2      
327NNAME10558       U2    -B53        A01X+026624Y+034863X0120Y0120     S2      
317LAN1_DISABLE_N   VIA   -     D0100PA00X+026946Y+035535               S3      
317GND              VIA   -     D0100PA00X+026912Y+035288               S3      
327TP_CPU_D53       VIA   -           A10X+026972Y+034969X0260Y0260     S1      
317NNAME10558       VIA   -     D0100PA00X+026989Y+035875               S1      
327NNAME10472       R155  -2          A10X+026035Y+036699X0180Y0200R090 S1      
327GND              R155  -1          A10X+026035Y+036384X0180Y0200R090 S1      
317NNAME10484       VIA   -     D0100PA00X+026054Y+037422               S1      
327NNAME10488       VIA   -           A01X+026358Y+036405X0300Y0300     S2      
327NNAME10478       VIA   -           A01X+027203Y+037458X0300Y0300     S2      
317NNAME10554       VIA   -     D0100PA00X+027029Y+036397               S1      
327CPU_RSV_1_R      VIA   -           A10X+026812Y+037456X0260Y0260     S1      
327NNAME10481       R65   -2          A01X+026073Y+037917X0180Y0200R090 S2      
327NNAME10559       R65   -1          A01X+026073Y+038232X0180Y0200R090 S2      
327NNAME10548       R90   -2          A10X+027269Y+037912X0180Y0200R270 S1      
327P3V3_NODE1       R90   -1          A10X+027269Y+038227X0180Y0200R270 S1      
327CPU_RSV_1        R110  -2          A10X+026869Y+038227X0180Y0200R090 S1      
327CPU_RSV_1_R      R110  -1          A10X+026869Y+037912X0180Y0200R090 S1      
327P3V3_NODE1       R152  -2          A10X+026069Y+038227X0180Y0200R090 S1      
327NNAME10472       R152  -1          A10X+026069Y+037912X0180Y0200R090 S1      
327NNAME10476       R69   -2          A01X+027273Y+037917X0180Y0200R090 S2      
327NNAME10486       R69   -1          A01X+027273Y+038232X0180Y0200R090 S2      
327GND              R92   -1          A10X+027511Y+038767X0180Y0200     S1      
327NNAME10489       R1090 -2          A01X+026175Y+039087X0180Y0200     S2      
327P5V_STB_NODE1    R1090 -1          A01X+026490Y+039087X0180Y0200     S2      
327NNAME10560       R73   -2          A01X+026473Y+038232X0180Y0200R270 S2      
327NNAME10484       R73   -1          A01X+026473Y+037917X0180Y0200R270 S2      
327NNAME10561       R72   -2          A01X+026873Y+038232X0180Y0200R270 S2      
327NNAME10485       R72   -1          A01X+026873Y+037917X0180Y0200R270 S2      
317P3V3_NODE1       VIA   -     D0100PA00X+027348Y+038510               S3      
317P3V3_NODE1       VIA   -     D0100PA00X+026166Y+038519               S3      
317P5V_STB_NODE1    VIA   -     D0100PA00X+026799Y+039070               S3      
317NNAME10550       VIA   -     D0100PA00X+027080Y+038664               S1      
317NNAME10561       VIA   -     D0100PA00X+026688Y+038817               S3      
317NNAME10559       VIA   -     D0100PA00X+026154Y+038776               S3      
317NNAME10560       VIA   -     D0100PA00X+026442Y+038481               S3      
317CPU_RSV_1        VIA   -     D0100PA00X+027550Y+039076               S3      
327NNAME10562       C826  -1          A01X+027463Y+040320X0180Y0200R180 S2      
327NNAME10563       R1092 -1          A01X+027463Y+039470X0180Y0200R180 S2      
327NNAME10562       R1091 -1          A01X+027463Y+039920X0180Y0200R180 S2      
327NNAME10489       Q30   -D          A01X+026089Y+039945X0320Y0360R090 S2      
327NNAME10562       Q30   -S          A01X+026876Y+040319X0320Y0360R090 S2      
327NNAME10563       Q30   -G          A01X+026876Y+039571X0320Y0360R090 S2      
317P3V3_SUS_NODE1   VIA   -     D0100PA00X+026342Y+039345               S1      
317NNAME10489       VIA   -     D0100PA00X+026516Y+040139               S1      
317NNAME10563       VIA   -     D0100PA00X+027222Y+040134               S1      
327GND              C848  -2          A01X+026280Y+042093X0180Y0200R090 S2      
327NNAME10492       C848  -1          A01X+026280Y+042408X0180Y0200R090 S2      
327NNAME10492       R1238 -2          A01X+026673Y+042009X0180Y0200R270 S2      
327GND              R1238 -1          A01X+026673Y+041694X0180Y0200R270 S2      
317GND              VIA   -     D0100PA00X+026280Y+041789               S3      
327NNAME10195       VIA   -           A10X+026493Y+040849X0160Y0050     S1      
317P1V8_STB_NODE1   VIA   -     D0100PA00X+027172Y+042259               S3      
317NNAME10492       VIA   -     D0100PA00X+026553Y+042265               S3      
327NNAME10493       Q37   -4          A01X+026805Y+044016X0140Y0200R180 S2      
327P1V8_NODE1       Q37   -3          A01X+027061Y+044016X0140Y0200R180 S2      
327P1V8_NODE1       Q37   -2          A01X+027317Y+044016X0140Y0200R180 S2      
327P1V8_STB_NODE1   Q37   -5          A01X+027189Y+043465X1264Y0898R180 S2      
327NNAME10492       Q38   -S          A01X+026229Y+043045X0320Y0360     S2      
317P1V8_STB_NODE1   VIA   -     D0100PA00X+026963Y+042488               S3      
317P1V8_STB_NODE1   VIA   -     D0100PA00X+027418Y+042497               S1      
327NNAME10493       C847  -1          A01X+026570Y+044694X0280Y0320R270 S2      
327P1V8_NODE1       C847  -2          A01X+027150Y+044694X0280Y0320R270 S2      
317NNAME10493       VIA   -     D0100PA00X+026682Y+044330               S1      
317P1V8_NODE1       VIA   -     D0100PA00X+027526Y+044575               S3      
317P1V8_NODE1       VIA   -     D0100PA00X+027104Y+044305               S3      
317P1V8_NODE1       VIA   -     D0100PA00X+027374Y+044303               S3      
327PU_I2C_BMC_SDA   R345  -2          A01X+026061Y+046598X0180Y0200R090 S2      
327P3V3_NODE1       R345  -1          A01X+026061Y+046913X0180Y0200R090 S2      
327BMC_ROMA17       R333  -2          A10X+026061Y+046598X0180Y0200R270 S1      
327P3V3_NODE1       R333  -1          A10X+026061Y+046913X0180Y0200R270 S1      
327BMC_ROMA8        R324  -2          A10X+026491Y+046598X0180Y0200R270 S1      
327P3V3_NODE1       R324  -1          A10X+026491Y+046913X0180Y0200R270 S1      
327BMC_ROMA13       R329  -2          A10X+026921Y+046598X0180Y0200R270 S1      
327P3V3_NODE1       R329  -1          A10X+026921Y+046913X0180Y0200R270 S1      
327BMC_ROMA23       R339  -2          A10X+027351Y+046598X0180Y0200R270 S1      
327P3V3_NODE1       R339  -1          A10X+027351Y+046913X0180Y0200R270 S1      
317P3V3_NODE1       VIA   -     D0100PA00X+027351Y+047165               S3      
317PU_I2C_BMC_SDA   VIA   -     D0100PA00X+026381Y+046123               S1      
327PU_I2C_BMC_SCL   R346  -2          A01X+026061Y+047813X0180Y0200R270 S2      
327P3V3_NODE1       R346  -1          A01X+026061Y+047498X0180Y0200R270 S2      
327BMC_ROMA9        R325  -2          A10X+026061Y+047813X0180Y0200R090 S1      
327P3V3_NODE1       R325  -1          A10X+026061Y+047498X0180Y0200R090 S1      
327NNAME10564       R255  -2          A01X+026911Y+047813X0180Y0200R270 S2      
327NNAME10269       R255  -1          A01X+026911Y+047498X0180Y0200R270 S2      
327BMC_ROMA14       R330  -2          A10X+026911Y+047813X0180Y0200R090 S1      
327P3V3_NODE1       R330  -1          A10X+026911Y+047498X0180Y0200R090 S1      
327BMC_ROMA19       R335  -2          A10X+026491Y+047813X0180Y0200R090 S1      
327P3V3_NODE1       R335  -1          A10X+026491Y+047498X0180Y0200R090 S1      
327NNAME10565       R253  -2          A10X+027321Y+047813X0180Y0200R090 S1      
327GND              R253  -1          A10X+027321Y+047498X0180Y0200R090 S1      
317P3V3_NODE1       VIA   -     D0100PA00X+026061Y+047245               S3      
317P3V3_NODE1       VIA   -     D0100PA00X+026491Y+047255               S3      
317P3V3_NODE1       VIA   -     D0100PA00X+026911Y+047235               S3      
317P3V3_NODE1       VIA   -     D0100PA00X+027545Y+048322               S3      
327BMC_ROMA19       VIA   -           A10X+026061Y+048615X0260Y0260     S1      
327BMC_ROMA14       VIA   -           A10X+026621Y+048334X0260Y0260     S1      
327NNAME10565       VIA   -           A10X+027221Y+048575X0260Y0260     S1      
327PU_I2C_BMC_SCL   VIA   -           A01X+026332Y+048339X0300Y0300     S2      
327BMC_ROMA22       U14   -L22        A01X+026040Y+049787X0145Y0145R270 S2      
327BMC_ROMA15       U14   -L21        A01X+026040Y+050102X0145Y0145R270 S2      
327PU_I2C_BMC_SDA   U14   -K22        A01X+026355Y+049787X0145Y0145R270 S2      
327PU_I2C_BMC_SCL   U14   -K21        A01X+026355Y+050102X0145Y0145R270 S2      
327NNAME10564       U14   -J22        A01X+026670Y+049787X0145Y0145R270 S2      
327N/C              U14   -J21        A01X+026670Y+050102X0145Y0145R270 S2      
327NNAME10566       U14   -H22        A01X+026985Y+049787X0145Y0145R270 S2      
327NNAME10566       U14   -H21        A01X+026985Y+050102X0145Y0145R270 S2      
327NNAME10567       U14   -G22        A01X+027300Y+049787X0145Y0145R270 S2      
327NNAME10568       U14   -G21        A01X+027300Y+050102X0145Y0145R270 S2      
327GND              C277  -2          A10X+027021Y+049028X0180Y0200R270 S1      
327NNAME10566       C277  -1          A10X+027021Y+049343X0180Y0200R270 S1      
327GND              C278  -2          A10X+027421Y+049028X0180Y0200R270 S1      
327NNAME10566       C278  -1          A10X+027421Y+049343X0180Y0200R270 S1      
317GND              VIA   -     D0100PA00X+026512Y+050259               S3      
317GND              VIA   -     D0100PA00X+026774Y+049161               S3      
327NNAME10566       VIA   -           A10X+027384Y+049799X0260Y0260     S1      
317NNAME10566       VIA   -     D0100PA00X+027458Y+050259               S3      
317NNAME10566       VIA   -     D0100PA00X+027140Y+049944               S3      
317NNAME10566       VIA   -     D0100PA00X+027143Y+049630               S3      
317BMC_ROMA14       VIA   -     D0100PA00X+026197Y+050259               S3      
327BMC_ROMA23       VIA   -           A10X+026491Y+049815X0260Y0260     S1      
327BMC_ROMA13       VIA   -           A10X+026011Y+050015X0260Y0260R090 S1      
317NNAME10564       VIA   -     D0100PA00X+026392Y+049175               S1      
327BMC_ROMA14       U14   -L20        A01X+026040Y+050417X0145Y0145R270 S2      
327BMC_ROMA13       U14   -L19        A01X+026040Y+050732X0145Y0145R270 S2      
327BMC_ROMA12       U14   -L18        A01X+026040Y+051047X0145Y0145R270 S2      
327NNAME10317       U14   -L17        A01X+026040Y+051362X0145Y0145R270 S2      
327GND              U14   -K20        A01X+026355Y+050417X0145Y0145R270 S2      
327NNAME10565       U14   -K19        A01X+026355Y+050732X0145Y0145R270 S2      
327BMC_ROMA23       U14   -K18        A01X+026355Y+051047X0145Y0145R270 S2      
327NNAME10317       U14   -K17        A01X+026355Y+051362X0145Y0145R270 S2      
327N/C              U14   -J20        A01X+026670Y+050417X0145Y0145R270 S2      
327GND              U14   -J19        A01X+026670Y+050732X0145Y0145R270 S2      
327GND              U14   -J18        A01X+026670Y+051047X0145Y0145R270 S2      
327P3V3_NODE1       U14   -J17        A01X+026670Y+051362X0145Y0145R270 S2      
327N/C              U14   -H20        A01X+026985Y+050417X0145Y0145R270 S2      
327N/C              U14   -H19        A01X+026985Y+050732X0145Y0145R270 S2      
327N/C              U14   -H18        A01X+026985Y+051047X0145Y0145R270 S2      
327P3V3_NODE1       U14   -H17        A01X+026985Y+051362X0145Y0145R270 S2      
327NNAME10566       U14   -G20        A01X+027300Y+050417X0145Y0145R270 S2      
327N/C              U14   -G19        A01X+027300Y+050732X0145Y0145R270 S2      
327N/C              U14   -G18        A01X+027300Y+051047X0145Y0145R270 S2      
327GND              C256  -2          A10X+027021Y+051843X0180Y0200R090 S1      
327P3V3_NODE1       C256  -1          A10X+027021Y+051528X0180Y0200R090 S1      
327GND              C255  -2          A10X+027421Y+051843X0180Y0200R090 S1      
327P3V3_NODE1       C255  -1          A10X+027421Y+051528X0180Y0200R090 S1      
317GND              VIA   -     D0100PA00X+026827Y+050574               S3      
317GND              VIA   -     D0100PA00X+026827Y+050889               S3      
317P3V3_NODE1       VIA   -     D0100PA00X+026827Y+051204               S3      
317P3V3_NODE1       VIA   -     D0100PA00X+027142Y+051204               S3      
317BMC_ROMA23       VIA   -     D0100PA00X+026512Y+050889               S3      
317BMC_ROMA12       VIA   -     D0100PA00X+026197Y+050889               S3      
327BMC_ROMA12       VIA   -           A10X+026501Y+051556X0260Y0260     S1      
317BMC_ROMA13       VIA   -     D0100PA00X+026197Y+050574               S3      
317NNAME10317       VIA   -     D0100PA00X+026512Y+051204               S3      
317NNAME10317       VIA   -     D0100PA00X+026197Y+051204               S3      
317NNAME10565       VIA   -     D0100PA00X+026512Y+050574               S3      
327GND              U14   -L14        A01X+026040Y+052307X0145Y0145R270 S2      
327GND              U14   -L13        A01X+026040Y+052622X0145Y0145R270 S2      
327GND              U14   -L12        A01X+026040Y+052937X0145Y0145R270 S2      
327GND              U14   -L11        A01X+026040Y+053252X0145Y0145R270 S2      
327GND              U14   -K14        A01X+026355Y+052307X0145Y0145R270 S2      
327GND              U14   -K13        A01X+026355Y+052622X0145Y0145R270 S2      
327GND              U14   -K12        A01X+026355Y+052937X0145Y0145R270 S2      
327GND              U14   -K11        A01X+026355Y+053252X0145Y0145R270 S2      
327GND              U14   -J14        A01X+026670Y+052307X0145Y0145R270 S2      
327GND              U14   -J13        A01X+026670Y+052622X0145Y0145R270 S2      
327GND              U14   -J12        A01X+026670Y+052937X0145Y0145R270 S2      
327GND              U14   -J11        A01X+026670Y+053252X0145Y0145R270 S2      
327GND              C249  -2          A10X+027136Y+052942X0180Y0200R180 S1      
327P3V3_NODE1       C249  -1          A10X+027451Y+052942X0180Y0200R180 S1      
327GND              C290  -2          A10X+027113Y+052235X0180Y0200R180 S1      
327NNAME10317       C290  -1          A10X+027428Y+052235X0180Y0200R180 S1      
327GND              C281  -2          A10X+027136Y+053342X0180Y0200R180 S1      
327P3V3_NODE1       C281  -1          A10X+027451Y+053342X0180Y0200R180 S1      
317GND              VIA   -     D0100PA00X+026197Y+052149               S3      
317GND              VIA   -     D0100PA00X+026827Y+053409               S3      
317GND              VIA   -     D0100PA00X+026512Y+053409               S3      
317GND              VIA   -     D0100PA00X+026197Y+053409               S3      
317GND              VIA   -     D0100PA00X+026827Y+052464               S3      
317GND              VIA   -     D0100PA00X+026827Y+052779               S3      
317GND              VIA   -     D0100PA00X+026512Y+052779               S3      
317GND              VIA   -     D0100PA00X+026512Y+052464               S3      
317GND              VIA   -     D0100PA00X+026197Y+052464               S3      
317GND              VIA   -     D0100PA00X+026197Y+052779               S3      
317GND              VIA   -     D0100PA00X+026827Y+052149               S3      
317GND              VIA   -     D0100PA00X+026512Y+052149               S3      
327GND              VIA   -           A10X+026331Y+053125X0260Y0260R090 S1      
327GND              U14   -L10        A01X+026040Y+053567X0145Y0145R270 S2      
327GND              U14   -L9         A01X+026040Y+053882X0145Y0145R270 S2      
327NNAME10317       U14   -L6         A01X+026040Y+054827X0145Y0145R270 S2      
327GND              U14   -K10        A01X+026355Y+053567X0145Y0145R270 S2      
327GND              U14   -K9         A01X+026355Y+053882X0145Y0145R270 S2      
327NNAME10317       U14   -K6         A01X+026355Y+054827X0145Y0145R270 S2      
327GND              U14   -J10        A01X+026670Y+053567X0145Y0145R270 S2      
327GND              U14   -J9         A01X+026670Y+053882X0145Y0145R270 S2      
327P3V3_NODE1       U14   -J6         A01X+026670Y+054827X0145Y0145R270 S2      
327P3V3_NODE1       U14   -H6         A01X+026985Y+054827X0145Y0145R270 S2      
327GND              C291  -2          A10X+026032Y+054711X0180Y0200R180 S1      
327NNAME10317       C291  -1          A10X+026347Y+054711X0180Y0200R180 S1      
327GND              C292  -2          A10X+026033Y+054325X0180Y0200R180 S1      
327NNAME10317       C292  -1          A10X+026348Y+054325X0180Y0200R180 S1      
327GND              C243  -2          A10X+026724Y+054351X0180Y0200R270 S1      
327P3V3_NODE1       C243  -1          A10X+026724Y+054666X0180Y0200R270 S1      
327GND              C252  -2          A10X+027140Y+054143X0180Y0200R180 S1      
327P3V3_NODE1       C252  -1          A10X+027455Y+054143X0180Y0200R180 S1      
327GND              C282  -2          A10X+027136Y+053742X0180Y0200R180 S1      
327P3V3_NODE1       C282  -1          A10X+027451Y+053742X0180Y0200R180 S1      
327GND              C248  -2          A10X+027198Y+054664X0280Y0320R090 S1      
317GND              VIA   -     D0100PA00X+026827Y+054039               S3      
317GND              VIA   -     D0100PA00X+026512Y+054039               S3      
317GND              VIA   -     D0100PA00X+026197Y+054039               S3      
317GND              VIA   -     D0100PA00X+026512Y+053724               S3      
317GND              VIA   -     D0100PA00X+026827Y+053724               S3      
317GND              VIA   -     D0100PA00X+026197Y+053724               S3      
317P3V3_NODE1       VIA   -     D0100PA00X+026827Y+054984               S3      
317P3V3_NODE1       VIA   -     D0100PA00X+027142Y+054984               S3      
317NNAME10317       VIA   -     D0100PA00X+026512Y+054984               S3      
317NNAME10317       VIA   -     D0100PA00X+026197Y+054984               S3      
327GND              U14   -L5         A01X+026040Y+055142X0145Y0145R270 S2      
327GND              U14   -L4         A01X+026040Y+055457X0145Y0145R270 S2      
327GND              U14   -L3         A01X+026040Y+055772X0145Y0145R270 S2      
327GND              U14   -L2         A01X+026040Y+056086X0145Y0145R270 S2      
327GND              U14   -L1         A01X+026040Y+056401X0145Y0145R270 S2      
327GND              U14   -K5         A01X+026355Y+055142X0145Y0145R270 S2      
327N/C              U14   -K4         A01X+026355Y+055457X0145Y0145R270 S2      
327N/C              U14   -K3         A01X+026355Y+055772X0145Y0145R270 S2      
327NNAME10569       U14   -K2         A01X+026355Y+056086X0145Y0145R270 S2      
327NNAME10570       U14   -K1         A01X+026355Y+056401X0145Y0145R270 S2      
327N/C              U14   -J5         A01X+026670Y+055142X0145Y0145R270 S2      
327N/C              U14   -J4         A01X+026670Y+055457X0145Y0145R270 S2      
327GND              U14   -J3         A01X+026670Y+055772X0145Y0145R270 S2      
327N/C              U14   -J2         A01X+026670Y+056086X0145Y0145R270 S2      
327N/C              U14   -J1         A01X+026670Y+056401X0145Y0145R270 S2      
327BMC_DEBUG_TXD    U14   -H5         A01X+026985Y+055142X0145Y0145R270 S2      
327GND              U14   -H4         A01X+026985Y+055457X0145Y0145R270 S2      
327GND              U14   -H3         A01X+026985Y+055772X0145Y0145R270 S2      
327GND              U14   -H2         A01X+026985Y+056086X0145Y0145R270 S2      
327GND              U14   -H1         A01X+026985Y+056401X0145Y0145R270 S2      
327GND              U14   -G5         A01X+027300Y+055142X0145Y0145R270 S2      
327N/C              U14   -G4         A01X+027300Y+055457X0145Y0145R270 S2      
327N3975090755      U14   -G3         A01X+027300Y+055772X0145Y0145R270 S2      
327NNAME10571       U14   -G2         A01X+027300Y+056086X0145Y0145R270 S2      
327BMC_DEBUG_RXD    U14   -G1         A01X+027300Y+056401X0145Y0145R270 S2      
327N3975090755      TP8   -1          A10X+027454Y+056252X0300Y0300     S1      
317GND              VIA   -     D0100PA00X+027457Y+055299               S3      
317GND              VIA   -     D0100PA00X+026512Y+055299               S3      
317GND              VIA   -     D0100PA00X+026827Y+055929               S3      
317GND              VIA   -     D0100PA00X+027142Y+056243               S3      
317GND              VIA   -     D0100PA00X+027142Y+055614               S3      
317GND              VIA   -     D0100PA00X+027142Y+055929               S3      
317GND              VIA   -     D0100PA00X+026197Y+055299               S3      
317GND              VIA   -     D0100PA00X+026201Y+055615               S3      
317GND              VIA   -     D0100PA00X+026197Y+056243               S3      
317GND              VIA   -     D0100PA00X+027142Y+056558               S3      
317BMC_DEBUG_TXD    VIA   -     D0100PA00X+027142Y+055299               S3      
327BMC_DEBUG_TXD    VIA   -           A10X+026610Y+056196X0260Y0260     S1      
317N3975090755      VIA   -     D0100PA00X+027457Y+055614               S3      
327BMC_DEBUG_RXD    PJ18  -2          A10X+026642Y+058063X0180Y0200R270 S1      
327N/C              PJ18  -1          A10X+026642Y+058378X0200Y0400     S1      
317NNAME10571       VIA   -     D0100PA00X+026961Y+057641               S1      
317NNAME10572       VIA   -     D0100PA00X+027431Y+057465               S1      
317NNAME10570       VIA   -     D0100PA00X+026118Y+056905               S1      
317NNAME10569       VIA   -     D0100PA00X+026379Y+057420               S1      
317BMC_DEBUG_RXD    VIA   -     D0100PA00X+026801Y+057095               S1      
327NNAME10572       R300  -2          A01X+027381Y+058298X0180Y0200R090 S2      
327P3V3_NODE1       R300  -1          A01X+027381Y+058613X0180Y0200R090 S2      
327NNAME10571       R302  -2          A01X+026961Y+058298X0180Y0200R090 S2      
327P3V3_NODE1       R302  -1          A01X+026961Y+058613X0180Y0200R090 S2      
317P3V3_NODE1       VIA   -     D0100PA00X+027348Y+058920               S1      
317P3V3_NODE1       VIA   -     D0100PA00X+026961Y+058865               S3      
327P5V_STB_NODE1    PL12  -2          A01X+026807Y+061455X0848Y1300R180 S2      
317P5V_STB_NODE1    VIA   -     D0100PA00X+026872Y+060602               S3      
317P5V_STB_NODE1    VIA   -     D0100PA00X+026197Y+060864               S3      
317P5V_STB_NODE1    VIA   -     D0100PA00X+026197Y+060564               S3      
317P5V_STB_NODE1    VIA   -     D0100PA00X+026006Y+060299               S3      
317P5V_STB_NODE1    VIA   -     D0100PA00X+026197Y+061464               S3      
317P5V_STB_NODE1    VIA   -     D0100PA00X+026347Y+062664               S3      
317P5V_STB_NODE1    VIA   -     D0100PA00X+026943Y+062297               S1      
317P5V_STB_NODE1    VIA   -     D0100PA00X+026197Y+061764               S3      
317P5V_STB_NODE1    VIA   -     D0100PA00X+026347Y+062364               S3      
327P5V_STB_NODE1    Q35   -5          A01X+026438Y+063683X1264Y0898R270 S2      
317P5V_STB_NODE1    VIA   -     D0100PA00X+027394Y+063308               S3      
317P5V_STB_NODE1    VIA   -     D0100PA00X+027367Y+064010               S3      
317P5V_STB_NODE1    VIA   -     D0100PA00X+027355Y+063647               S3      
327CPLD123_RSV1     R662  -1          A01X+027305Y+065649X0180Y0200R180 S2      
327CPLD123_RSV2     R676  -1          A01X+027305Y+065221X0180Y0200R180 S2      
327CPLD123_RSV3     R678  -1          A01X+027305Y+064812X0180Y0200R180 S2      
317CPLD123_RSV2     VIA   -     D0100PA00X+026661Y+065417               S1      
317CPLD123_RSV3     VIA   -     D0100PA00X+027004Y+065124               S3      
317CPLD123_RSV1     VIA   -     D0100PA00X+026964Y+065529               S3      
327GND              C582  -2          A01X+027305Y+066416X0180Y0200     S2      
327GND              C617  -2          A01X+025990Y+067177X0180Y0200     S2      
327P3V3_NODE1       C617  -1          A01X+026305Y+067177X0180Y0200     S2      
327P3V3_NODE1       C885  -1          A01X+027551Y+066880X0280Y0320R090 S2      
327GND              C885  -2          A01X+026971Y+066880X0280Y0320R090 S2      
317GND              VIA   -     D0100PA00X+027043Y+066558               S3      
317GND              VIA   -     D0100PA00X+026971Y+067258               S3      
317P3V3_NODE1       VIA   -     D0100PA00X+026591Y+067177               S3      
317NNAME10369       VIA   -     D0100PA00X+026189Y+066476               S1      
317NNAME10367       VIA   -     D0100PA00X+026555Y+066842               S1      
317NNAME10432       VIA   -     D0100PA00X+027436Y+067383               S1      
327GND              C583  -2          A01X+027305Y+069104X0180Y0200     S2      
327N/C              U84   -1          A01X+026147Y+068800X0180Y0520R180 S2      
327P3V3_NODE1       U84   -5          A01X+026147Y+067836X0180Y0520R180 S2      
317GND              VIA   -     D0100PA00X+027014Y+069104               S3      
317P5V_NODE1        VIA   -     D0100PA00X+027246Y+068789               S3      
317NNAME10366       VIA   -     D0100PA00X+026724Y+068252               S1      
317NNAME10437       VIA   -     D0100PA00X+026942Y+067706               S1      
327GND              D25   -C          A01X+027014Y+070280X0320Y0320R090 S2      
327WDT_LED          D25   -A          A01X+027014Y+069689X0320Y0320R090 S2      
327NNAME10321       U94   -G          A01X+026294Y+070836X0400Y0500R180 S2      
317GND              VIA   -     D0100PA00X+026530Y+070213               S3      
317P5V_NODE1        VIA   -     D0100PA00X+027265Y+069374               S3      
317T1_NODE2_EN      VIA   -     D0100PA00X+026941Y+070600               S3      
317T1_NODE3_EN      VIA   -     D0100PA00X+026712Y+070789               S1      
317NNAME10496       VIA   -     D0100PA00X+027351Y+069975               S1      
317NNAME10433       VIA   -     D0100PA00X+026617Y+069483               S1      
317NNAME10321       VIA   -     D0100PA00X+026068Y+071299               S1      
317NNAME10573       VIA   -     D0100PA00X+027121Y+071800               S1      
317T1_NODE4_EN      VIA   -     D0100PA00X+026460Y+072309               S1      
317T2_NODE1_EN      VIA   -     D0100PA00X+027094Y+072208               S3      
327GND              C640  -2          A01X+026194Y+073908X0180Y0200R090 S2      
327GND              C689  -2          A10X+027094Y+073073X0180Y0200R090 S1      
327NNAME10573       C689  -1          A10X+027094Y+072758X0180Y0200R090 S1      
327GND              C637  -2          A01X+026644Y+073908X0180Y0200R090 S2      
327GND              C622  -2          A10X+026194Y+073908X0180Y0200R270 S1      
327GND              C634  -2          A01X+027094Y+073908X0180Y0200R090 S2      
327GND              C692  -2          A10X+026644Y+073908X0180Y0200R270 S1      
327T2_NODE2_EN_R    R874  -2          A01X+026644Y+073073X0180Y0200R270 S2      
327T2_NODE2_EN      R874  -1          A01X+026644Y+072758X0180Y0200R270 S2      
327T1_NODE1_EN_R    R859  -2          A10X+026194Y+073073X0180Y0200R090 S1      
327T1_NODE1_EN      R859  -1          A10X+026194Y+072758X0180Y0200R090 S1      
327T2_NODE1_EN_R    R871  -2          A01X+027094Y+073073X0180Y0200R270 S2      
327T2_NODE1_EN      R871  -1          A01X+027094Y+072758X0180Y0200R270 S2      
327T2_NODE3_EN_R    R877  -2          A01X+026194Y+073073X0180Y0200R270 S2      
327T2_NODE3_EN      R877  -1          A01X+026194Y+072758X0180Y0200R270 S2      
327NNAME10573       R926  -1          A10X+027094Y+073908X0180Y0200R090 S1      
327NNAME10574       R929  -2          A10X+026644Y+073073X0180Y0200R090 S1      
327NNAME10575       R929  -1          A10X+026644Y+072758X0180Y0200R090 S1      
317GND              VIA   -     D0100PA00X+027544Y+073563               S3      
317GND              VIA   -     D0100PA00X+026194Y+073588               S3      
317GND              VIA   -     D0100PA00X+026644Y+073603               S3      
317GND              VIA   -     D0100PA00X+027094Y+073564               S3      
327T2_NODE3_EN_R    C640  -1          A01X+026194Y+074223X0180Y0200R090 S2      
327T2_NODE2_EN_R    C637  -1          A01X+026644Y+074223X0180Y0200R090 S2      
327T1_NODE1_EN_R    C622  -1          A10X+026194Y+074223X0180Y0200R270 S1      
327T2_NODE1_EN_R    C634  -1          A01X+027094Y+074223X0180Y0200R090 S2      
327NNAME10574       C692  -1          A10X+026644Y+074223X0180Y0200R270 S1      
327NNAME10576       R926  -2          A10X+027094Y+074223X0180Y0200R090 S1      
317T2_NODE3_EN_R    VIA   -     D0100PA00X+026343Y+077042               S1      
327NNAME10577       VIA   -           A10X+027544Y+077079X0260Y0260     S1      
317T2_NODE2_EN_R    VIA   -     D0100PA00X+026434Y+077878               S1      
317T2_NODE1_EN_R    VIA   -     D0100PA00X+027218Y+078307               S1      
327NNAME10574       VIA   -           A10X+026685Y+078597X0260Y0260     S1      
327NNAME10576       VIA   -           A10X+026989Y+077327X0260Y0260     S1      
327T1_NODE1_EN_R    VIA   -           A10X+026000Y+078523X0260Y0260     S1      
327NNAME10574       J35   -A28        A10X+026384Y+080787X0300Y1660R180 S1      
327NNAME10576       J35   -A27        A10X+026778Y+080787X0300Y1660R180 S1      
327NNAME10577       J35   -A26        A10X+027171Y+080787X0300Y1660R180 S1      
327NNAME10578       J35   -A25        A10X+027565Y+080787X0300Y1660R180 S1      
327T2_NODE2_EN_R    J35   -B28        A01X+026384Y+080787X0300Y1660R180 S2      
327T2_NODE1_EN_R    J35   -B27        A01X+026778Y+080787X0300Y1660R180 S2      
327GND              J35   -B26        A01X+027171Y+080787X0300Y1660R180 S2      
327NNAME10579       J35   -B25        A01X+027565Y+080787X0300Y1660R180 S2      
317GND              VIA   -     D0100PA00X+027171Y+078870               S3      
317GND              VIA   -     D0100PA00X+027171Y+079170               S3      
317GND              VIA   -     D0100PA00X+025990Y+079170               S3      
327GND              C933  -2          A01X+028570Y+000667X0180Y0200R180 S2      
327NNAME10503       C933  -1          A01X+028255Y+000667X0180Y0200R180 S2      
327NNAME10503       R1237 -2          A01X+027865Y+000664X0180Y0200R180 S2      
327GND              R1237 -1          A01X+027550Y+000664X0180Y0200R180 S2      
317GND              VIA   -     D0100PA00X+028070Y+001391               S3      
317GND              VIA   -     D0100PA00X+027820Y+001391               S3      
317GND              VIA   -     D0100PA00X+028218Y+001025               S3      
317GND              VIA   -     D0100PA00X+028570Y+000981               S3      
317NNAME10503       VIA   -     D0100PA00X+027866Y+001007               S3      
327P5V_STB_NODE1    PU5   -15         A01X+027499Y+003119X0100Y0330     S2      
327P12V_AUX         PU5   -14         A01X+027696Y+003119X0100Y0330     S2      
327P12V_AUX         PU5   -13         A01X+027893Y+003119X0100Y0330     S2      
327GND              PU5   -8          A01X+027893Y+001957X0100Y0330     S2      
327GND              PU5   -7          A01X+027696Y+001957X0100Y0330     S2      
327NNAME10502       PU5   -6          A01X+027499Y+001957X0100Y0330     S2      
327NNAME10580       PU5   -12         A01X+028178Y+002833X0100Y0330R090 S2      
327NNAME10581       PU5   -11         A01X+028178Y+002636X0100Y0330R090 S2      
327NNAME10581       PU5   -10         A01X+028178Y+002440X0100Y0330R090 S2      
327NNAME10581       PU5   -9          A01X+028178Y+002243X0100Y0330R090 S2      
327NNAME10581       PC47  -2          A01X+028723Y+002571X0180Y0200R090 S2      
327NNAME10580       PC47  -1          A01X+028723Y+002886X0180Y0200R090 S2      
317GND              VIA   -     D0100PA00X+027831Y+002306               S3      
317GND              VIA   -     D0100PA00X+028070Y+001641               S3      
317GND              VIA   -     D0100PA00X+027820Y+001641               S3      
317GND              VIA   -     D0100PA00X+027831Y+002771               S3      
317NNAME10580       VIA   -     D0100PA00X+028451Y+003068               S1      
317NNAME10581       VIA   -     D0100PA00X+028777Y+002129               S1      
327GND              PC44  -2          A01X+028460Y+003679X0180Y0200R180 S2      
327P12V_AUX         PC44  -1          A01X+028145Y+003679X0180Y0200R180 S2      
327GND              PC43  -2          A01X+029124Y+004289X0460Y0620R180 S2      
327P12V_AUX         PC43  -1          A01X+027964Y+004289X0460Y0620R180 S2      
317GND              VIA   -     D0100PA00X+028748Y+003713               S3      
327P12V_AUX         VIA   -           A10X+027825Y+003104X0260Y0260R090 S1      
317P12V_AUX         VIA   -     D0100PA00X+027747Y+003496               S3      
317P12V_AUX         VIA   -     D0100PA00X+027747Y+003746               S3      
317P12V_AUX         VIA   -     D0100PA00X+028007Y+003433               S3      
327GND              PC45  -2          A01X+029124Y+005129X0460Y0620R180 S2      
327P12V_AUX         PC45  -1          A01X+027964Y+005129X0460Y0620R180 S2      
317P12V_AUX         VIA   -     D0100PA00X+027577Y+005277               S3      
317P12V_AUX         VIA   -     D0100PA00X+027580Y+005021               S3      
327GND              C152  -2          A01X+027599Y+006803X0180Y0200R090 S2      
327PV_VDDR_NODE1    C152  -1          A01X+027599Y+007118X0180Y0200R090 S2      
327GND              C159  -2          A01X+028399Y+006803X0180Y0200R090 S2      
327PV_VDDR_NODE1    C159  -1          A01X+028399Y+007118X0180Y0200R090 S2      
327GND              C160  -2          A01X+027999Y+006803X0180Y0200R090 S2      
327PV_VDDR_NODE1    C160  -1          A01X+027999Y+007118X0180Y0200R090 S2      
327GND              C151  -2          A01X+028799Y+006803X0180Y0200R090 S2      
327PV_VDDR_NODE1    C151  -1          A01X+028799Y+007118X0180Y0200R090 S2      
317GND              VIA   -     D0100PA00X+029082Y+006317               S3      
317GND              VIA   -     D0100PA00X+028202Y+006317               S3      
317GND              VIA   -     D0100PA00X+027785Y+006317               S3      
317PV_VDDR_NODE1    VIA   -     D0100PA00X+028727Y+007502               S3      
317PV_VDDR_NODE1    VIA   -     D0100PA00X+028387Y+007472               S3      
317PV_VDDR_NODE1    VIA   -     D0100PA00X+027910Y+007445               S3      
317PV_VDDR_NODE1    VIA   -     D0100PA00X+028974Y+007617               S3      
317PV_VDDR_NODE1    VIA   -     D0100PA00X+028554Y+007687               S3      
317PV_VDDR_NODE1    VIA   -     D0100PA00X+028140Y+007594               S3      
317PV_VDDR_NODE1    VIA   -     D0100PA00X+027697Y+007625               S3      
327GND              C156  -2          A10X+027955Y+008491X0180Y0200R090 S1      
327PV_VDDR_NODE1    C156  -1          A10X+027955Y+008176X0180Y0200R090 S1      
327GND              C162  -2          A10X+028791Y+008470X0180Y0200R090 S1      
327PV_VDDR_NODE1    C162  -1          A10X+028791Y+008155X0180Y0200R090 S1      
327GND              C168  -2          A10X+028379Y+008470X0180Y0200R090 S1      
327PV_VDDR_NODE1    C168  -1          A10X+028379Y+008155X0180Y0200R090 S1      
327GND              C158  -2          A10X+027554Y+008493X0180Y0200R090 S1      
327PV_VDDR_NODE1    C158  -1          A10X+027554Y+008178X0180Y0200R090 S1      
327NNAME10391       J2    -103        A01X+028878Y+008248X0150Y0810     S2      
327PV_VDDR_NODE1    J2    -101        A01X+028642Y+008248X0150Y0810     S2      
327NNAME10387       J2    -99         A01X+028406Y+008248X0150Y0810     S2      
327NNAME10382       J2    -97         A01X+028169Y+008248X0150Y0810     S2      
327NNAME10333       J2    -95         A01X+027933Y+008248X0150Y0810     S2      
327PV_VDDR_NODE1    J2    -93         A01X+027697Y+008248X0150Y0810     S2      
317GND              VIA   -     D0100PA00X+027700Y+008832               S3      
317GND              VIA   -     D0100PA00X+028626Y+008868               S3      
317NNAME10339       VIA   -     D0100PA00X+027660Y+009212               S1      
317NNAME10391       VIA   -     D0100PA00X+028742Y+009186               S1      
327GND              C169  -2          A10X+028420Y+010611X0180Y0200R270 S1      
327PV_VDDR_NODE1    C169  -1          A10X+028420Y+010926X0180Y0200R270 S1      
317GND              VIA   -     D0100PA00X+028760Y+010611               S3      
317GND              VIA   -     D0100PA00X+027901Y+010489               S3      
317GND              VIA   -     D0100PA00X+028671Y+009572               S3      
317NNAME10387       VIA   -     D0100PA00X+028120Y+009837               S3      
317NNAME10390       VIA   -     D0100PA00X+028972Y+009609               S3      
317NNAME10382       VIA   -     D0100PA00X+027876Y+010106               S3      
317PV_VDDR_NODE1    VIA   -     D0100PA00X+028760Y+010883               S3      
317PV_VDDR_NODE1    VIA   -     D0100PA00X+027888Y+010848               S3      
327NNAME10507       R202  -2          A10X+027695Y+011730X0180Y0200R090 S1      
327PV_VDDR_NODE1    R202  -1          A10X+027695Y+011415X0180Y0200R090 S1      
327NNAME10388       J2    -104        A01X+028996Y+011476X0150Y0810     S2      
327PV_VDDR_NODE1    J2    -102        A01X+028760Y+011476X0150Y0810     S2      
327NNAME10385       J2    -100        A01X+028524Y+011476X0150Y0810     S2      
327NNAME10394       J2    -98         A01X+028288Y+011476X0150Y0810     S2      
327NNAME10395       J2    -96         A01X+028051Y+011476X0150Y0810     S2      
327PV_VDDR_NODE1    J2    -94         A01X+027815Y+011476X0150Y0810     S2      
327NNAME10384       J2    -92         A01X+027579Y+011476X0150Y0810     S2      
327PV_VDDR_NODE1    VIA   -           A10X+028338Y+013616X0260Y0260     S1      
327NNAME10385       VIA   -           A01X+028359Y+014448X0300Y0300     S2      
327PV_VDDR_NODE1    VIA   -           A10X+028460Y+021053X0260Y0260     S1      
327GND              C116  -2          A10X+028007Y+024768X0180Y0200     S1      
327PV_VDDR_NODE1    C116  -1          A10X+027692Y+024768X0180Y0200     S1      
327GND              PJ11  -2          A10X+028656Y+025018X0180Y0200R180 S1      
327NNAME10081       PJ11  -1          A10X+028971Y+025018X0200Y0400R270 S1      
327PV_VDDR_NODE1    PJ12  -2          A10X+028681Y+024680X0180Y0200R180 S1      
327NNAME10082       PJ12  -1          A10X+028996Y+024680X0200Y0400R270 S1      
327GND              U2    -BP62       A01X+028538Y+024681X0160Y0160     S2      
327GND              U2    -BM62       A01X+028538Y+025001X0160Y0160     S2      
327GND              U2    -BP61       A01X+028218Y+024681X0160Y0160     S2      
327GND              U2    -BP59       A01X+027898Y+024681X0110Y0135     S2      
327GND              U2    -BM61       A01X+028194Y+024998X0120Y0120     S2      
327NNAME10513       U2    -BM58       A01X+027718Y+025022X0120Y0120     S2      
327GND              U2    -BP58       A01X+027628Y+024626X0100Y0135     S2      
327NNAME10582       U2    -BN57       A01X+027490Y+024866X0120Y0120     S2      
327GND              U2    -BP64       A01X+028858Y+024681X0160Y0160     S2      
327GND              U2    -BM64       A01X+028858Y+025001X0160Y0160     S2      
317GND              VIA   -     D0100PA00X+027835Y+024428               S3      
317GND              VIA   -     D0100PA00X+029015Y+024401               S3      
317GND              VIA   -     D0100PA00X+028593Y+024393               S3      
317GND              VIA   -     D0100PA00X+028218Y+024401               S3      
317NNAME10583       VIA   -     D0100PA00X+027916Y+023782               S1      
327NNAME10514       U2    -BL57       A01X+027478Y+025157X0120Y0120     S2      
327GND              U2    -BK62       A01X+028538Y+025321X0160Y0160     S2      
327GND              U2    -BH60       A01X+028089Y+025842X0120Y0120     S2      
327NNAME10584       U2    -BH62       A01X+028378Y+025858X0120Y0120     S2      
327NNAME10585       U2    -BF62       A01X+028372Y+026136X0120Y0120     S2      
327GND              U2    -BD62       A01X+028372Y+026539X0120Y0120     S2      
327GND              U2    -BJ62       A01X+028427Y+025585X0120Y0120     S2      
327GND              U2    -BD59       A01X+027789Y+026624X0120Y0120     S2      
327NNAME10586       U2    -BD60       A01X+028089Y+026624X0120Y0120     S2      
327NNAME10587       U2    -BH58       A01X+027712Y+025770X0120Y0120     S2      
327NNAME10588       U2    -BG58       A01X+027712Y+026070X0120Y0120     S2      
327GND              U2    -BK60       A01X+027993Y+025487X0120Y0120     S2      
327GND              U2    -BL61       A01X+028194Y+025298X0120Y0120     S2      
327NNAME10583       U2    -BL59       A01X+027927Y+025216X0120Y0120     S2      
327GND              U2    -BK58       A01X+027714Y+025480X0120Y0120     S2      
327GND              U2    -BK64       A01X+028858Y+025321X0160Y0160     S2      
327GND              U2    -BJ63       A01X+028701Y+025631X0120Y0120     S2      
327GND              U2    -BH64       A01X+028858Y+025862X0120Y0120     S2      
327GND              U2    -BG63       A01X+028643Y+026070X0120Y0120     S2      
327NNAME10589       U2    -BE64       A01X+028860Y+026318X0120Y0120     S2      
327GND              U2    -BE63       A01X+028560Y+026338X0120Y0120     S2      
327NNAME10590       U2    -BD63       A01X+028643Y+026605X0120Y0120     S2      
317GND              VIA   -     D0100PA00X+028925Y+025569               S3      
317GND              VIA   -     D0100PA00X+028649Y+025836               S3      
317GND              VIA   -     D0100PA00X+028366Y+025154               S3      
317GND              VIA   -     D0100PA00X+028195Y+025559               S3      
317GND              VIA   -     D0100PA00X+028895Y+026079               S3      
317GND              VIA   -     D0100PA00X+027633Y+026469               S3      
317NNAME10582       VIA   -     D0100PA00X+027690Y+025255               S1      
317NNAME10585       VIA   -     D0100PA00X+028217Y+026292               S1      
317NNAME10584       VIA   -     D0100PA00X+028195Y+026023               S3      
317NNAME10587       VIA   -     D0100PA00X+027881Y+025914               S1      
317NNAME10588       VIA   -     D0100PA00X+027934Y+026480               S3      
327GND              U2    -BC62       A01X+028352Y+026815X0120Y0120     S2      
327GND              U2    -BB62       A01X+028427Y+027082X0120Y0120     S2      
327NNAME10591       U2    -BB59       A01X+027789Y+026899X0120Y0120     S2      
327NNAME10592       U2    -BB60       A01X+028089Y+026899X0120Y0120     S2      
327NNAME10521       U2    -BB57       A01X+027489Y+026899X0120Y0120     S2      
327GND              U2    -AY59       A01X+027939Y+027406X0120Y0120     S2      
327GND              U2    -AY58       A01X+027639Y+027406X0120Y0120     S2      
327GND              U2    -AW59       A01X+027939Y+027681X0120Y0120     S2      
327NNAME10593       U2    -AW58       A01X+027639Y+027681X0120Y0120     S2      
327GND              U2    -AU62       A01X+028372Y+027909X0120Y0120     S2      
327NNAME10594       U2    -AW62       A01X+028378Y+027631X0120Y0120     S2      
327GND              U2    -AY62       A01X+028427Y+027358X0120Y0120     S2      
327NNAME10595       U2    -AT57       A01X+027489Y+028188X0120Y0120     S2      
327NNAME10596       U2    -AT60       A01X+028089Y+028188X0120Y0120     S2      
327NNAME10597       U2    -AT59       A01X+027789Y+028188X0120Y0120     S2      
327NNAME10598       U2    -BB65       A01X+028993Y+027042X0120Y0120     S2      
327NNAME10599       U2    -BC64       A01X+028838Y+026803X0120Y0120     S2      
327NNAME10600       U2    -BB63       A01X+028701Y+027044X0120Y0120     S2      
327NNAME10601       U2    -AT64       A01X+028860Y+028090X0120Y0120     S2      
327GND              U2    -AV65       A01X+029037Y+027826X0120Y0120     S2      
327NNAME10602       U2    -AY65       A01X+028992Y+027406X0120Y0120     S2      
327GND              U2    -AV63       A01X+028660Y+027847X0120Y0120     S2      
327NNAME10603       U2    -AW64       A01X+028836Y+027635X0120Y0120     S2      
327NNAME10604       U2    -AY63       A01X+028701Y+027394X0120Y0120     S2      
327NNAME10605       U2    -AT63       A01X+028560Y+028110X0120Y0120     S2      
317GND              VIA   -     D0100PA00X+027789Y+027259               S3      
317GND              VIA   -     D0100PA00X+028089Y+027259               S3      
317GND              VIA   -     D0100PA00X+028601Y+027604               S3      
317GND              VIA   -     D0100PA00X+028287Y+028114               S3      
317NNAME10591       VIA   -     D0100PA00X+027644Y+027054               S3      
317NNAME10586       VIA   -     D0100PA00X+028231Y+027044               S3      
317NNAME10592       VIA   -     D0100PA00X+027944Y+027054               S3      
317NNAME10593       VIA   -     D0100PA00X+027794Y+027836               S3      
317NNAME10597       VIA   -     D0100PA00X+027939Y+028041               S3      
317NNAME10595       VIA   -     D0100PA00X+027639Y+028041               S3      
317NNAME10596       VIA   -     D0100PA00X+028177Y+027774               S1      
327GND              U2    -AR62       A01X+028372Y+028311X0120Y0120     S2      
327GND              U2    -AP62       A01X+028352Y+028588X0120Y0120     S2      
327GND              U2    -AN62       A01X+028427Y+028855X0120Y0120     S2      
327NNAME10606       U2    -AR60       A01X+028089Y+028463X0120Y0120     S2      
327NNAME10607       U2    -AR59       A01X+027789Y+028463X0120Y0120     S2      
327N/C              U2    -AH59       A01X+027789Y+029752X0120Y0120     S2      
327GND              U2    -AH60       A01X+028089Y+029752X0120Y0120     S2      
327GND              U2    -AM59       A01X+027939Y+028970X0120Y0120     S2      
327GND              U2    -AL59       A01X+027939Y+029245X0120Y0120     S2      
327NNAME10531       U2    -AR57       A01X+027489Y+028463X0120Y0120     S2      
327N/C              U2    -AH57       A01X+027489Y+029752X0120Y0120     S2      
327N/C              U2    -AL58       A01X+027639Y+029245X0120Y0120     S2      
327NNAME10608       U2    -AM58       A01X+027639Y+028970X0120Y0120     S2      
327GND              U2    -AK62       A01X+028378Y+029404X0120Y0120     S2      
327N/C              U2    -AH62       A01X+028372Y+029682X0120Y0120     S2      
327NNAME10609       U2    -AL62       A01X+028427Y+029131X0120Y0120     S2      
327NNAME10610       U2    -AR63       A01X+028643Y+028378X0120Y0120     S2      
327NNAME10611       U2    -AN65       A01X+028993Y+028814X0120Y0120     S2      
327NNAME10612       U2    -AN63       A01X+028701Y+028817X0120Y0120     S2      
327NNAME10613       U2    -AP64       A01X+028838Y+028576X0120Y0120     S2      
327N/C              U2    -AJ65       A01X+029037Y+029599X0120Y0120     S2      
327NNAME10614       U2    -AL65       A01X+028992Y+029179X0120Y0120     S2      
327N/C              U2    -AJ63       A01X+028660Y+029620X0120Y0120     S2      
327GND              U2    -AK64       A01X+028836Y+029407X0120Y0120     S2      
327NNAME10615       U2    -AL63       A01X+028701Y+029167X0120Y0120     S2      
317GND              VIA   -     D0100PA00X+027651Y+029582               S3      
317NNAME10610       VIA   -     D0100PA00X+029036Y+028608               S1      
317NNAME10615       VIA   -     D0100PA00X+028613Y+028595               S3      
317NNAME10606       VIA   -     D0100PA00X+028182Y+029079               S1      
317NNAME10608       VIA   -     D0100PA00X+027892Y+028689               S3      
317NNAME10607       VIA   -     D0100PA00X+027644Y+028618               S3      
327NNAME10616       R117  -1          A10X+028894Y+030688X0180Y0200     S1      
327NNAME10617       U2    -AG59       A01X+027789Y+030027X0120Y0120     S2      
327N/C              U2    -AG60       A01X+028089Y+030027X0120Y0120     S2      
327GND              U2    -AC59       A01X+027939Y+030809X0120Y0120     S2      
327GND              U2    -AD59       A01X+027939Y+030534X0120Y0120     S2      
327N/C              U2    -AG57       A01X+027489Y+030027X0120Y0120     S2      
327NNAME10618       U2    -AD58       A01X+027639Y+030534X0120Y0120     S2      
327NNAME10616       U2    -AC58       A01X+027639Y+030809X0120Y0120     S2      
327GND              U2    -AF62       A01X+028372Y+030084X0120Y0120     S2      
327NNAME10619       U2    -AE62       A01X+028352Y+030361X0120Y0120     S2      
327NNAME10620       U2    -AD62       A01X+028427Y+030628X0120Y0120     S2      
327NNAME10621       U2    -AA62       A01X+028378Y+031176X0120Y0120     S2      
327NNAME10622       U2    -AB62       A01X+028427Y+030903X0120Y0120     S2      
327GND              U2    -Y60        A01X+028089Y+031316X0120Y0120     S2      
327PV_VCCP_NODE1    U2    -Y59        A01X+027789Y+031316X0120Y0120     S2      
327PV_VCCP_NODE1    U2    -Y57        A01X+027489Y+031316X0120Y0120     S2      
327N/C              U2    -AF63       A01X+028643Y+030151X0120Y0120     S2      
327N/C              U2    -AG63       A01X+028560Y+029883X0120Y0120     S2      
327N/C              U2    -AG64       A01X+028860Y+029863X0120Y0120     S2      
327GND              U2    -AD65       A01X+028993Y+030587X0120Y0120     S2      
327NNAME10623       U2    -AD63       A01X+028701Y+030590X0120Y0120     S2      
327NNAME10624       U2    -AE64       A01X+028838Y+030349X0120Y0120     S2      
327GND              U2    -AB65       A01X+028992Y+030952X0120Y0120     S2      
327NNAME10625       U2    -AB63       A01X+028701Y+030940X0120Y0120     S2      
327NNAME10626       U2    -AA64       A01X+028836Y+031180X0120Y0120     S2      
317GND              VIA   -     D0100PA00X+027939Y+031169               S3      
317GND              VIA   -     D0100PA00X+028589Y+031136               S3      
317NNAME10617       VIA   -     D0100PA00X+027702Y+030230               S3      
317NNAME10622       VIA   -     D0100PA00X+028234Y+030822               S3      
317NNAME10621       VIA   -     D0100PA00X+028186Y+031086               S3      
317NNAME10616       VIA   -     D0100PA00X+027782Y+030968               S3      
327NNAME10616       VIA   -           A10X+028457Y+030570X0260Y0260     S1      
317NNAME10618       VIA   -     D0100PA00X+027975Y+030327               S3      
317PV_VCCP_NODE1    VIA   -     D0100PA00X+027639Y+031169               S3      
327NNAME10539       VIA   -           A10X+027628Y+030693X0260Y0260     S1      
327GND              C71   -2          A10X+027622Y+031856X0180Y0200R090 S1      
327PV_VCCP_NODE1    C71   -1          A10X+027622Y+031541X0180Y0200R090 S1      
327GND              C73   -2          A10X+028422Y+031856X0180Y0200R090 S1      
327PV_VCCP_NODE1    C73   -1          A10X+028422Y+031541X0180Y0200R090 S1      
327GND              C72   -2          A10X+028022Y+031856X0180Y0200R090 S1      
327PV_VCCP_NODE1    C72   -1          A10X+028022Y+031541X0180Y0200R090 S1      
327GND              C69   -2          A10X+028822Y+031856X0180Y0200R090 S1      
327PV_VCCP_NODE1    C69   -1          A10X+028822Y+031541X0180Y0200R090 S1      
327GND              U2    -W60        A01X+028089Y+031591X0120Y0120     S2      
327PV_VCCP_NODE1    U2    -W59        A01X+027789Y+031591X0120Y0120     S2      
327PV_VCCP_NODE1    U2    -W57        A01X+027489Y+031591X0120Y0120     S2      
327PV_VCCP_NODE1    U2    -U62        A01X+028372Y+031857X0120Y0120     S2      
327GND              U2    -W62        A01X+028372Y+031455X0120Y0120     S2      
327GND              U2    -T62        A01X+028352Y+032134X0120Y0120     S2      
327N32265582        U2    -R62        A01X+028427Y+032401X0120Y0120     S2      
327GND              U2    -T59        A01X+027939Y+032098X0120Y0120     S2      
327NNAME10319       U2    -T58        A01X+027639Y+032098X0120Y0120     S2      
327GND              U2    -R59        A01X+027939Y+032373X0120Y0120     S2      
327NNAME10546       U2    -R58        A01X+027639Y+032373X0120Y0120     S2      
327NNAME10627       U2    -N62        A01X+028427Y+032676X0120Y0120     S2      
327N/C              U2    -M59        A01X+027789Y+032880X0120Y0120     S2      
327NNAME10110       U2    -M60        A01X+028089Y+032880X0120Y0120     S2      
327GND              U2    -M57        A01X+027489Y+032880X0120Y0120     S2      
327PV_VCCP_NODE1    U2    -U63        A01X+028643Y+031924X0120Y0120     S2      
327PV_VCCP_NODE1    U2    -V63        A01X+028560Y+031656X0120Y0120     S2      
327PV_VCCP_NODE1    U2    -V64        A01X+028860Y+031636X0120Y0120     S2      
327GND              U2    -Y65        A01X+029037Y+031372X0120Y0120     S2      
327GND              U2    -Y63        A01X+028660Y+031393X0120Y0120     S2      
327GND              U2    -T64        A01X+028838Y+032122X0120Y0120     S2      
327NNAME10628       U2    -R65        A01X+028993Y+032360X0120Y0120     S2      
327NNAME10629       U2    -R63        A01X+028701Y+032362X0120Y0120     S2      
327GND              U2    -N63        A01X+028701Y+032712X0120Y0120     S2      
327NNAME10630       U2    -N65        A01X+028992Y+032725X0120Y0120     S2      
317GND              VIA   -     D0100PA00X+028146Y+032174               S3      
317GND              VIA   -     D0100PA00X+028078Y+032641               S3      
317NNAME10631       VIA   -     D0100PA00X+028607Y+032918               S3      
317NNAME10269       VIA   -     D0100PA00X+027807Y+032584               S3      
327NNAME10544       VIA   -           A10X+027583Y+032930X0260Y0260     S1      
317NNAME10319       VIA   -     D0100PA00X+028217Y+032424               S3      
317NNAME10627       VIA   -     D0100PA00X+028847Y+032534               S3      
317N32265582        VIA   -     D0100PA00X+028570Y+032181               S3      
327NNAME10052       R77   -2          A10X+028049Y+033055X0180Y0200R180 S1      
327P3V3_SUS_NODE1   R77   -1          A10X+028364Y+033055X0180Y0200R180 S1      
327GND              U2    -M62        A01X+028378Y+032949X0120Y0120     S2      
327NNAME10632       U2    -K62        A01X+028372Y+033228X0120Y0120     S2      
327GND              U2    -H62        A01X+028372Y+033630X0120Y0120     S2      
327NNAME10633       U2    -G62        A01X+028352Y+033906X0120Y0120     S2      
327NNAME10052       U2    -L59        A01X+027789Y+033155X0120Y0120     S2      
327NNAME10631       U2    -L60        A01X+028089Y+033155X0120Y0120     S2      
327GND              U2    -L57        A01X+027489Y+033155X0120Y0120     S2      
327NNAME10634       U2    -H59        A01X+027939Y+033662X0120Y0120     S2      
327GND              U2    -H58        A01X+027639Y+033662X0120Y0120     S2      
327GND              U2    -G59        A01X+027789Y+033915X0120Y0120     S2      
327GND              U2    -E61        A01X+028314Y+034198X0120Y0120     S2      
327TP_CPU_E59       U2    -E59        A01X+027912Y+034198X0120Y0120     S2      
327GND              U2    -E58        A01X+027635Y+034178X0120Y0120     S2      
327GND              U2    -D60        A01X+028113Y+034387X0120Y0120     S2      
327GND              U2    -D59        A01X+027845Y+034469X0120Y0120     S2      
327GND              U2    -M64        A01X+028836Y+032953X0120Y0120     S2      
327NNAME10635       U2    -L63        A01X+028660Y+033166X0120Y0120     S2      
327NNAME10636       U2    -L65        A01X+029037Y+033145X0120Y0120     S2      
327NNAME10637       U2    -J64        A01X+028860Y+033409X0120Y0120     S2      
327NNAME10638       U2    -J63        A01X+028560Y+033429X0120Y0120     S2      
327NNAME10639       U2    -G64        A01X+028858Y+033904X0120Y0120     S2      
327GND              U2    -H63        A01X+028643Y+033696X0120Y0120     S2      
327GND              U2    -F63        A01X+028701Y+034135X0120Y0120     S2      
327GND              U2    -E62        A01X+028538Y+034364X0160Y0160     S2      
327GND              U2    -E64        A01X+028858Y+034364X0160Y0160     S2      
317GND              VIA   -     D0100PA00X+027566Y+033886               S3      
317GND              VIA   -     D0100PA00X+028121Y+033808               S3      
317NNAME10110       VIA   -     D0100PA00X+027729Y+033428               S3      
317NNAME10634       VIA   -     D0100PA00X+028223Y+033379               S3      
327P3V3_SUS_NODE1   VIA   -           A10X+028982Y+033309X0260Y0260     S1      
317NNAME10633       VIA   -     D0100PA00X+028579Y+033906               S3      
317TP_CPU_E59       VIA   -     D0100PA00X+028121Y+034100               S1      
317NNAME10052       VIA   -     D0100PA00X+027972Y+033369               S3      
317NNAME10553       VIA   -     D0100PA00X+027560Y+034381               S3      
317NNAME10639       VIA   -     D0100PA00X+028919Y+034135               S1      
327NNAME10552       R87   -2          A10X+027782Y+034973X0180Y0200R180 S1      
327NNAME10547       R87   -1          A10X+028097Y+034973X0180Y0200R180 S1      
327GND              U2    -A57        A01X+027546Y+035059X0100Y0135     S2      
327GND              U2    -C60        A01X+028113Y+034687X0120Y0120     S2      
327GND              U2    -C58        A01X+027647Y+034664X0120Y0120     S2      
327GND              U2    -A59        A01X+027898Y+035004X0110Y0135     S2      
327GND              U2    -A61        A01X+028218Y+035004X0160Y0160     S2      
327GND              U2    -C62        A01X+028538Y+034684X0160Y0160     S2      
327GND              U2    -A64        A01X+028858Y+035004X0160Y0160     S2      
327GND              U2    -A62        A01X+028538Y+035004X0160Y0160     S2      
327GND              U2    -C64        A01X+028858Y+034684X0160Y0160     S2      
317GND              VIA   -     D0100PA00X+029019Y+035248               S3      
317GND              VIA   -     D0100PA00X+027894Y+034691               S3      
317GND              VIA   -     D0100PA00X+027772Y+035269               S3      
317GND              VIA   -     D0100PA00X+028282Y+035269               S3      
317GND              VIA   -     D0100PA00X+028671Y+035267               S3      
317GND              VIA   -     D0100PA00X+028314Y+034608               S3      
317LAN2_DISABLE_N   VIA   -     D0100PA00X+028602Y+035645               S3      
327NNAME10552       VIA   -           A10X+028004Y+035859X0260Y0260     S1      
327NNAME10549       VIA   -           A10X+027590Y+035567X0260Y0260     S1      
327NNAME10482       R89   -2          A10X+028350Y+036740X0180Y0200R090 S1      
327NNAME10639       R89   -1          A10X+028350Y+036425X0180Y0200R090 S1      
327NNAME10555       R85   -2          A10X+027683Y+036702X0180Y0200R090 S1      
327NNAME10549       R85   -1          A10X+027683Y+036387X0180Y0200R090 S1      
327P3V3_NODE1       R151  -2          A01X+028914Y+037217X0180Y0200R270 S2      
327NNAME10551       R151  -1          A01X+028914Y+036902X0180Y0200R270 S2      
317NNAME10486       VIA   -     D0100PA00X+027704Y+037617               S1      
317NNAME10552       VIA   -     D0100PA00X+027986Y+036751               S3      
317NNAME10555       VIA   -     D0100PA00X+028655Y+037440               S1      
317NNAME10482       VIA   -     D0100PA00X+028145Y+037315               S1      
327NNAME10551       VIA   -           A01X+028799Y+036445X0300Y0300     S2      
327NNAME10548       R92   -2          A10X+027826Y+038767X0180Y0200     S1      
327P3V3_NODE1       R109  -2          A01X+028873Y+038232X0180Y0200R270 S2      
327NNAME10552       R109  -1          A01X+028873Y+037917X0180Y0200R270 S2      
327NNAME10488       R71   -2          A01X+028073Y+037917X0180Y0200R090 S2      
327NNAME10550       R71   -1          A01X+028073Y+038232X0180Y0200R090 S2      
327NNAME10478       R67   -2          A01X+027673Y+037917X0180Y0200R090 S2      
327NNAME10486       R67   -1          A01X+027673Y+038232X0180Y0200R090 S2      
327P3V3_NODE1       R111  -2          A01X+028473Y+038232X0180Y0200R270 S2      
327NNAME10482       R111  -1          A01X+028473Y+037917X0180Y0200R270 S2      
317GND              VIA   -     D0100PA00X+027669Y+038510               S3      
317P3V3_NODE1       VIA   -     D0100PA00X+028869Y+038529               S3      
317P3V3_NODE1       VIA   -     D0100PA00X+028186Y+038618               S3      
317P3V3_NODE1       VIA   -     D0100PA00X+028469Y+038677               S3      
317NNAME10261       VIA   -     D0100PA00X+028539Y+039055               S1      
317PCIE_SW_P0_ERR   VIA   -     D0100PA00X+028822Y+038963               S3      
327GND              C826  -2          A01X+027778Y+040320X0180Y0200R180 S2      
327P3V3_STB_NODE1   R1092 -2          A01X+027778Y+039470X0180Y0200R180 S2      
327P3V3_STB_NODE1   R1091 -2          A01X+027778Y+039920X0180Y0200R180 S2      
327NNAME10562       R1231 -2          A01X+028671Y+039879X0180Y0200R270 S2      
327GND              R1231 -1          A01X+028671Y+039564X0180Y0200R270 S2      
317GND              VIA   -     D0100PA00X+028382Y+039627               S3      
317GND              VIA   -     D0100PA00X+028114Y+040238               S3      
317NNAME10562       VIA   -     D0100PA00X+028707Y+040236               S1      
317P3V3_STB_NODE1   VIA   -     D0100PA00X+028073Y+039386               S3      
317P1V8_STB_NODE1   VIA   -     D0100PA00X+027640Y+042234               S3      
317P1V8_STB_NODE1   VIA   -     D0100PA00X+028001Y+042228               S3      
327P1V8_NODE1       Q37   -1          A01X+027573Y+044016X0140Y0200R180 S2      
317P1V8_STB_NODE1   VIA   -     D0100PA00X+028119Y+042497               S3      
317P1V8_STB_NODE1   VIA   -     D0100PA00X+027808Y+042476               S3      
327P1V8_NODE1       R1114 -2          A01X+027635Y+044843X0180Y0200R090 S2      
327GND              R1114 -1          A01X+027635Y+045158X0180Y0200R090 S2      
317P1V8_NODE1       VIA   -     D0100PA00X+028621Y+044493               S3      
317P1V8_NODE1       VIA   -     D0100PA00X+028963Y+044483               S3      
317P1V8_NODE1       VIA   -     D0100PA00X+028321Y+044229               S3      
317P1V8_NODE1       VIA   -     D0100PA00X+028610Y+044230               S3      
317P1V8_NODE1       VIA   -     D0100PA00X+028874Y+044209               S3      
317P1V8_NODE1       VIA   -     D0100PA00X+028797Y+044671               S3      
317P1V8_NODE1       VIA   -     D0100PA00X+028200Y+044497               S3      
317P1V8_NODE1       VIA   -     D0100PA00X+027911Y+044495               S3      
317P1V8_NODE1       VIA   -     D0100PA00X+027663Y+044291               S1      
317P1V8_NODE1       VIA   -     D0100PA00X+027999Y+044207               S3      
317GND              VIA   -     D0100PA00X+027681Y+047185               S3      
317GND              VIA   -     D0100PA00X+027635Y+045974               S1      
317NNAME10209       VIA   -     D0100PA00X+028021Y+046076               S3      
317NNAME10568       VIA   -     D0100PA00X+028757Y+047065               S3      
317NNAME10567       VIA   -     D0100PA00X+028757Y+046765               S3      
317NNAME10640       VIA   -     D0100PA00X+028038Y+046728               S3      
317NNAME10641       VIA   -     D0100PA00X+027899Y+046479               S3      
327NNAME10565       R272  -2          A10X+028237Y+047819X0180Y0200R090 S1      
327NNAME10641       R272  -1          A10X+028237Y+047504X0180Y0200R090 S1      
327NNAME10565       R254  -2          A10X+027831Y+047820X0180Y0200R090 S1      
327NNAME10640       R254  -1          A10X+027831Y+047505X0180Y0200R090 S1      
317GND              VIA   -     D0100PA00X+028433Y+047283               S3      
317GND              VIA   -     D0100PA00X+028230Y+048380               S3      
317NNAME10642       VIA   -     D0100PA00X+027747Y+048120               S3      
317NNAME10643       VIA   -     D0100PA00X+028097Y+048120               S3      
327P1V8_NODE1       VIA   -           A10X+028759Y+048203X0260Y0260     S1      
327NNAME10644       VIA   -           A01X+029049Y+047370X0160Y0050     S2      
327NNAME10645       VIA   -           A01X+028771Y+048362X0160Y0050R270 S2      
327NNAME10642       U14   -F22        A01X+027615Y+049787X0145Y0145R270 S2      
327NNAME10643       U14   -F21        A01X+027615Y+050102X0145Y0145R270 S2      
327NNAME10644       U14   -E22        A01X+027930Y+049787X0145Y0145R270 S2      
327NNAME10645       U14   -E21        A01X+027930Y+050102X0145Y0145R270 S2      
327GND              U14   -D22        A01X+028245Y+049787X0145Y0145R270 S2      
327GND              U14   -D21        A01X+028245Y+050102X0145Y0145R270 S2      
327N/C              U14   -C22        A01X+028560Y+049787X0145Y0145R270 S2      
327NNAME10646       U14   -C21        A01X+028560Y+050102X0145Y0145R270 S2      
327N/C              U14   -B22        A01X+028875Y+049787X0145Y0145R270 S2      
327PD_BMC_LPC       U14   -B21        A01X+028875Y+050102X0145Y0145R270 S2      
327NNAME10566       C276  -1          A10X+027900Y+049496X0280Y0320R180 S1      
327GND              C276  -2          A10X+027900Y+048916X0280Y0320R180 S1      
327NNAME10646       L18   -1          A10X+029120Y+049479X0280Y0320R180 S1      
327P1V8_NODE1       L18   -2          A10X+029120Y+048899X0280Y0320R180 S1      
327NNAME10566       L17   -1          A10X+028472Y+049552X0280Y0320R180 S1      
327P1V8_NODE1       L17   -2          A10X+028472Y+048972X0280Y0320R180 S1      
317GND              VIA   -     D0100PA00X+028402Y+049945               S3      
317NNAME10646       VIA   -     D0100PA00X+028717Y+049945               S3      
317NNAME10646       VIA   -     D0100PA00X+028801Y+049565               S3      
317NNAME10646       VIA   -     D0100PA00X+027771Y+050260               S3      
317NNAME10647       VIA   -     D0100PA00X+028402Y+050260               S1      
317LPC_CLK_AST      VIA   -     D0100PA00X+029032Y+050260               S1      
327NNAME10646       U14   -F20        A01X+027615Y+050417X0145Y0145R270 S2      
327PD_BMC_LPC       U14   -F19        A01X+027615Y+050732X0145Y0145R270 S2      
327N/C              U14   -F18        A01X+027615Y+051047X0145Y0145R270 S2      
327N/C              U14   -E20        A01X+027930Y+050417X0145Y0145R270 S2      
327N/C              U14   -E19        A01X+027930Y+050732X0145Y0145R270 S2      
327N/C              U14   -E18        A01X+027930Y+051047X0145Y0145R270 S2      
327PD_BMC_LPC       U14   -E17        A01X+027930Y+051362X0145Y0145R270 S2      
327NNAME10647       U14   -D20        A01X+028245Y+050417X0145Y0145R270 S2      
327N/C              U14   -D19        A01X+028245Y+050732X0145Y0145R270 S2      
327N/C              U14   -D18        A01X+028245Y+051047X0145Y0145R270 S2      
327N/C              U14   -D17        A01X+028245Y+051362X0145Y0145R270 S2      
327N/C              U14   -C20        A01X+028560Y+050417X0145Y0145R270 S2      
327PD_BMC_LPC       U14   -C19        A01X+028560Y+050732X0145Y0145R270 S2      
327N/C              U14   -C18        A01X+028560Y+051047X0145Y0145R270 S2      
327N/C              U14   -C17        A01X+028560Y+051362X0145Y0145R270 S2      
327LPC_CLK_AST      U14   -B20        A01X+028875Y+050417X0145Y0145R270 S2      
327N/C              U14   -B19        A01X+028875Y+050732X0145Y0145R270 S2      
327N/C              U14   -B18        A01X+028875Y+051047X0145Y0145R270 S2      
327N/C              U14   -B17        A01X+028875Y+051362X0145Y0145R270 S2      
327N/C              U14   -E16        A01X+027930Y+051677X0145Y0145R270 S2      
327N/C              U14   -D16        A01X+028245Y+051677X0145Y0145R270 S2      
327N/C              U14   -C16        A01X+028560Y+051677X0145Y0145R270 S2      
327N/C              U14   -B16        A01X+028875Y+051677X0145Y0145R270 S2      
327GND              C279  -2          A10X+027821Y+051793X0180Y0200R090 S1      
327P3V3_NODE1       C279  -1          A10X+027821Y+051478X0180Y0200R090 S1      
327NNAME10317       U14   -F15        A01X+027615Y+051992X0145Y0145R270 S2      
327NNAME10317       U14   -F14        A01X+027615Y+052307X0145Y0145R270 S2      
327P3V3_NODE1       U14   -F13        A01X+027615Y+052622X0145Y0145R270 S2      
327P3V3_NODE1       U14   -F12        A01X+027615Y+052937X0145Y0145R270 S2      
327P3V3_NODE1       U14   -F11        A01X+027615Y+053252X0145Y0145R270 S2      
327N/C              U14   -E15        A01X+027930Y+051992X0145Y0145R270 S2      
327N/C              U14   -E14        A01X+027930Y+052307X0145Y0145R270 S2      
327N/C              U14   -E13        A01X+027930Y+052622X0145Y0145R270 S2      
327N/C              U14   -E12        A01X+027930Y+052937X0145Y0145R270 S2      
327GND              U14   -E11        A01X+027930Y+053252X0145Y0145R270 S2      
327N/C              U14   -D15        A01X+028245Y+051992X0145Y0145R270 S2      
327N/C              U14   -D14        A01X+028245Y+052307X0145Y0145R270 S2      
327N/C              U14   -D13        A01X+028245Y+052622X0145Y0145R270 S2      
327N/C              U14   -D12        A01X+028245Y+052937X0145Y0145R270 S2      
327GND              U14   -D11        A01X+028245Y+053252X0145Y0145R270 S2      
327N/C              U14   -C15        A01X+028560Y+051992X0145Y0145R270 S2      
327N/C              U14   -C14        A01X+028560Y+052307X0145Y0145R270 S2      
327N/C              U14   -C13        A01X+028560Y+052622X0145Y0145R270 S2      
327N/C              U14   -C12        A01X+028560Y+052937X0145Y0145R270 S2      
327GND              U14   -C11        A01X+028560Y+053252X0145Y0145R270 S2      
327N/C              U14   -B15        A01X+028875Y+051992X0145Y0145R270 S2      
327N/C              U14   -B14        A01X+028875Y+052307X0145Y0145R270 S2      
327N/C              U14   -B13        A01X+028875Y+052622X0145Y0145R270 S2      
327N/C              U14   -B12        A01X+028875Y+052937X0145Y0145R270 S2      
327GND              U14   -B11        A01X+028875Y+053252X0145Y0145R270 S2      
317GND              VIA   -     D0100PA00X+029032Y+053409               S3      
317GND              VIA   -     D0100PA00X+028087Y+053409               S3      
317GND              VIA   -     D0100PA00X+028717Y+053409               S3      
317GND              VIA   -     D0100PA00X+028402Y+053409               S3      
317P3V3_NODE1       VIA   -     D0100PA00X+027773Y+053409               S3      
317P3V3_NODE1       VIA   -     D0100PA00X+027773Y+052779               S3      
327P3V3_NODE1       VIA   -           A10X+028175Y+053135X0260Y0260R090 S1      
317NNAME10317       VIA   -     D0100PA00X+027773Y+052149               S3      
327P3V3_NODE1       U14   -F10        A01X+027615Y+053567X0145Y0145R270 S2      
327P3V3_NODE1       U14   -F9         A01X+027615Y+053882X0145Y0145R270 S2      
327P3V3_NODE1       U14   -F8         A01X+027615Y+054197X0145Y0145R270 S2      
327GND              U14   -E10        A01X+027930Y+053567X0145Y0145R270 S2      
327N/C              U14   -E9         A01X+027930Y+053882X0145Y0145R270 S2      
327GND              U14   -E8         A01X+027930Y+054197X0145Y0145R270 S2      
327N/C              U14   -E7         A01X+027930Y+054512X0145Y0145R270 S2      
327N3975090767      U14   -E6         A01X+027930Y+054827X0145Y0145R270 S2      
327N/C              U14   -D10        A01X+028245Y+053567X0145Y0145R270 S2      
327N/C              U14   -D9         A01X+028245Y+053882X0145Y0145R270 S2      
327GND              U14   -D8         A01X+028245Y+054197X0145Y0145R270 S2      
327N/C              U14   -D7         A01X+028245Y+054512X0145Y0145R270 S2      
327N/C              U14   -D6         A01X+028245Y+054827X0145Y0145R270 S2      
327N/C              U14   -C10        A01X+028560Y+053567X0145Y0145R270 S2      
327GND              U14   -C9         A01X+028560Y+053882X0145Y0145R270 S2      
327GND              U14   -C8         A01X+028560Y+054197X0145Y0145R270 S2      
327N/C              U14   -C7         A01X+028560Y+054512X0145Y0145R270 S2      
327N/C              U14   -C6         A01X+028560Y+054827X0145Y0145R270 S2      
327N/C              U14   -B10        A01X+028875Y+053567X0145Y0145R270 S2      
327GND              U14   -B9         A01X+028875Y+053882X0145Y0145R270 S2      
327GND              U14   -B8         A01X+028875Y+054197X0145Y0145R270 S2      
327N/C              U14   -B7         A01X+028875Y+054512X0145Y0145R270 S2      
327N/C              U14   -B6         A01X+028875Y+054827X0145Y0145R270 S2      
327P3V3_NODE1       C248  -1          A10X+027778Y+054664X0280Y0320R090 S1      
327N3975090767      TP7   -1          A10X+028417Y+054799X0300Y0300     S1      
317GND              VIA   -     D0100PA00X+028087Y+053724               S3      
317GND              VIA   -     D0100PA00X+028087Y+054354               S3      
317GND              VIA   -     D0100PA00X+028402Y+054354               S3      
317GND              VIA   -     D0100PA00X+028717Y+054039               S3      
317GND              VIA   -     D0100PA00X+028717Y+054354               S3      
317GND              VIA   -     D0100PA00X+029032Y+054039               S3      
317GND              VIA   -     D0100PA00X+029032Y+054354               S3      
317P3V3_NODE1       VIA   -     D0100PA00X+027773Y+054039               S3      
317P3V3_NODE1       VIA   -     D0100PA00X+027773Y+054354               S3      
317P3V3_NODE1       VIA   -     D0100PA00X+027773Y+053724               S3      
317N3975090765      VIA   -     D0100PA00X+029032Y+054984               S3      
317N3975090767      VIA   -     D0100PA00X+028087Y+054984               S3      
327GND              U14   -F5         A01X+027615Y+055142X0145Y0145R270 S2      
327GND              U14   -F4         A01X+027615Y+055457X0145Y0145R270 S2      
327GND              U14   -F3         A01X+027615Y+055772X0145Y0145R270 S2      
327NNAME10648       U14   -F2         A01X+027615Y+056086X0145Y0145R270 S2      
327NNAME10572       U14   -F1         A01X+027615Y+056401X0145Y0145R270 S2      
327GND              U14   -E5         A01X+027930Y+055142X0145Y0145R270 S2      
327N20822523        U14   -E4         A01X+027930Y+055457X0145Y0145R270 S2      
327GND              U14   -E3         A01X+027930Y+055772X0145Y0145R270 S2      
327GND              U14   -E2         A01X+027930Y+056086X0145Y0145R270 S2      
327NNAME10649       U14   -E1         A01X+027930Y+056401X0145Y0145R270 S2      
327GND              U14   -D5         A01X+028245Y+055142X0145Y0145R270 S2      
327GND              U14   -D4         A01X+028245Y+055457X0145Y0145R270 S2      
327GND              U14   -D3         A01X+028245Y+055772X0145Y0145R270 S2      
327GND              U14   -D2         A01X+028245Y+056086X0145Y0145R270 S2      
327GND              U14   -D1         A01X+028245Y+056401X0145Y0145R270 S2      
327GND              U14   -C5         A01X+028560Y+055142X0145Y0145R270 S2      
327GND              U14   -C4         A01X+028560Y+055457X0145Y0145R270 S2      
327GND              U14   -C3         A01X+028560Y+055772X0145Y0145R270 S2      
327GND              U14   -C2         A01X+028560Y+056086X0145Y0145R270 S2      
327GND              U14   -C1         A01X+028560Y+056401X0145Y0145R270 S2      
327N3975090765      U14   -B5         A01X+028875Y+055142X0145Y0145R270 S2      
327GND              U14   -B4         A01X+028875Y+055457X0145Y0145R270 S2      
327GND              U14   -B3         A01X+028875Y+055772X0145Y0145R270 S2      
327GND              U14   -B2         A01X+028875Y+056086X0145Y0145R270 S2      
327GND              U14   -B1         A01X+028875Y+056401X0145Y0145R270 S2      
317GND              VIA   -     D0100PA00X+028717Y+055929               S3      
317GND              VIA   -     D0100PA00X+029032Y+056559               S3      
317GND              VIA   -     D0100PA00X+028402Y+056559               S3      
317GND              VIA   -     D0100PA00X+028717Y+056559               S3      
317GND              VIA   -     D0100PA00X+029032Y+055929               S3      
317GND              VIA   -     D0100PA00X+029032Y+056244               S3      
317GND              VIA   -     D0100PA00X+029032Y+055614               S3      
317GND              VIA   -     D0100PA00X+028717Y+056244               S3      
317GND              VIA   -     D0100PA00X+028087Y+056244               S3      
317GND              VIA   -     D0100PA00X+028402Y+056244               S3      
317GND              VIA   -     D0100PA00X+028402Y+055929               S3      
317GND              VIA   -     D0100PA00X+027773Y+055299               S3      
317GND              VIA   -     D0100PA00X+028087Y+055929               S3      
317GND              VIA   -     D0100PA00X+027773Y+055614               S3      
317GND              VIA   -     D0100PA00X+027773Y+055929               S3      
317GND              VIA   -     D0100PA00X+028717Y+055614               S3      
317GND              VIA   -     D0100PA00X+028087Y+055299               S3      
317GND              VIA   -     D0100PA00X+028402Y+055614               S3      
317GND              VIA   -     D0100PA00X+028717Y+055299               S3      
317GND              VIA   -     D0100PA00X+028402Y+055299               S3      
317N20822523        VIA   -     D0100PA00X+028087Y+055614               S3      
327BMC_DEBUG_TXD    PJ19  -1          A10X+027759Y+057973X0200Y0400R180 S1      
317NNAME10648       VIA   -     D0100PA00X+027966Y+057444               S1      
317NNAME10649       VIA   -     D0100PA00X+028553Y+057300               S1      
327NNAME10648       R304  -2          A01X+027811Y+058298X0180Y0200R090 S2      
327P3V3_NODE1       R304  -1          A01X+027811Y+058613X0180Y0200R090 S2      
327NNAME10649       R298  -2          A01X+028231Y+058298X0180Y0200R090 S2      
327P3V3_NODE1       R298  -1          A01X+028231Y+058613X0180Y0200R090 S2      
327N/C              PJ19  -2          A10X+027759Y+058288X0180Y0200R090 S1      
317GND              VIA   -     D0100PA00X+029107Y+059049               S3      
317GND              VIA   -     D0100PA00X+029107Y+059309               S3      
317P3V3_NODE1       VIA   -     D0100PA00X+028365Y+058904               S1      
317P3V3_NODE1       VIA   -     D0100PA00X+027811Y+058924               S3      
327NNAME10650       PL12  -1          A01X+029110Y+061455X0848Y1300R180 S2      
327CPLD2_RSV2       U128  -50         A01X+028443Y+065403X0110Y0590R270 S2      
327CPLD2_RSV1       U128  -49         A01X+028443Y+065600X0110Y0590R270 S2      
327NNAME10369       U128  -48         A01X+028443Y+065797X0110Y0590R270 S2      
327NNAME10367       U128  -47         A01X+028443Y+065994X0110Y0590R270 S2      
327CPLD2_RSV1       R662  -2          A01X+027620Y+065649X0180Y0200R180 S2      
327CPLD2_RSV2       R676  -2          A01X+027620Y+065221X0180Y0200R180 S2      
327CPLD2_RSV3       R678  -2          A01X+027620Y+064812X0180Y0200R180 S2      
317NNAME10651       VIA   -     D0100PA00X+028800Y+064906               S1      
317CPLD2_RSV2       VIA   -     D0100PA00X+028088Y+065030               S1      
317CPLD2_RSV1       VIA   -     D0100PA00X+027870Y+065649               S1      
327GND              U128  -46         A01X+028443Y+066191X0110Y0590R270 S2      
327P3V3_NODE1       U128  -45         A01X+028443Y+066388X0110Y0590R270 S2      
327CPLD_WDT2        U128  -44         A01X+028443Y+066585X0110Y0590R270 S2      
327CPLD_WDT1        U128  -43         A01X+028443Y+066781X0110Y0590R270 S2      
327NNAME10432       U128  -42         A01X+028443Y+066978X0110Y0590R270 S2      
327NNAME10437       U128  -41         A01X+028443Y+067175X0110Y0590R270 S2      
327NNAME10438       U128  -40         A01X+028443Y+067372X0110Y0590R270 S2      
327NNAME10436       U128  -39         A01X+028443Y+067569X0110Y0590R270 S2      
327P3V3_NODE1       C582  -1          A01X+027620Y+066416X0180Y0200     S2      
317GND              VIA   -     D0100PA00X+028917Y+066191               S3      
317P3V3_NODE1       VIA   -     D0100PA00X+027909Y+066850               S3      
317P3V3_NODE1       VIA   -     D0100PA00X+027979Y+066388               S3      
317CPLD_WDT2        VIA   -     D0100PA00X+028937Y+066585               S3      
317NNAME10438       VIA   -     D0100PA00X+028937Y+067372               S1      
317NNAME10436       VIA   -     D0100PA00X+027984Y+067569               S1      
327NNAME10497       U128  -38         A01X+028443Y+067766X0110Y0590R270 S2      
327NNAME10498       U128  -37         A01X+028443Y+067962X0110Y0590R270 S2      
327NNAME10368       U128  -36         A01X+028443Y+068159X0110Y0590R270 S2      
327NNAME10366       U128  -35         A01X+028443Y+068356X0110Y0590R270 S2      
327NNAME10433       U128  -34         A01X+028443Y+068553X0110Y0590R270 S2      
327NNAME10431       U128  -33         A01X+028443Y+068750X0110Y0590R270 S2      
327GND              U128  -32         A01X+028443Y+068947X0110Y0590R270 S2      
327P3V3_NODE1       U128  -31         A01X+028443Y+069144X0110Y0590R270 S2      
327P3V3_NODE1       C583  -1          A01X+027620Y+069104X0180Y0200     S2      
317GND              VIA   -     D0100PA00X+028888Y+068947               S3      
317P3V3_NODE1       VIA   -     D0100PA00X+027835Y+068731               S3      
327T1_NODE1_EN      VIA   -           A10X+028239Y+068798X0260Y0260     S1      
317NNAME10368       VIA   -     D0100PA00X+027571Y+068159               S1      
317NNAME10498       VIA   -     D0100PA00X+028925Y+068052               S1      
327WDT_LED          U128  -30         A01X+028443Y+069340X0110Y0590R270 S2      
327NNAME10496       U128  -29         A01X+028443Y+069537X0110Y0590R270 S2      
327NNAME10430       U128  -28         A01X+028443Y+069734X0110Y0590R270 S2      
327NNAME10365       U128  -27         A01X+028443Y+069931X0110Y0590R270 S2      
327NNAME10370       U128  -26         A01X+028443Y+070128X0110Y0590R270 S2      
317P5V_NODE1        VIA   -     D0100PA00X+027556Y+069780               S3      
317P5V_NODE1        VIA   -     D0100PA00X+027906Y+069331               S3      
317NNAME10575       VIA   -     D0100PA00X+028476Y+070702               S3      
317NNAME10430       VIA   -     D0100PA00X+028680Y+070414               S1      
317NNAME10370       VIA   -     D0100PA00X+027837Y+070509               S1      
317WDT_LED          VIA   -     D0100PA00X+027748Y+069572               S1      
327JTAG_CPLD2_TCK   R1074 -2          A01X+028567Y+071727X0180Y0200R180 S2      
327GND              R1074 -1          A01X+028252Y+071727X0180Y0200R180 S2      
317GND              VIA   -     D0100PA00X+027834Y+071727               S3      
317NNAME10652       VIA   -     D0100PA00X+028906Y+072219               S3      
317NNAME10653       VIA   -     D0100PA00X+028183Y+072218               S3      
317NNAME10654       VIA   -     D0100PA00X+028513Y+071443               S1      
317NNAME10655       VIA   -     D0100PA00X+027588Y+072214               S1      
317NNAME10656       VIA   -     D0100PA00X+028588Y+072227               S1      
317T2_NODE3_EN      VIA   -     D0100PA00X+028915Y+071855               S3      
327GND              C716  -2          A01X+027544Y+073908X0180Y0200R090 S2      
327GND              C677  -2          A10X+028863Y+072736X0180Y0200R270 S1      
327NNAME10652       C677  -1          A10X+028863Y+073051X0180Y0200R270 S1      
327GND              C713  -2          A01X+027994Y+072758X0180Y0200R090 S2      
327NNAME10657       C713  -1          A01X+027994Y+073073X0180Y0200R090 S2      
327GND              C680  -2          A10X+028344Y+073908X0180Y0200R270 S1      
327GND              C686  -2          A10X+027544Y+073908X0180Y0200R270 S1      
327GND              C710  -2          A01X+028444Y+073908X0180Y0200R090 S2      
327GND              C683  -2          A10X+027994Y+072728X0180Y0200R270 S1      
327NNAME10653       C683  -1          A10X+027994Y+073043X0180Y0200R270 S1      
327GND              C707  -2          A01X+028894Y+072758X0180Y0200R090 S2      
327NNAME10658       C707  -1          A01X+028894Y+073073X0180Y0200R090 S2      
327NNAME10579       R953  -2          A01X+027544Y+073073X0180Y0200R270 S2      
327NNAME10655       R953  -1          A01X+027544Y+072758X0180Y0200R270 S2      
327NNAME10652       R914  -1          A10X+028744Y+073908X0180Y0200R090 S1      
327NNAME10657       R950  -1          A01X+027994Y+073908X0180Y0200R270 S2      
327NNAME10653       R920  -1          A10X+027944Y+073908X0180Y0200R090 S1      
327NNAME10658       R944  -1          A01X+028894Y+073908X0180Y0200R270 S2      
327NNAME10577       R923  -2          A10X+027544Y+073073X0180Y0200R090 S1      
327NNAME10654       R923  -1          A10X+027544Y+072758X0180Y0200R090 S1      
327NNAME10659       R947  -2          A01X+028444Y+073073X0180Y0200R270 S2      
327NNAME10656       R947  -1          A01X+028444Y+072758X0180Y0200R270 S2      
317GND              VIA   -     D0100PA00X+027994Y+072413               S3      
317GND              VIA   -     D0100PA00X+028924Y+072469               S3      
317GND              VIA   -     D0100PA00X+028399Y+073498               S3      
317NNAME10657       VIA   -     D0100PA00X+028021Y+073481               S1      
317NNAME10658       VIA   -     D0100PA00X+028839Y+073480               S1      
317T2_NODE4_EN      VIA   -     D0100PA00X+028402Y+072496               S3      
327NNAME10579       C716  -1          A01X+027544Y+074223X0180Y0200R090 S2      
327NNAME10660       C680  -1          A10X+028344Y+074223X0180Y0200R270 S1      
327NNAME10577       C686  -1          A10X+027544Y+074223X0180Y0200R270 S1      
327NNAME10659       C710  -1          A01X+028444Y+074223X0180Y0200R090 S2      
327NNAME10661       R914  -2          A10X+028744Y+074223X0180Y0200R090 S1      
327NNAME10662       R950  -2          A01X+027994Y+074223X0180Y0200R270 S2      
327NNAME10578       R920  -2          A10X+027944Y+074223X0180Y0200R090 S1      
327NNAME10663       R944  -2          A01X+028894Y+074223X0180Y0200R270 S2      
317NNAME10660       VIA   -     D0100PA00X+028453Y+074749               S1      
317NNAME10579       VIA   -     D0100PA00X+027563Y+077769               S1      
317NNAME10662       VIA   -     D0100PA00X+028193Y+077319               S1      
317NNAME10659       VIA   -     D0100PA00X+028672Y+078593               S1      
327NNAME10578       VIA   -           A10X+027855Y+078638X0260Y0260     S1      
327NNAME10661       VIA   -           A10X+028903Y+077838X0260Y0260     S1      
327GND              J35   -A24        A10X+027959Y+080787X0300Y1660R180 S1      
327NNAME10660       J35   -A23        A10X+028352Y+080787X0300Y1660R180 S1      
327NNAME10661       J35   -A22        A10X+028746Y+080787X0300Y1660R180 S1      
327NNAME10664       J35   -A21        A10X+029140Y+080787X0300Y1660R180 S1      
327NNAME10662       J35   -B24        A01X+027959Y+080787X0300Y1660R180 S2      
327NNAME10659       J35   -B23        A01X+028352Y+080787X0300Y1660R180 S2      
327NNAME10663       J35   -B22        A01X+028746Y+080787X0300Y1660R180 S2      
327GND              J35   -B21        A01X+029140Y+080787X0300Y1660R180 S2      
317GND              VIA   -     D0100PA00X+027959Y+079170               S3      
327NNAME10581       PL17  -1          A01X+029495Y+002010X0848Y1300     S2      
317GND              VIA   -     D0100PA00X+029531Y+004126               S3      
317GND              VIA   -     D0100PA00X+029539Y+004402               S3      
317GND              VIA   -     D0100PA00X+029561Y+005030               S3      
317GND              VIA   -     D0100PA00X+029556Y+005291               S3      
327PV_VDDR_NODE1    C177  -1          A01X+029289Y+007244X0280Y0320R180 S2      
327GND              C177  -2          A01X+029289Y+006664X0280Y0320R180 S2      
327PV_VDDR_NODE1    C173  -1          A01X+029829Y+007244X0280Y0320R180 S2      
327GND              C173  -2          A01X+029829Y+006664X0280Y0320R180 S2      
327PV_VDDR_NODE1    C176  -1          A01X+030369Y+007244X0280Y0320R180 S2      
327GND              C176  -2          A01X+030369Y+006664X0280Y0320R180 S2      
317GND              VIA   -     D0100PA00X+029490Y+006317               S3      
317GND              VIA   -     D0100PA00X+030669Y+006317               S3      
317GND              VIA   -     D0100PA00X+030305Y+006317               S3      
317GND              VIA   -     D0100PA00X+029888Y+006317               S3      
317PV_VDDR_NODE1    VIA   -     D0100PA00X+029231Y+007635               S3      
317PV_VDDR_NODE1    VIA   -     D0100PA00X+030588Y+007636               S3      
317PV_VDDR_NODE1    VIA   -     D0100PA00X+029922Y+007620               S3      
317PV_VDDR_NODE1    VIA   -     D0100PA00X+030295Y+007617               S3      
317PV_VDDR_NODE1    VIA   -     D0100PA00X+029587Y+007657               S3      
327GND              C154  -2          A10X+029586Y+008474X0180Y0200R090 S1      
327PV_VDDR_NODE1    C154  -1          A10X+029586Y+008159X0180Y0200R090 S1      
327GND              C171  -2          A10X+029182Y+008482X0180Y0200R090 S1      
327PV_VDDR_NODE1    C171  -1          A10X+029182Y+008167X0180Y0200R090 S1      
327PV_VDDR_NODE1    C178  -1          A10X+030622Y+007954X0280Y0320     S1      
327GND              C178  -2          A10X+030622Y+008534X0280Y0320     S1      
327PV_VDDR_NODE1    C175  -1          A10X+030082Y+007954X0280Y0320     S1      
327GND              C175  -2          A10X+030082Y+008534X0280Y0320     S1      
327NNAME10454       J2    -117        A01X+030532Y+008248X0150Y0810     S2      
327PV_VDDR_NODE1    J2    -115        A01X+030295Y+008248X0150Y0810     S2      
327NNAME10463       J2    -113        A01X+030059Y+008248X0150Y0810     S2      
327NNAME10398       J2    -111        A01X+029823Y+008248X0150Y0810     S2      
327PV_VDDR_NODE1    J2    -109        A01X+029587Y+008248X0150Y0810     S2      
327NNAME10389       J2    -107        A01X+029351Y+008248X0150Y0810     S2      
327NNAME10390       J2    -105        A01X+029114Y+008248X0150Y0810     S2      
317GND              VIA   -     D0100PA00X+029609Y+008848               S3      
317GND              VIA   -     D0100PA00X+030285Y+008906               S3      
317NNAME10463       VIA   -     D0100PA00X+030187Y+009207               S1      
317NNAME10398       VIA   -     D0100PA00X+029687Y+009207               S1      
317GND              VIA   -     D0100PA00X+029480Y+010059               S3      
317GND              VIA   -     D0100PA00X+029549Y+009721               S3      
317GND              VIA   -     D0100PA00X+030237Y+009522               S3      
317NNAME10392       VIA   -     D0100PA00X+029193Y+010299               S1      
317NNAME10389       VIA   -     D0100PA00X+029351Y+009497               S3      
317NNAME10461       VIA   -     D0100PA00X+029693Y+010299               S1      
317NNAME10454       VIA   -     D0100PA00X+030322Y+009840               S3      
327GND              C144  -2          A10X+029373Y+012491X0180Y0200R180 S1      
327PV_VDDR_NODE1    C144  -1          A10X+029688Y+012491X0180Y0200R180 S1      
327GND              C153  -2          A10X+029373Y+012091X0180Y0200R180 S1      
327PV_VDDR_NODE1    C153  -1          A10X+029688Y+012091X0180Y0200R180 S1      
327NNAME10665       J2    -118        A01X+030650Y+011476X0150Y0810     S2      
327PV_VDDR_NODE1    J2    -116        A01X+030414Y+011476X0150Y0810     S2      
327NNAME10461       J2    -114        A01X+030177Y+011476X0150Y0810     S2      
327NNAME10392       J2    -112        A01X+029941Y+011476X0150Y0810     S2      
327PV_VDDR_NODE1    J2    -110        A01X+029705Y+011476X0150Y0810     S2      
327NNAME10458       J2    -108        A01X+029469Y+011476X0150Y0810     S2      
327NNAME10386       J2    -106        A01X+029232Y+011476X0150Y0810     S2      
317PV_VDDR_NODE1    VIA   -     D0100PA00X+029959Y+012129               S3      
317PV_VDDR_NODE1    VIA   -     D0100PA00X+029985Y+012471               S3      
317GND              VIA   -     D0100PA00X+029387Y+013036               S3      
327NNAME10386       VIA   -           A01X+029538Y+014053X0300Y0300     S2      
317NNAME10454       VIA   -     D0100PA00X+030293Y+013299               S1      
327NNAME10388       VIA   -           A01X+029305Y+015500X0300Y0300     S2      
327GND              U2    -BP66       A01X+029178Y+024681X0160Y0160     S2      
327GND              U2    -BM66       A01X+029178Y+025001X0160Y0160     S2      
317GND              VIA   -     D0100PA00X+030012Y+025099               S3      
317NNAME10590       VIA   -     D0100PA00X+029618Y+024959               S3      
317NNAME10603       VIA   -     D0100PA00X+029978Y+024801               S1      
327GND              U2    -BG66       A01X+029178Y+025961X0135Y0110     S2      
327GND              U2    -BJ66       A01X+029178Y+025641X0160Y0160     S2      
327GND              U2    -BK66       A01X+029178Y+025321X0160Y0160     S2      
327GND              U2    -BE66       A01X+029232Y+026338X0100Y0135R090 S2      
317GND              VIA   -     D0100PA00X+029591Y+026671               S3      
317GND              VIA   -     D0100PA00X+029511Y+026296               S3      
317NNAME10602       VIA   -     D0100PA00X+030151Y+026220               S1      
317NNAME10604       VIA   -     D0100PA00X+030048Y+026501               S3      
317NNAME10666       VIA   -     D0100PA00X+029621Y+025319               S1      
317NNAME10598       VIA   -     D0100PA00X+030031Y+025384               S3      
317NNAME10600       VIA   -     D0100PA00X+030031Y+025724               S3      
317NNAME10599       VIA   -     D0100PA00X+029271Y+026654               S1      
327NNAME10666       U2    -BD65       A01X+029058Y+026637X0120Y0120     S2      
327GND              U2    -BB66       A01X+029232Y+026904X0100Y0135R090 S2      
327GND              U2    -AT66       A01X+029232Y+028110X0100Y0135R090 S2      
327GND              U2    -AW66       A01X+029232Y+027544X0100Y0135R090 S2      
317GND              VIA   -     D0100PA00X+029531Y+027544               S3      
317GND              VIA   -     D0100PA00X+029451Y+028071               S3      
317NNAME10611       VIA   -     D0100PA00X+030147Y+028265               S3      
317NNAME10601       VIA   -     D0100PA00X+029781Y+028071               S1      
317NNAME10605       VIA   -     D0100PA00X+030172Y+027915               S3      
327NNAME10667       U2    -AR65       A01X+029058Y+028409X0120Y0120     S2      
327GND              U2    -AN66       A01X+029232Y+028677X0100Y0135R090 S2      
327GND              U2    -AK66       A01X+029232Y+029317X0100Y0135R090 S2      
317GND              VIA   -     D0100PA00X+029778Y+029197               S3      
317GND              VIA   -     D0100PA00X+029501Y+028677               S3      
317NNAME10609       VIA   -     D0100PA00X+030118Y+029197               S3      
317NNAME10614       VIA   -     D0100PA00X+029438Y+029197               S1      
317NNAME10612       VIA   -     D0100PA00X+030513Y+028687               S3      
317NNAME10667       VIA   -     D0100PA00X+029833Y+028687               S3      
317NNAME10613       VIA   -     D0100PA00X+030173Y+028687               S3      
327NNAME10624       VIA   -           A01X+030678Y+029246X0300Y0300     S2      
327NNAME10668       R117  -2          A10X+029209Y+030688X0180Y0200     S1      
327GND              U2    -AF65       A01X+029058Y+030182X0120Y0120     S2      
327GND              U2    -AD66       A01X+029232Y+030450X0100Y0135R090 S2      
327NNAME10669       U2    -AA66       A01X+029232Y+031090X0100Y0135R090 S2      
327N/C              U2    -AG66       A01X+029232Y+029883X0100Y0135R090 S2      
317GND              VIA   -     D0100PA00X+029767Y+030071               S3      
317GND              VIA   -     D0100PA00X+029489Y+030446               S3      
317GND              VIA   -     D0100PA00X+029478Y+030979               S3      
317NNAME10626       VIA   -     D0100PA00X+030180Y+031040               S3      
317NNAME10625       VIA   -     D0100PA00X+029664Y+030806               S3      
317NNAME10669       VIA   -     D0100PA00X+030525Y+031034               S3      
317NNAME10534       VIA   -     D0100PA00X+030020Y+030087               S3      
317NNAME10620       VIA   -     D0100PA00X+030320Y+030430               S3      
327GND              C32   -2          A10X+029914Y+032265X0180Y0200R270 S1      
327N32265582        C32   -1          A10X+029914Y+032580X0180Y0200R270 S1      
327GND              C87   -2          A10X+029222Y+031856X0180Y0200R090 S1      
327PV_VCCP_NODE1    C87   -1          A10X+029222Y+031541X0180Y0200R090 S1      
327GND              C86   -2          A10X+029622Y+031856X0180Y0200R090 S1      
327PV_VCCP_NODE1    C86   -1          A10X+029622Y+031541X0180Y0200R090 S1      
327GND              C63   -2          A10X+030485Y+032338X0440Y0540R090 S1      
327PV_VCCP_NODE1    C63   -1          A10X+030485Y+031590X0440Y0540R090 S1      
327PV_VCCP_NODE1    U2    -U65        A01X+029058Y+031955X0120Y0120     S2      
327GND              U2    -M66        A01X+029232Y+032862X0100Y0135R090 S2      
327GND              U2    -R66        A01X+029232Y+032222X0100Y0135R090 S2      
327PV_VCCP_NODE1    U2    -V66        A01X+029232Y+031656X0100Y0135R090 S2      
317GND              VIA   -     D0100PA00X+029520Y+032147               S3      
317GND              VIA   -     D0100PA00X+029460Y+032813               S3      
317NNAME10635       VIA   -     D0100PA00X+029707Y+032916               S3      
327N32265582        VIA   -           A10X+029185Y+032703X0260Y0260     S1      
327P3V3_SUS_NODE1   R144  -2          A10X+030038Y+034435X0180Y0200R180 S1      
327NNAME10269       R144  -1          A10X+030353Y+034435X0180Y0200R180 S1      
327NNAME10553       R1216 -1          A10X+030646Y+033041X0180Y0200     S1      
327N32265582        R143  -1          A10X+030497Y+033438X0180Y0200     S1      
327GND              U2    -J66        A01X+029232Y+033429X0100Y0135R090 S2      
327GND              U2    -H66        A01X+029178Y+033724X0135Y0110     S2      
327GND              U2    -F66        A01X+029178Y+034044X0160Y0160     S2      
327GND              U2    -E66        A01X+029178Y+034364X0160Y0160     S2      
317GND              VIA   -     D0100PA00X+029422Y+034359               S3      
317GND              VIA   -     D0100PA00X+029489Y+033533               S3      
317NNAME10670       VIA   -     D0100PA00X+029845Y+034049               S3      
317NNAME10631       VIA   -     D0100PA00X+030588Y+033905               S1      
317NNAME10269       VIA   -     D0100PA00X+030682Y+034215               S3      
317NNAME10636       VIA   -     D0100PA00X+029941Y+033120               S1      
327P3V3_SUS_NODE1   VIA   -           A10X+030053Y+033708X0260Y0260     S1      
317NNAME10553       VIA   -     D0100PA00X+030376Y+033148               S3      
327GND              U2    -A66        A01X+029178Y+035004X0160Y0160     S2      
327GND              U2    -C66        A01X+029178Y+034684X0160Y0160     S2      
317GND              VIA   -     D0100PA00X+029462Y+034829               S3      
317GND              VIA   -     D0100PA00X+029347Y+035244               S3      
317NNAME10638       VIA   -     D0100PA00X+030545Y+035945               S3      
327NNAME10634       VIA   -           A10X+029622Y+035369X0260Y0260     S1      
317NNAME10556       VIA   -     D0100PA00X+029553Y+035981               S1      
327P3V3_NODE1       R153  -2          A01X+030514Y+037217X0180Y0200R270 S2      
327NNAME10556       R153  -1          A01X+030514Y+036902X0180Y0200R270 S2      
327NNAME10634       R96   -2          A10X+029713Y+036902X0180Y0200R270 S1      
327GND              R96   -1          A10X+029713Y+037217X0180Y0200R270 S1      
327NNAME10634       R94   -2          A10X+030113Y+036902X0180Y0200R270 S1      
327P3V3_NODE1       R94   -1          A10X+030113Y+037217X0180Y0200R270 S1      
327GND              R160  -2          A01X+029714Y+037217X0180Y0200R270 S2      
327NNAME10557       R160  -1          A01X+029714Y+036902X0180Y0200R270 S2      
327GND              R154  -2          A01X+029314Y+037217X0180Y0200R270 S2      
327NNAME10551       R154  -1          A01X+029314Y+036902X0180Y0200R270 S2      
327P3V3_NODE1       R157  -2          A01X+030114Y+037217X0180Y0200R270 S2      
327NNAME10557       R157  -1          A01X+030114Y+036902X0180Y0200R270 S2      
317GND              VIA   -     D0100PA00X+029820Y+037457               S3      
317P3V3_NODE1       VIA   -     D0100PA00X+030317Y+037422               S3      
317P3V3_NODE1       VIA   -     D0100PA00X+029169Y+037518               S3      
317NNAME10110       VIA   -     D0100PA00X+029539Y+037564               S3      
327NNAME10557       VIA   -           A01X+029361Y+036431X0300Y0300     S2      
327P3V3_STB_NODE1   OSC5  -4          A01X+030681Y+039010X0380Y0480     S2      
327NNAME10671       OSC5  -3          A01X+030681Y+038144X0380Y0480     S2      
327GND              OSC5  -2          A01X+029992Y+038144X0380Y0480     S2      
327NNAME10672       OSC5  -1          A01X+029992Y+039010X0380Y0480     S2      
327P3V3_NODE1       R105  -2          A01X+029273Y+038232X0180Y0200R270 S2      
327NNAME10555       R105  -1          A01X+029273Y+037917X0180Y0200R270 S2      
317GND              VIA   -     D0100PA00X+030372Y+038537               S3      
317LAN2_DISABLE_N   VIA   -     D0100PA00X+029329Y+038974               S1      
317P3V3_NODE1       VIA   -     D0100PA00X+029138Y+038546               S3      
327NNAME10672       R1051 -2          A01X+030119Y+039843X0180Y0200     S2      
327P3V3_STB_NODE1   R1051 -1          A01X+030434Y+039843X0180Y0200     S2      
317NNAME10672       VIA   -     D0100PA00X+029953Y+039406               S1      
317P1V8_NODE1       VIA   -     D0100PA00X+029186Y+044293               S3      
317P1V8_NODE1       VIA   -     D0100PA00X+029217Y+044599               S3      
317GND              VIA   -     D0100PA00X+030124Y+047089               S3      
317GND              VIA   -     D0100PA00X+029133Y+046681               S3      
317P3V3_SUS_NODE1   VIA   -     D0100PA00X+030004Y+045973               S1      
327NNAME10644       C202  -2          A01X+029443Y+047193X0180Y0200     S2      
327NNAME10673       C202  -1          A01X+029758Y+047193X0180Y0200     S2      
327NNAME10645       C203  -2          A01X+029439Y+047624X0180Y0200     S2      
327NNAME10674       C203  -1          A01X+029754Y+047624X0180Y0200     S2      
327GND              C283  -2          A10X+029674Y+048783X0280Y0320R180 S1      
317GND              VIA   -     D0100PA00X+030622Y+047713               S3      
317NNAME10674       VIA   -     D0100PA00X+030363Y+047561               S3      
317NNAME10673       VIA   -     D0100PA00X+030363Y+047261               S3      
327P1V8_NODE1       VIA   -           A10X+029822Y+047885X0260Y0260     S1      
327PD_BMC_LPC       U14   -A22        A01X+029190Y+049787X0145Y0145R270 S2      
327PD_BMC_LPC       U14   -A21        A01X+029190Y+050102X0145Y0145R270 S2      
327GND              C284  -2          A10X+030628Y+049785X0180Y0200     S1      
327NNAME10646       C284  -1          A10X+030313Y+049785X0180Y0200     S1      
327GND              C285  -2          A10X+030628Y+049385X0180Y0200     S1      
327NNAME10646       C285  -1          A10X+030313Y+049385X0180Y0200     S1      
327NNAME10646       C283  -1          A10X+029674Y+049363X0280Y0320R180 S1      
317GND              VIA   -     D0100PA00X+030121Y+048885               S3      
317GND              VIA   -     D0100PA00X+030371Y+048935               S3      
317NNAME10646       VIA   -     D0100PA00X+029737Y+049856               S1      
317NNAME10646       VIA   -     D0100PA00X+030021Y+049585               S3      
317PD_BMC_LPC       VIA   -     D0100PA00X+030571Y+050304               S1      
327N/C              U14   -A20        A01X+029190Y+050417X0145Y0145R270 S2      
327N/C              U14   -A19        A01X+029190Y+050732X0145Y0145R270 S2      
327N/C              U14   -A18        A01X+029190Y+051047X0145Y0145R270 S2      
327N/C              U14   -A17        A01X+029190Y+051362X0145Y0145R270 S2      
327N/C              U14   -A16        A01X+029190Y+051677X0145Y0145R270 S2      
327PD_BMC_LPC       R1230 -2          A10X+030571Y+050782X0180Y0200R270 S1      
327GND              R1230 -1          A10X+030571Y+051097X0180Y0200R270 S1      
327GND              R256  -2          A10X+029691Y+051098X0180Y0200R090 S1      
327NNAME10647       R256  -1          A10X+029691Y+050783X0180Y0200R090 S1      
327LPC_CLK_AST      R258  -2          A10X+030146Y+050783X0180Y0200R270 S1      
327GND              R258  -1          A10X+030146Y+051098X0180Y0200R270 S1      
317GND              VIA   -     D0100PA00X+029691Y+051446               S3      
317GND              VIA   -     D0100PA00X+030146Y+051384               S3      
327N/C              U14   -A15        A01X+029190Y+051992X0145Y0145R270 S2      
327N/C              U14   -A14        A01X+029190Y+052307X0145Y0145R270 S2      
327N/C              U14   -A13        A01X+029190Y+052622X0145Y0145R270 S2      
327N/C              U14   -A12        A01X+029190Y+052937X0145Y0145R270 S2      
327GND              U14   -A11        A01X+029190Y+053252X0145Y0145R270 S2      
317GND              VIA   -     D0100PA00X+029347Y+053409               S3      
327N/C              U14   -A10        A01X+029190Y+053567X0145Y0145R270 S2      
327GND              U14   -A9         A01X+029190Y+053882X0145Y0145R270 S2      
327N/C              U14   -A8         A01X+029190Y+054197X0145Y0145R270 S2      
327N/C              U14   -A7         A01X+029190Y+054512X0145Y0145R270 S2      
327N/C              U14   -A6         A01X+029190Y+054827X0145Y0145R270 S2      
327N3975090765      TP5   -1          A10X+029634Y+054876X0300Y0300     S1      
317GND              VIA   -     D0100PA00X+029347Y+054039               S3      
327N/C              U14   -A5         A01X+029190Y+055142X0145Y0145R270 S2      
327N3975090766      U14   -A4         A01X+029190Y+055457X0145Y0145R270 S2      
327GND              U14   -A3         A01X+029190Y+055772X0145Y0145R270 S2      
327GND              U14   -A2         A01X+029190Y+056086X0145Y0145R270 S2      
327GND              U14   -A1         A01X+029190Y+056401X0145Y0145R270 S2      
327N3975090766      TP6   -1          A10X+030085Y+055625X0300Y0300     S1      
317GND              VIA   -     D0100PA00X+029347Y+056559               S3      
317GND              VIA   -     D0100PA00X+029347Y+056244               S3      
317GND              VIA   -     D0100PA00X+029347Y+055929               S3      
317N3975090766      VIA   -     D0100PA00X+029505Y+055457               S3      
317NNAME10207       VIA   -     D0100PA00X+030441Y+057278               S1      
327N20822523        VIA   -           A10X+029491Y+057865X0260Y0260     S1      
327GND              PC3   -2          A10X+029518Y+059563X0460Y0620R180 S1      
327P12V_AUX         PC3   -1          A10X+030678Y+059563X0460Y0620R180 S1      
327GND              PC1   -2          A01X+029506Y+059171X0460Y0620     S2      
327P12V_AUX         PC1   -1          A01X+030666Y+059171X0460Y0620     S2      
327GND              R293  -2          A10X+029491Y+058613X0180Y0200R090 S1      
327N20822523        R293  -1          A10X+029491Y+058298X0180Y0200R090 S1      
317GND              VIA   -     D0100PA00X+029136Y+058613               S3      
317GND              VIA   -     D0100PA00X+029912Y+059754               S3      
327NNAME10675       PU1   -12         A01X+030452Y+060626X0100Y0330R270 S2      
327NNAME10650       PU1   -11         A01X+030452Y+060823X0100Y0330R270 S2      
327NNAME10650       PU1   -10         A01X+030452Y+061020X0100Y0330R270 S2      
327NNAME10650       PU1   -9          A01X+030452Y+061217X0100Y0330R270 S2      
327NNAME10650       PC4   -2          A01X+029897Y+060864X0180Y0200R270 S2      
327NNAME10675       PC4   -1          A01X+029897Y+060549X0180Y0200R270 S2      
327GND              PC2   -2          A01X+030170Y+059781X0180Y0200     S2      
327P12V_AUX         PC2   -1          A01X+030485Y+059781X0180Y0200     S2      
317P12V_AUX         VIA   -     D0100PA00X+030623Y+060026               S3      
317NNAME10675       VIA   -     D0100PA00X+030180Y+060392               S1      
317NNAME10650       VIA   -     D0100PA00X+029830Y+061318               S1      
327GND              PC25  -2          A01X+030204Y+062388X0180Y0200     S2      
327NNAME10676       PC25  -1          A01X+030519Y+062388X0180Y0200     S2      
317GND              VIA   -     D0100PA00X+030560Y+062069               S3      
317GND              VIA   -     D0100PA00X+030560Y+061819               S3      
317GND              VIA   -     D0100PA00X+029963Y+062388               S3      
327P3V3_NODE1       R793  -2          A10X+030058Y+064221X0180Y0200R180 S1      
327CPLD_WDT2_R      R793  -1          A10X+030373Y+064221X0180Y0200R180 S1      
317GND              VIA   -     D0100PA00X+029909Y+063442               S3      
317P3V3_NODE1       VIA   -     D0100PA00X+030287Y+063398               S3      
317P3V3_NODE1       VIA   -     D0100PA00X+029716Y+064207               S3      
317CPLD2_RSV3       VIA   -     D0100PA00X+029384Y+064254               S1      
317TACKOVER_EN_N    VIA   -     D0100PA00X+030311Y+063938               S3      
327TACKOVER_EN_N    U128  -58         A01X+030510Y+064714X0110Y0590     S2      
327NNAME10653       U128  -57         A01X+030313Y+064714X0110Y0590     S2      
327NNAME10654       U128  -56         A01X+030116Y+064714X0110Y0590     S2      
327NNAME10652       U128  -55         A01X+029919Y+064714X0110Y0590     S2      
327NNAME10677       U128  -54         A01X+029722Y+064714X0110Y0590     S2      
327NNAME10678       U128  -53         A01X+029526Y+064714X0110Y0590     S2      
327NNAME10651       U128  -52         A01X+029329Y+064714X0110Y0590     S2      
327CPLD2_RSV3       U128  -51         A01X+029132Y+064714X0110Y0590     S2      
327NNAME10664       R911  -2          A10X+029242Y+065239X0180Y0200R090 S1      
327NNAME10651       R911  -1          A10X+029242Y+064924X0180Y0200R090 S1      
327NNAME10660       R917  -2          A10X+029645Y+064920X0180Y0200R270 S1      
327NNAME10677       R917  -1          A10X+029645Y+065235X0180Y0200R270 S1      
327CPLD_WDT2_R      R622  -2          A10X+030373Y+064619X0180Y0200     S1      
327CPLD_WDT2        R622  -1          A10X+030058Y+064619X0180Y0200     S1      
317GND              VIA   -     D0100PA00X+030520Y+065288               S3      
317NNAME10660       VIA   -     D0100PA00X+030107Y+065592               S3      
317NNAME10664       VIA   -     D0100PA00X+029285Y+065636               S3      
317P3V3_NODE1       VIA   -     D0100PA00X+030487Y+065575               S3      
317P3V3_NODE1       VIA   -     D0100PA00X+030629Y+065916               S3      
317NNAME10677       VIA   -     D0100PA00X+029739Y+065703               S1      
317NNAME10653       VIA   -     D0100PA00X+030277Y+065960               S1      
317NNAME10654       VIA   -     D0100PA00X+030136Y+065218               S3      
317P3V3_NODE1       VIA   -     D0100PA00X+030629Y+066716               S3      
317P3V3_NODE1       VIA   -     D0100PA00X+030629Y+066316               S3      
317P5V_NODE1        VIA   -     D0100PA00X+030629Y+067516               S3      
317P5V_NODE1        VIA   -     D0100PA00X+030629Y+067116               S3      
317NNAME10652       VIA   -     D0100PA00X+030088Y+066430               S1      
317CPLD_WDT1        VIA   -     D0100PA00X+029412Y+066839               S3      
317NNAME10678       VIA   -     D0100PA00X+029589Y+066266               S1      
317TACKOVER_EN_N    VIA   -     D0100PA00X+029777Y+067472               S3      
317P5V_NODE1        VIA   -     D0100PA00X+030598Y+069116               S3      
317P5V_NODE1        VIA   -     D0100PA00X+030615Y+068316               S3      
317P5V_NODE1        VIA   -     D0100PA00X+030598Y+068716               S3      
317P5V_NODE1        VIA   -     D0100PA00X+030629Y+067916               S3      
317CPLD_WDT2        VIA   -     D0100PA00X+029297Y+068245               S3      
317NNAME10575       VIA   -     D0100PA00X+029595Y+068952               S1      
317NNAME10497       VIA   -     D0100PA00X+029307Y+067711               S1      
327JTAG_CPLD2_TDO   U128  -25         A01X+029132Y+070817X0110Y0590     S2      
327JTAG_CPLD2_TCK   U128  -24         A01X+029329Y+070817X0110Y0590     S2      
327JTAG_CPLD2_TDI   U128  -23         A01X+029526Y+070817X0110Y0590     S2      
327JTAG_CPLD2_TMS   U128  -22         A01X+029722Y+070817X0110Y0590     S2      
327UART_SDC_RX      U128  -21         A01X+029919Y+070817X0110Y0590     S2      
327UART_SDC_TX      U128  -20         A01X+030116Y+070817X0110Y0590     S2      
327UART_RI_P4_N     U128  -19         A01X+030313Y+070817X0110Y0590     S2      
327UART_RTS_P4_N    U128  -18         A01X+030510Y+070817X0110Y0590     S2      
327GND              R1165 -2          A10X+029964Y+070705X0180Y0200R270 S1      
327GND              R1166 -2          A10X+030354Y+070705X0180Y0200R270 S1      
317UART_SDC_RX      VIA   -     D0100PA00X+029686Y+070254               S1      
317UART_SDC_TX      VIA   -     D0100PA00X+029730Y+069722               S1      
317GND              VIA   -     D0100PA00X+030170Y+070185               S3      
317GND              VIA   -     D0100PA00X+030170Y+069935               S3      
317JTAG_CPLD2_TCK   VIA   -     D0100PA00X+029329Y+070350               S3      
317UART_RI_P4_N     VIA   -     D0100PA00X+030599Y+069719               S3      
327UART_RTS_P4_N    R1165 -1          A10X+029964Y+071020X0180Y0200R270 S1      
327JTAG_CPLD2_TMS   R1075 -2          A01X+030080Y+071721X0180Y0200     S2      
327P3V3_NODE1       R1075 -1          A01X+030395Y+071721X0180Y0200     S2      
327JTAG_CPLD2_TDI   R1076 -2          A01X+029672Y+072108X0180Y0200     S2      
327P3V3_NODE1       R1076 -1          A01X+029987Y+072108X0180Y0200     S2      
327UART_DTR_P4_N    R1166 -1          A10X+030354Y+071020X0180Y0200R270 S1      
317UART_RTS_P4_N    VIA   -     D0100PA00X+030368Y+071442               S3      
317P3V3_NODE1       VIA   -     D0100PA00X+030521Y+072039               S3      
317T2_NODE2_EN      VIA   -     D0100PA00X+029330Y+071894               S1      
317JTAG_CPLD2_TDI   VIA   -     D0100PA00X+029689Y+071806               S3      
317JTAG_CPLD2_TMS   VIA   -     D0100PA00X+029722Y+071552               S3      
317JTAG_CPLD2_TDO   VIA   -     D0100PA00X+029132Y+071388               S3      
327GND              C655  -2          A10X+029944Y+073908X0180Y0200R270 S1      
327GND              C674  -2          A10X+029144Y+073908X0180Y0200R270 S1      
327GND              C698  -2          A01X+030244Y+073908X0180Y0200R090 S2      
327GND              C671  -2          A10X+029284Y+072952X0180Y0200R270 S1      
327NNAME10678       C671  -1          A10X+029284Y+073267X0180Y0200R270 S1      
327GND              C701  -2          A01X+029794Y+072758X0180Y0200R090 S2      
327NNAME10679       C701  -1          A01X+029794Y+073073X0180Y0200R090 S2      
327GND              C704  -2          A01X+029344Y+073908X0180Y0200R090 S2      
327GND              C652  -2          A10X+030344Y+073908X0180Y0200R270 S1      
327T3_NODE4_EN_R    R892  -2          A10X+030145Y+072935X0180Y0200R090 S1      
327T3_NODE4_EN      R892  -1          A10X+030145Y+072620X0180Y0200R090 S1      
327NNAME10678       R908  -1          A10X+029544Y+073908X0180Y0200R090 S1      
327NNAME10679       R938  -1          A01X+029794Y+073908X0180Y0200R270 S2      
327NNAME10680       R941  -2          A01X+029344Y+073073X0180Y0200R270 S2      
327NNAME10681       R941  -1          A01X+029344Y+072758X0180Y0200R270 S2      
327T3_NODE3_EN_R    R889  -2          A10X+030564Y+073094X0180Y0200R090 S1      
327T3_NODE3_EN      R889  -1          A10X+030564Y+072779X0180Y0200R090 S1      
317GND              VIA   -     D0100PA00X+029179Y+073598               S3      
317GND              VIA   -     D0100PA00X+030654Y+072427               S3      
317GND              VIA   -     D0100PA00X+029794Y+072438               S3      
317GND              VIA   -     D0100PA00X+030266Y+073636               S3      
317GND              VIA   -     D0100PA00X+029816Y+073649               S3      
317NNAME10682       VIA   -     D0100PA00X+030281Y+073381               S3      
317NNAME10679       VIA   -     D0100PA00X+029859Y+073367               S1      
317NNAME10681       VIA   -     D0100PA00X+029348Y+072508               S1      
317NNAME10678       VIA   -     D0100PA00X+029570Y+073313               S3      
327T3_NODE4_EN_R    C655  -1          A10X+029944Y+074223X0180Y0200R270 S1      
327NNAME10664       C674  -1          A10X+029144Y+074223X0180Y0200R270 S1      
327NNAME10682       C698  -1          A01X+030244Y+074223X0180Y0200R090 S2      
327NNAME10680       C704  -1          A01X+029344Y+074223X0180Y0200R090 S2      
327T3_NODE3_EN_R    C652  -1          A10X+030344Y+074223X0180Y0200R270 S1      
327NNAME10683       R908  -2          A10X+029544Y+074223X0180Y0200R090 S1      
327NNAME10684       R938  -2          A01X+029794Y+074223X0180Y0200R270 S2      
317NNAME10664       VIA   -     D0100PA00X+029344Y+074838               S1      
317NNAME10663       VIA   -     D0100PA00X+029134Y+077122               S1      
317NNAME10680       VIA   -     D0100PA00X+029510Y+078627               S1      
317NNAME10684       VIA   -     D0100PA00X+029925Y+077140               S1      
317NNAME10682       VIA   -     D0100PA00X+030474Y+077728               S1      
327NNAME10683       VIA   -           A10X+029728Y+077894X0260Y0260     S1      
327T3_NODE4_EN_R    VIA   -           A10X+030244Y+078473X0260Y0260     S1      
327NNAME10683       J35   -A20        A10X+029534Y+080787X0300Y1660R180 S1      
327GND              J35   -A19        A10X+029927Y+080787X0300Y1660R180 S1      
327T3_NODE4_EN_R    J35   -A18        A10X+030321Y+080787X0300Y1660R180 S1      
327T3_NODE3_EN_R    J35   -A17        A10X+030715Y+080787X0300Y1660R180 S1      
327NNAME10680       J35   -B20        A01X+029534Y+080787X0300Y1660R180 S2      
327NNAME10684       J35   -B19        A01X+029927Y+080787X0300Y1660R180 S2      
327NNAME10682       J35   -B18        A01X+030321Y+080787X0300Y1660R180 S2      
327NNAME10685       J35   -B17        A01X+030715Y+080590X0300Y1260R180 S2      
317GND              VIA   -     D0100PA00X+029140Y+079223               S3      
317GND              VIA   -     D0100PA00X+029927Y+079170               S3      
327P3V3_NODE1       PL17  -2          A01X+031798Y+002010X0848Y1300     S2      
317P3V3_NODE1       VIA   -     D0100PA00X+031733Y+001096               S3      
317P3V3_NODE1       VIA   -     D0100PA00X+032264Y+000977               S3      
317P3V3_NODE1       VIA   -     D0100PA00X+031733Y+002896               S3      
327GND              C145  -2          A01X+031647Y+006803X0180Y0200R090 S2      
327PV_VDDR_NODE1    C145  -1          A01X+031647Y+007118X0180Y0200R090 S2      
327GND              C149  -2          A01X+031247Y+006803X0180Y0200R090 S2      
327PV_VDDR_NODE1    C149  -1          A01X+031247Y+007118X0180Y0200R090 S2      
327GND              C166  -2          A01X+030847Y+006803X0180Y0200R090 S2      
327PV_VDDR_NODE1    C166  -1          A01X+030847Y+007118X0180Y0200R090 S2      
327GND              C148  -2          A01X+032047Y+006803X0180Y0200R090 S2      
327PV_VDDR_NODE1    C148  -1          A01X+032047Y+007118X0180Y0200R090 S2      
317GND              VIA   -     D0100PA00X+031464Y+006317               S3      
317GND              VIA   -     D0100PA00X+031048Y+006317               S3      
317GND              VIA   -     D0100PA00X+031854Y+006317               S3      
317GND              VIA   -     D0100PA00X+032271Y+006317               S3      
317PV_VDDR_NODE1    VIA   -     D0100PA00X+031891Y+007460               S3      
317PV_VDDR_NODE1    VIA   -     D0100PA00X+031431Y+007454               S3      
317PV_VDDR_NODE1    VIA   -     D0100PA00X+030774Y+007426               S3      
317PV_VDDR_NODE1    VIA   -     D0100PA00X+030973Y+007623               S3      
317PV_VDDR_NODE1    VIA   -     D0100PA00X+032128Y+007633               S3      
317PV_VDDR_NODE1    VIA   -     D0100PA00X+031662Y+007605               S3      
317PV_VDDR_NODE1    VIA   -     D0100PA00X+031240Y+007659               S3      
327GND              C146  -2          A10X+031094Y+008482X0180Y0200R090 S1      
327PV_VDDR_NODE1    C146  -1          A10X+031094Y+008167X0180Y0200R090 S1      
327GND              C165  -2          A10X+031901Y+008464X0180Y0200R090 S1      
327PV_VDDR_NODE1    C165  -1          A10X+031901Y+008149X0180Y0200R090 S1      
327GND              C167  -2          A10X+031493Y+008471X0180Y0200R090 S1      
327PV_VDDR_NODE1    C167  -1          A10X+031493Y+008156X0180Y0200R090 S1      
327PV_VDDR_NODE1    J2    -131        A01X+032185Y+008248X0150Y0810     S2      
327NNAME10450       J2    -129        A01X+031949Y+008248X0150Y0810     S2      
327NNAME10452       J2    -127        A01X+031713Y+008248X0150Y0810     S2      
327NNAME10451       J2    -125        A01X+031477Y+008248X0150Y0810     S2      
327PV_VDDR_NODE1    J2    -123        A01X+031240Y+008248X0150Y0810     S2      
327NNAME10449       J2    -121        A01X+031004Y+008248X0150Y0810     S2      
327NNAME10447       J2    -119        A01X+030768Y+008248X0150Y0810     S2      
317GND              VIA   -     D0100PA00X+031483Y+009285               S3      
317GND              VIA   -     D0100PA00X+031218Y+008884               S3      
317GND              VIA   -     D0100PA00X+032146Y+008852               S3      
317NNAME10451       VIA   -     D0100PA00X+031508Y+009021               S3      
317NNAME10449       VIA   -     D0100PA00X+031155Y+009235               S1      
317NNAME10665       VIA   -     D0100PA00X+031085Y+009962               S1      
317NNAME10450       VIA   -     D0100PA00X+032074Y+009860               S1      
317NNAME10447       VIA   -     D0100PA00X+031222Y+009641               S3      
317NNAME10452       VIA   -     D0100PA00X+031797Y+009596               S3      
327GND              C157  -2          A10X+031379Y+011566X0180Y0200R270 S1      
327PV_VDDR_NODE1    C157  -1          A10X+031379Y+011881X0180Y0200R270 S1      
327NNAME10456       J2    -130        A01X+032067Y+011476X0150Y0810     S2      
327NNAME10455       J2    -128        A01X+031831Y+011476X0150Y0810     S2      
327NNAME10462       J2    -126        A01X+031595Y+011476X0150Y0810     S2      
327PV_VDDR_NODE1    J2    -124        A01X+031358Y+011476X0150Y0810     S2      
327NNAME10453       J2    -122        A01X+031122Y+011476X0150Y0810     S2      
327NNAME10686       J2    -120        A01X+030886Y+011476X0150Y0810     S2      
317PV_VDDR_NODE1    VIA   -     D0100PA00X+031358Y+012239               S3      
327NNAME10453       VIA   -           A01X+031489Y+014090X0300Y0300     S2      
327NNAME10458       VIA   -           A01X+030757Y+014960X0300Y0300     S2      
327NNAME10462       VIA   -           A01X+031560Y+018981X0300Y0300     S2      
317GND              VIA   -     D0100PA00X+031142Y+025023               S3      
317NNAME10589       VIA   -     D0100PA00X+031129Y+024725               S1      
317GND              VIA   -     D0100PA00X+031541Y+025866               S3      
317NNAME10594       VIA   -     D0100PA00X+031268Y+025835               S3      
327P1V05_NODE1      R114  -2          A01X+031647Y+029585X0180Y0200R180 S2      
327NNAME10534       R114  -1          A01X+031332Y+029585X0180Y0200R180 S2      
327NNAME10624       R103  -2          A01X+032037Y+029265X0180Y0200R090 S2      
327P1V05_NODE1      R103  -1          A01X+032037Y+029580X0180Y0200R090 S2      
327NNAME10537       VIA   -           A10X+031502Y+029526X0260Y0260     S1      
327NNAME10467       VIA   -           A10X+030935Y+029194X0260Y0260     S1      
327NNAME10687       R91   -2          A10X+031757Y+030280X0180Y0200     S1      
327NNAME10539       R91   -1          A10X+031442Y+030280X0180Y0200     S1      
327NNAME10623       R74   -2          A01X+031332Y+030389X0180Y0200     S2      
327P1V05_NODE1      R74   -1          A01X+031647Y+030389X0180Y0200     S2      
327NNAME10669       R76   -2          A01X+031317Y+030784X0180Y0200     S2      
327P1V05_NODE1      R76   -1          A01X+031632Y+030784X0180Y0200     S2      
327GND              R78   -2          A01X+031659Y+029995X0180Y0200R180 S2      
327NNAME10620       R78   -1          A01X+031344Y+029995X0180Y0200R180 S2      
327NNAME10688       R118  -2          A10X+031761Y+030688X0180Y0200     S1      
327NNAME10625       R118  -1          A10X+031446Y+030688X0180Y0200     S1      
317NNAME10623       VIA   -     D0100PA00X+030720Y+030421               S3      
327NNAME10625       VIA   -           A10X+030980Y+030610X0260Y0260     S1      
317PV_VCCP_NODE1    VIA   -     D0100PA00X+031062Y+031359               S3      
317PV_VCCP_NODE1    VIA   -     D0100PA00X+031312Y+031359               S3      
317PV_VCCP_NODE1    VIA   -     D0100PA00X+032062Y+031359               S3      
317PV_VCCP_NODE1    VIA   -     D0100PA00X+031812Y+031359               S3      
317PV_VCCP_NODE1    VIA   -     D0100PA00X+031562Y+031359               S3      
327GND              C70   -2          A01X+031464Y+031923X0180Y0200R270 S2      
327PV_VCCP_NODE1    C70   -1          A01X+031464Y+031608X0180Y0200R270 S2      
327GND              C82   -2          A01X+031864Y+031923X0180Y0200R270 S2      
327PV_VCCP_NODE1    C82   -1          A01X+031864Y+031608X0180Y0200R270 S2      
327GND              C85   -2          A01X+031064Y+031923X0180Y0200R270 S2      
327PV_VCCP_NODE1    C85   -1          A01X+031064Y+031608X0180Y0200R270 S2      
327P3V3_NODE1       R169  -2          A10X+031923Y+032639X0180Y0200     S1      
327NNAME10629       R169  -1          A10X+031608Y+032639X0180Y0200     S1      
327GND              R170  -2          A01X+031923Y+032639X0180Y0200R180 S2      
327NNAME10629       R170  -1          A01X+031608Y+032639X0180Y0200R180 S2      
317GND              VIA   -     D0100PA00X+032164Y+032193               S3      
317GND              VIA   -     D0100PA00X+030914Y+032193               S3      
317GND              VIA   -     D0100PA00X+031164Y+032193               S3      
317GND              VIA   -     D0100PA00X+031414Y+032193               S3      
317GND              VIA   -     D0100PA00X+031664Y+032193               S3      
317GND              VIA   -     D0100PA00X+031914Y+032193               S3      
317GND              VIA   -     D0100PA00X+032277Y+032772               S3      
317NNAME10629       VIA   -     D0100PA00X+031174Y+032584               S1      
327PV_VCCP_NODE1    VIA   -           A10X+031667Y+031656X0260Y0260     S1      
327GND              C23   -2          A01X+031639Y+033832X0180Y0200R180 S2      
327NNAME10636       C23   -1          A01X+031324Y+033832X0180Y0200R180 S2      
327GND              C33   -2          A10X+031319Y+034235X0180Y0200R090 S1      
327P3V3_RTC_NODE1   C33   -1          A10X+031319Y+033920X0180Y0200R090 S1      
327P3V3_NODE1       R1216 -2          A10X+030961Y+033041X0180Y0200     S1      
327P3V3_RTC_NODE1   R143  -2          A10X+030812Y+033438X0180Y0200     S1      
327NNAME10631       R112  -2          A01X+031324Y+034242X0180Y0200     S2      
327P3V3_SUS_NODE1   R112  -1          A01X+031639Y+034242X0180Y0200     S2      
327NNAME10630       R64   -2          A01X+032111Y+033401X0180Y0200R270 S2      
327NNAME10628       R64   -1          A01X+032111Y+033086X0180Y0200R270 S2      
317GND              VIA   -     D0100PA00X+032221Y+033670               S3      
317GND              VIA   -     D0100PA00X+031932Y+033832               S3      
317GND              VIA   -     D0100PA00X+030951Y+034413               S3      
317P3V3_NODE1       VIA   -     D0100PA00X+031398Y+033581               S3      
317NNAME10628       VIA   -     D0100PA00X+031455Y+033156               S1      
317NNAME10630       VIA   -     D0100PA00X+031848Y+033504               S1      
317P3V3_SUS_NODE1   VIA   -     D0100PA00X+032113Y+034242               S3      
317P3V3_RTC_NODE1   VIA   -     D0100PA00X+030919Y+033696               S3      
327GND              R166  -2          A01X+031639Y+035438X0180Y0200R180 S2      
327NNAME10637       R166  -1          A01X+031324Y+035438X0180Y0200R180 S2      
327P3V3_RTC_NODE1   R163  -2          A01X+031639Y+035838X0180Y0200R180 S2      
327NNAME10637       R163  -1          A01X+031324Y+035838X0180Y0200R180 S2      
327NNAME10631       R49   -2          A01X+031324Y+035038X0180Y0200     S2      
327NNAME10689       R49   -1          A01X+031639Y+035038X0180Y0200     S2      
327NNAME10631       R48   -2          A01X+031324Y+034638X0180Y0200     S2      
327P3V3_NODE1       R48   -1          A01X+031639Y+034638X0180Y0200     S2      
317GND              VIA   -     D0100PA00X+031967Y+035438               S3      
317P3V3_NODE1       VIA   -     D0100PA00X+031981Y+034638               S3      
317P3V3_RTC_NODE1   VIA   -     D0100PA00X+032115Y+035773               S3      
327NNAME10637       VIA   -           A01X+030742Y+035438X0300Y0300     S2      
317NNAME10689       VIA   -     D0100PA00X+031929Y+035038               S1      
317NNAME10632       VIA   -     D0100PA00X+030741Y+034838               S1      
327NNAME10638       R142  -2          A01X+031102Y+036251X0180Y0200     S2      
327GND              R142  -1          A01X+031417Y+036251X0180Y0200     S2      
327NNAME10556       R156  -2          A01X+030914Y+036902X0180Y0200R090 S2      
327GND              R156  -1          A01X+030914Y+037217X0180Y0200R090 S2      
317GND              VIA   -     D0100PA00X+030913Y+037457               S3      
317GND              VIA   -     D0100PA00X+031486Y+036766               S3      
317NNAME10670       VIA   -     D0100PA00X+031322Y+037423               S1      
317P3V3_SUS_NODE1   VIA   -     D0100PA00X+032226Y+037194               S3      
317P3V3_SUS_NODE1   VIA   -     D0100PA00X+032130Y+036774               S1      
317P3V3_SUS_NODE1   VIA   -     D0100PA00X+031936Y+037215               S3      
327GND              C795  -2          A01X+031282Y+038786X0180Y0200R090 S2      
327P3V3_STB_NODE1   C795  -1          A01X+031282Y+039101X0180Y0200R090 S2      
327NNAME10670       R1052 -2          A01X+031322Y+037898X0180Y0200R090 S2      
327NNAME10671       R1052 -1          A01X+031322Y+038213X0180Y0200R090 S2      
327NNAME10540       R139  -2          A10X+031633Y+037897X0180Y0200     S1      
327NNAME10670       R139  -1          A10X+031318Y+037897X0180Y0200     S1      
327P3V3_SUS_NODE1   R1102 -2          A01X+032013Y+038057X0180Y0200R180 S2      
327GND              R1102 -1          A01X+031698Y+038057X0180Y0200R180 S2      
327P3V3_SUS_NODE1   Q31   -2          A01X+032140Y+038613X0140Y0200     S2      
327P3V3_SUS_NODE1   Q31   -1          A01X+031885Y+038613X0140Y0200     S2      
327P3V3_STB_NODE1   Q31   -5          A01X+032268Y+039164X1264Y0898     S2      
317GND              VIA   -     D0100PA00X+031538Y+038786               S3      
317GND              VIA   -     D0100PA00X+030712Y+038598               S3      
317GND              VIA   -     D0100PA00X+031553Y+038475               S3      
317NNAME10671       VIA   -     D0100PA00X+031048Y+038331               S1      
327NNAME10690       R1099 -2          A01X+031694Y+040707X0180Y0200R090 S2      
317P3V3_STB_NODE1   VIA   -     D0100PA00X+032114Y+039964               S3      
317P3V3_STB_NODE1   VIA   -     D0100PA00X+031864Y+039964               S3      
327P12V_AUX         R1099 -1          A01X+031694Y+041022X0180Y0200R090 S2      
327NNAME10691       Q32   -S          A01X+032151Y+041563X0320Y0360R180 S2      
317P12V_AUX         VIA   -     D0100PA00X+031619Y+041330               S3      
317NNAME10047       VIA   -     D0100PA00X+031714Y+042178               S1      
317NNAME10425       VIA   -     D0100PA00X+032191Y+041014               S1      
317LAN1_DISABLE_N   VIA   -     D0100PA00X+031161Y+043253               S3      
317NNAME10269       VIA   -     D0100PA00X+031353Y+043646               S3      
317NNAME10319       VIA   -     D0100PA00X+031594Y+043810               S3      
317NNAME10204       VIA   -     D0100PA00X+031948Y+042939               S3      
317NNAME10207       VIA   -     D0100PA00X+030822Y+043255               S3      
317NNAME10691       VIA   -     D0100PA00X+032260Y+043251               S3      
317P3V3_SUS_NODE1   VIA   -     D0100PA00X+030944Y+042640               S3      
317NNAME10492       VIA   -     D0100PA00X+031895Y+043247               S3      
327GND              C1121 -2          A01X+031696Y+046379X0180Y0200     S2      
327P3V3_NODE1       C1121 -1          A01X+032011Y+046379X0180Y0200     S2      
317GND              VIA   -     D0100PA00X+031696Y+046766               S3      
317P3V3_NODE1       VIA   -     D0100PA00X+032136Y+045671               S3      
317NNAME10269       VIA   -     D0100PA00X+030780Y+046786               S3      
327P3V3_NODE1       C1120 -2          A01X+032011Y+047562X0180Y0200R180 S2      
327GND              C1120 -1          A01X+031696Y+047562X0180Y0200R180 S2      
317LAN1_DISABLE_N   VIA   -     D0100PA00X+031038Y+047394               S3      
317GND              VIA   -     D0100PA00X+031696Y+047883               S3      
317P3V3_NODE1       VIA   -     D0100PA00X+032125Y+047267               S3      
317NNAME10319       VIA   -     D0100PA00X+031598Y+047213               S3      
317NNAME10207       VIA   -     D0100PA00X+030767Y+047361               S3      
317N53313646        VIA   -     D0100PA00X+032008Y+051274               S1      
327N53313646        D31   -C          A01X+031829Y+052150X0320Y0320R270 S2      
327P3V3_NODE1       D31   -A          A01X+031829Y+052741X0320Y0320R270 S2      
327GND              C838  -2          A01X+031330Y+054640X0440Y0540     S2      
327NNAME10317       C838  -1          A01X+032078Y+054640X0440Y0540     S2      
327GND              R1098 -2          A10X+032199Y+053605X0180Y0200R270 S1      
327NNAME10692       R1098 -1          A10X+032199Y+053920X0180Y0200R270 S1      
317GND              VIA   -     D0100PA00X+031897Y+053605               S3      
317NNAME10317       VIA   -     D0100PA00X+031868Y+054097               S3      
317NNAME10317       VIA   -     D0100PA00X+032183Y+054168               S3      
327GND              C835  -2          A01X+031551Y+056300X0180Y0200     S2      
327P5V_STB_NODE1    C835  -1          A01X+031866Y+056300X0180Y0200     S2      
327GND              C840  -2          A01X+031696Y+055649X0180Y0200     S2      
327NNAME10317       C840  -1          A01X+032011Y+055649X0180Y0200     S2      
327GND              C839  -2          A01X+031696Y+055219X0180Y0200     S2      
327NNAME10317       C839  -1          A01X+032011Y+055219X0180Y0200     S2      
317GND              VIA   -     D0100PA00X+031389Y+056600               S3      
317GND              VIA   -     D0100PA00X+031314Y+055082               S3      
317GND              VIA   -     D0100PA00X+031308Y+055376               S3      
317GND              VIA   -     D0100PA00X+031311Y+055656               S3      
317GND              VIA   -     D0100PA00X+031328Y+055959               S3      
327GND              C836  -2          A01X+032185Y+057180X0440Y0540     S2      
317GND              VIA   -     D0100PA00X+031679Y+057290               S3      
317GND              VIA   -     D0100PA00X+031669Y+056960               S3      
317GND              VIA   -     D0100PA00X+031335Y+057070               S3      
327P12V_AUX         R1082 -2          A01X+031207Y+059726X0180Y0200     S2      
327NNAME10676       R1082 -1          A01X+031522Y+059726X0180Y0200     S2      
327GND              R1083 -2          A01X+031914Y+059411X0180Y0200R090 S2      
327NNAME10676       R1083 -1          A01X+031914Y+059726X0180Y0200R090 S2      
317GND              VIA   -     D0100PA00X+031914Y+059141               S3      
317P12V_AUX         VIA   -     D0100PA00X+031342Y+059404               S3      
317P12V_AUX         VIA   -     D0100PA00X+031323Y+059023               S3      
317P12V_AUX         VIA   -     D0100PA00X+031092Y+059404               S3      
317P12V_AUX         VIA   -     D0100PA00X+031063Y+059023               S3      
317NNAME10676       VIA   -     D0100PA00X+031596Y+059413               S3      
327GND              PU1   -TH         A01X+031033Y+060921X0670Y0670R270 S2      
327P5V_STB_NODE1    PU1   -16         A01X+031328Y+060341X0100Y0330R180 S2      
327P12V_AUX         PU1   -15         A01X+031131Y+060341X0100Y0330R180 S2      
327P12V_AUX         PU1   -14         A01X+030934Y+060341X0100Y0330R180 S2      
327P12V_AUX         PU1   -13         A01X+030737Y+060341X0100Y0330R180 S2      
327GND              PU1   -4          A01X+031613Y+061217X0100Y0330R270 S2      
327NNAME10693       PU1   -3          A01X+031613Y+061020X0100Y0330R270 S2      
327NNAME10694       PU1   -2          A01X+031613Y+060823X0100Y0330R270 S2      
327NNAME10695       PU1   -1          A01X+031613Y+060626X0100Y0330R270 S2      
317GND              VIA   -     D0100PA00X+031264Y+061156               S3      
317GND              VIA   -     D0100PA00X+030800Y+061154               S3      
317GND              VIA   -     D0100PA00X+031266Y+060688               S3      
317GND              VIA   -     D0100PA00X+030799Y+060689               S3      
317NNAME10695       VIA   -     D0100PA00X+032009Y+060411               S1      
317NNAME10693       VIA   -     D0100PA00X+032051Y+061360               S1      
327GND              PU1   -8          A01X+030737Y+061502X0100Y0330R180 S2      
327GND              PU1   -7          A01X+030934Y+061502X0100Y0330R180 S2      
327NNAME10696       PU1   -6          A01X+031131Y+061502X0100Y0330R180 S2      
327NNAME10207       PU1   -5          A01X+031328Y+061502X0100Y0330R180 S2      
327NNAME10207       PR1   -2          A01X+031888Y+062143X0180Y0200R090 S2      
327NNAME10694       PR1   -1          A01X+031888Y+062458X0180Y0200R090 S2      
327GND              PR2   -2          A01X+031491Y+062458X0180Y0200R270 S2      
327NNAME10207       PR2   -1          A01X+031491Y+062143X0180Y0200R270 S2      
327NNAME10696       PJ1   -2          A01X+031133Y+062072X0180Y0200R090 S2      
327NNAME10676       PJ1   -1          A01X+031133Y+062387X0200Y0400     S2      
317GND              VIA   -     D0100PA00X+030810Y+062069               S3      
317GND              VIA   -     D0100PA00X+030810Y+061819               S3      
317GND              VIA   -     D0100PA00X+032037Y+061807               S3      
317GND              VIA   -     D0100PA00X+031491Y+062722               S3      
317GND              VIA   -     D0100PA00X+031772Y+061465               S3      
317NNAME10676       VIA   -     D0100PA00X+030874Y+062387               S1      
317NNAME10696       VIA   -     D0100PA00X+031131Y+061820               S1      
317NNAME10207       VIA   -     D0100PA00X+031749Y+061819               S3      
327UART_SDC_TX      U73   -9          A10X+032247Y+064451X0140Y0590R090 S1      
327P3V3_NODE1       C579  -2          A10X+031268Y+063914X0180Y0200     S1      
327GND              C579  -1          A10X+030953Y+063914X0180Y0200     S1      
327GND              C578  -2          A01X+031485Y+063642X0180Y0200R090 S2      
327P3V3_NODE1       C578  -1          A01X+031485Y+063957X0180Y0200R090 S2      
327GND              C580  -2          A01X+030757Y+063661X0180Y0200R090 S2      
327P3V3_NODE1       C580  -1          A01X+030757Y+063976X0180Y0200R090 S2      
317GND              VIA   -     D0100PA00X+030757Y+063376               S3      
317P3V3_NODE1       VIA   -     D0100PA00X+031494Y+064207               S3      
317FAN_MAX_CTRL     VIA   -     D0100PA00X+031045Y+064245               S3      
327CPLD_WDT2_R      VIA   -           A10X+031618Y+064459X0260Y0260     S1      
317NNAME10573       VIA   -     D0100PA00X+032036Y+064228               S3      
317CMC_CPLD_RSV1    VIA   -     D0100PA00X+031138Y+063543               S3      
327UART_SW_S4_N     U73   -15         A10X+032247Y+065986X0140Y0590R090 S1      
327UART_SW_S5_N     U73   -14         A10X+032247Y+065730X0140Y0590R090 S1      
327SDC_WAKEUP       U73   -13         A10X+032247Y+065474X0140Y0590R090 S1      
327P3V3_NODE1       U73   -12         A10X+032247Y+065218X0140Y0590R090 S1      
327CPLD_WDT2_R      U73   -11         A10X+032247Y+064962X0140Y0590R090 S1      
327UART_SDC_RX      U73   -10         A10X+032247Y+064706X0140Y0590R090 S1      
327NNAME10575       U128  -66         A01X+032085Y+064714X0110Y0590     S2      
327GND              U128  -65         A01X+031888Y+064714X0110Y0590     S2      
327CLK_33K_CPLD23   U128  -64         A01X+031691Y+064714X0110Y0590     S2      
327P3V3_NODE1       U128  -63         A01X+031494Y+064714X0110Y0590     S2      
327CMC_CPLD_RSV1    U128  -62         A01X+031297Y+064714X0110Y0590     S2      
327FAN_MAX_CTRL     U128  -61         A01X+031100Y+064714X0110Y0590     S2      
327GND              U128  -60         A01X+030903Y+064714X0110Y0590     S2      
327P3V3_NODE1       U128  -59         A01X+030707Y+064714X0110Y0590     S2      
327P3V3_NODE1       R782  -2          A10X+030879Y+065116X0180Y0200R180 S1      
327SDC_WAKEUP       R782  -1          A10X+031194Y+065116X0180Y0200R180 S1      
327P3V3_NODE1       R790  -2          A10X+030879Y+065916X0180Y0200R180 S1      
327UART_SW_S4_N     R790  -1          A10X+031194Y+065916X0180Y0200R180 S1      
327P3V3_NODE1       R791  -2          A10X+030879Y+065516X0180Y0200R180 S1      
327UART_SW_S5_N     R791  -1          A10X+031194Y+065516X0180Y0200R180 S1      
327SDC_WAKEUP       R783  -2          A10X+031194Y+064716X0180Y0200     S1      
327GND              R783  -1          A10X+030879Y+064716X0180Y0200     S1      
327SDC_WAKEUP       VIA   -           A10X+031619Y+064962X0260Y0260     S1      
317GND              VIA   -     D0100PA00X+031479Y+065205               S3      
317GND              VIA   -     D0100PA00X+031713Y+065363               S3      
327CM_CABLE_DET_N   U73   -16         A10X+032247Y+066242X0140Y0590R090 S1      
327N21700927        U62   -3          A10X+032244Y+067370X0140Y0590R270 S1      
327N21700927        U62   -2          A10X+032244Y+067114X0140Y0590R270 S1      
327N21699285        U62   -1          A10X+032244Y+066858X0140Y0590R270 S1      
327P5V_NODE1        R690  -2          A10X+030879Y+067516X0180Y0200R180 S1      
327T1_NODE2_EN      R690  -1          A10X+031194Y+067516X0180Y0200R180 S1      
327P3V3_NODE1       R779  -2          A10X+030879Y+066316X0180Y0200R180 S1      
327CM_CABLE_DET_N   R779  -1          A10X+031194Y+066316X0180Y0200R180 S1      
327P5V_NODE1        R689  -2          A10X+030879Y+067116X0180Y0200R180 S1      
327T1_NODE1_EN      R689  -1          A10X+031194Y+067116X0180Y0200R180 S1      
327N21699285        R685  -2          A10X+031194Y+066716X0180Y0200     S1      
327P3V3_NODE1       R685  -1          A10X+030879Y+066716X0180Y0200     S1      
327N21699285        VIA   -           A10X+031619Y+066886X0260Y0260     S1      
317CM_CABLE_DET_N   VIA   -     D0100PA00X+031618Y+066263               S1      
327T2_NODE3_EN      U62   -10         A10X+032244Y+069161X0140Y0590R270 S1      
327T2_NODE2_EN      U62   -9          A10X+032244Y+068905X0140Y0590R270 S1      
327T2_NODE1_EN      U62   -8          A10X+032244Y+068650X0140Y0590R270 S1      
327T1_NODE4_EN      U62   -7          A10X+032244Y+068394X0140Y0590R270 S1      
327T1_NODE3_EN      U62   -6          A10X+032244Y+068138X0140Y0590R270 S1      
327T1_NODE2_EN      U62   -5          A10X+032244Y+067882X0140Y0590R270 S1      
327T1_NODE1_EN      U62   -4          A10X+032244Y+067626X0140Y0590R270 S1      
327P5V_NODE1        R692  -2          A10X+030879Y+068316X0180Y0200R180 S1      
327T1_NODE4_EN      R692  -1          A10X+031194Y+068316X0180Y0200R180 S1      
327P5V_NODE1        R693  -2          A10X+030879Y+068716X0180Y0200R180 S1      
327T2_NODE1_EN      R693  -1          A10X+031194Y+068716X0180Y0200R180 S1      
327P5V_NODE1        R694  -2          A10X+030879Y+069116X0180Y0200R180 S1      
327T2_NODE2_EN      R694  -1          A10X+031194Y+069116X0180Y0200R180 S1      
327P5V_NODE1        R691  -2          A10X+030879Y+067916X0180Y0200R180 S1      
327T1_NODE3_EN      R691  -1          A10X+031194Y+067916X0180Y0200R180 S1      
317T2_NODE2_EN      VIA   -     D0100PA00X+031461Y+069077               S3      
317T2_NODE1_EN      VIA   -     D0100PA00X+031618Y+068763               S1      
327GND              U62   -12         A10X+032244Y+069673X0140Y0590R270 S1      
327T2_NODE4_EN      U62   -11         A10X+032244Y+069417X0140Y0590R270 S1      
327UART_DTR_P4_N    U128  -17         A01X+030707Y+070817X0110Y0590     S2      
327UART_RX_P4       U128  -16         A01X+030903Y+070817X0110Y0590     S2      
327UART_TX_P4       U128  -15         A01X+031100Y+070817X0110Y0590     S2      
327CPU_RSV_1        U128  -14         A01X+031297Y+070817X0110Y0590     S2      
327P3V3_NODE1       U128  -13         A01X+031494Y+070817X0110Y0590     S2      
327CPLD_WDT3        U128  -12         A01X+031691Y+070817X0110Y0590     S2      
327GND              U128  -11         A01X+031888Y+070817X0110Y0590     S2      
327GND              U128  -10         A01X+032085Y+070817X0110Y0590     S2      
327P5V_NODE1        R696  -2          A10X+030879Y+069916X0180Y0200R180 S1      
327T2_NODE4_EN      R696  -1          A10X+031194Y+069916X0180Y0200R180 S1      
327P5V_NODE1        R695  -2          A10X+030879Y+069516X0180Y0200R180 S1      
327T2_NODE3_EN      R695  -1          A10X+031194Y+069516X0180Y0200R180 S1      
317GND              VIA   -     D0100PA00X+032244Y+070013               S3      
317GND              VIA   -     D0100PA00X+032011Y+070309               S3      
317T2_NODE3_EN      VIA   -     D0100PA00X+031617Y+069340               S1      
317UART_RX_P4       VIA   -     D0100PA00X+031323Y+070247               S3      
327GND              C585  -2          A01X+031494Y+071973X0180Y0200R270 S2      
327P3V3_NODE1       C585  -1          A01X+031494Y+071658X0180Y0200R270 S2      
317GND              VIA   -     D0100PA00X+031758Y+072000               S3      
317UART_DTR_P4_N    VIA   -     D0100PA00X+030711Y+071300               S3      
317P3V3_NODE1       VIA   -     D0100PA00X+032182Y+071268               S3      
317P3V3_NODE1       VIA   -     D0100PA00X+031199Y+071760               S3      
317T4_NODE4_EN      VIA   -     D0100PA00X+031962Y+071640               S1      
327T3_NODE4_EN      VIA   -           A10X+030843Y+071869X0260Y0260     S1      
317UART_TX_P4       VIA   -     D0100PA00X+030953Y+071430               S3      
317CPU_RSV_1        VIA   -     D0100PA00X+031297Y+071269               S3      
317CPLD_WDT3        VIA   -     D0100PA00X+031809Y+071285               S3      
327GND              C667  -2          A01X+031144Y+073908X0180Y0200R090 S2      
327GND              C646  -2          A10X+031194Y+073908X0180Y0200R270 S1      
327GND              C649  -2          A10X+030794Y+073908X0180Y0200R270 S1      
327GND              C661  -2          A01X+032044Y+073908X0180Y0200R090 S2      
327GND              C664  -2          A01X+031594Y+073908X0180Y0200R090 S2      
327GND              C695  -2          A01X+030694Y+072758X0180Y0200R090 S2      
327NNAME10697       C695  -1          A01X+030694Y+073073X0180Y0200R090 S2      
327T4_NODE4_EN_R    R904  -2          A01X+031144Y+073073X0180Y0200R270 S2      
327T4_NODE4_EN      R904  -1          A01X+031144Y+072758X0180Y0200R270 S2      
327T3_NODE1_EN_R    R883  -2          A10X+031341Y+073228X0180Y0200R090 S1      
327T3_NODE1_EN      R883  -1          A10X+031341Y+072913X0180Y0200R090 S1      
327T3_NODE2_EN_R    R886  -2          A10X+030953Y+073094X0180Y0200R090 S1      
327T3_NODE2_EN      R886  -1          A10X+030953Y+072779X0180Y0200R090 S1      
327T4_NODE2_EN_R    R898  -2          A01X+032044Y+073073X0180Y0200R270 S2      
327T4_NODE2_EN      R898  -1          A01X+032044Y+072758X0180Y0200R270 S2      
327T4_NODE3_EN_R    R901  -2          A01X+031594Y+073073X0180Y0200R270 S2      
327T4_NODE3_EN      R901  -1          A01X+031594Y+072758X0180Y0200R270 S2      
327NNAME10697       R932  -1          A01X+030694Y+073908X0180Y0200R270 S2      
317GND              VIA   -     D0100PA00X+030794Y+073645               S3      
317GND              VIA   -     D0100PA00X+031144Y+073583               S3      
317GND              VIA   -     D0100PA00X+031594Y+073592               S3      
317GND              VIA   -     D0100PA00X+032044Y+073603               S3      
317NNAME10697       VIA   -     D0100PA00X+030728Y+073371               S3      
317T4_NODE2_EN      VIA   -     D0100PA00X+032193Y+072490               S1      
317T3_NODE2_EN      VIA   -     D0100PA00X+031493Y+072453               S1      
327T4_NODE4_EN_R    C667  -1          A01X+031144Y+074223X0180Y0200R090 S2      
327T3_NODE1_EN_R    C646  -1          A10X+031194Y+074223X0180Y0200R270 S1      
327T3_NODE2_EN_R    C649  -1          A10X+030794Y+074223X0180Y0200R270 S1      
327T4_NODE2_EN_R    C661  -1          A01X+032044Y+074223X0180Y0200R090 S2      
327T4_NODE3_EN_R    C664  -1          A01X+031594Y+074223X0180Y0200R090 S2      
327NNAME10685       R932  -2          A01X+030694Y+074223X0180Y0200R270 S2      
317NNAME10685       VIA   -     D0100PA00X+030715Y+076942               S1      
317T4_NODE4_EN_R    VIA   -     D0100PA00X+031502Y+078056               S1      
317T4_NODE3_EN_R    VIA   -     D0100PA00X+032066Y+077960               S1      
317T4_NODE2_EN_R    VIA   -     D0100PA00X+032044Y+077197               S1      
327T3_NODE2_EN_R    VIA   -           A10X+031144Y+077405X0260Y0260     S1      
327T3_NODE1_EN_R    VIA   -           A10X+031702Y+078649X0260Y0260     S1      
327T3_NODE3_EN_R    VIA   -           A10X+031005Y+078592X0260Y0260     S1      
327T3_NODE2_EN_R    J35   -A16        A10X+031108Y+080787X0300Y1660R180 S1      
327T3_NODE1_EN_R    J35   -A15        A10X+031502Y+080787X0300Y1660R180 S1      
327GND              J35   -A14        A10X+031896Y+080787X0300Y1660R180 S1      
327NNAME10698       J35   -A13        A10X+032289Y+080787X0300Y1660R180 S1      
327GND              J35   -B16        A01X+031108Y+080787X0300Y1660R180 S2      
327T4_NODE4_EN_R    J35   -B15        A01X+031502Y+080787X0300Y1660R180 S2      
327T4_NODE3_EN_R    J35   -B14        A01X+031896Y+080787X0300Y1660R180 S2      
327T4_NODE2_EN_R    J35   -B13        A01X+032289Y+080787X0300Y1660R180 S2      
317GND              VIA   -     D0100PA00X+031108Y+079187               S3      
317GND              VIA   -     D0100PA00X+031896Y+079170               S3      
327GND              PC131 -2          A01X+033512Y+001053X0440Y0540R180 S2      
327P3V3_NODE1       PC131 -1          A01X+032764Y+001053X0440Y0540R180 S2      
317P3V3_NODE1       VIA   -     D0100PA00X+032333Y+001238               S3      
327GND              PC48  -2          A01X+033512Y+002653X0440Y0540R180 S2      
327P3V3_NODE1       PC48  -1          A01X+032764Y+002653X0440Y0540R180 S2      
327GND              PC49  -2          A01X+033512Y+001853X0440Y0540R180 S2      
327P3V3_NODE1       PC49  -1          A01X+032764Y+001853X0440Y0540R180 S2      
317P3V3_NODE1       VIA   -     D0100PA00X+032387Y+002581               S3      
317P3V3_NODE1       VIA   -     D0100PA00X+032387Y+001681               S3      
317P3V3_NODE1       VIA   -     D0100PA00X+032387Y+001981               S3      
317P3V3_NODE1       VIA   -     D0100PA00X+032387Y+002881               S3      
327GND              PC50  -2          A01X+033301Y+003233X0180Y0200R180 S2      
327P3V3_NODE1       PC50  -1          A01X+032986Y+003233X0180Y0200R180 S2      
317GND              VIA   -     D0100PA00X+033632Y+003182               S3      
317P3V3_NODE1       VIA   -     D0100PA00X+032712Y+003184               S3      
327GND              C150  -2          A01X+032447Y+006803X0180Y0200R090 S2      
327PV_VDDR_NODE1    C150  -1          A01X+032447Y+007118X0180Y0200R090 S2      
317GND              VIA   -     D0100PA00X+032635Y+006317               S3      
317PV_VDDR_NODE1    VIA   -     D0100PA00X+032364Y+007439               S3      
317PV_VDDR_NODE1    VIA   -     D0100PA00X+032614Y+007620               S3      
327GND              C147  -2          A10X+032701Y+008464X0180Y0200R090 S1      
327PV_VDDR_NODE1    C147  -1          A10X+032701Y+008149X0180Y0200R090 S1      
327GND              C163  -2          A10X+032301Y+008464X0180Y0200R090 S1      
327PV_VDDR_NODE1    C163  -1          A10X+032301Y+008149X0180Y0200R090 S1      
327GND              J2    -143        A01X+033602Y+008248X0150Y0810     S2      
327NNAME10512       J2    -141        A01X+033366Y+008248X0150Y0810     S2      
327NNAME10509       J2    -139        A01X+033130Y+008248X0150Y0810     S2      
327GND              J2    -137        A01X+032894Y+008248X0150Y0810     S2      
327NNAME10513       J2    -135        A01X+032658Y+008248X0150Y0810     S2      
327NNAME10511       J2    -133        A01X+032421Y+008248X0150Y0810     S2      
317GND              VIA   -     D0100PA00X+033602Y+008818               S3      
317GND              VIA   -     D0100PA00X+032964Y+008989               S3      
317NNAME10512       VIA   -     D0100PA00X+033567Y+009282               S1      
317NNAME10509       VIA   -     D0100PA00X+033067Y+009282               S1      
317NNAME10513       VIA   -     D0100PA00X+032536Y+009252               S1      
317NNAME10511       VIA   -     D0100PA00X+032407Y+008886               S3      
317GND              VIA   -     D0100PA00X+033634Y+009927               S3      
317GND              VIA   -     D0100PA00X+032795Y+010106               S3      
317GND              VIA   -     D0100PA00X+032300Y+009434               S3      
317NNAME10686       VIA   -     D0100PA00X+032597Y+009882               S1      
317NNAME10583       VIA   -     D0100PA00X+032743Y+010821               S3      
317NNAME10514       VIA   -     D0100PA00X+032719Y+010382               S1      
317NNAME10515       VIA   -     D0100PA00X+033763Y+010630               S1      
317NNAME10508       VIA   -     D0100PA00X+033472Y+010218               S1      
327PV_VDDR_NODE1    C174  -1          A10X+032396Y+011741X0280Y0320R270 S1      
327GND              C174  -2          A10X+032976Y+011741X0280Y0320R270 S1      
327PD_NODE1_DM4     R208  -2          A10X+033580Y+011730X0180Y0200R180 S1      
327NNAME10508       J2    -144        A01X+033721Y+011476X0150Y0810     S2      
327NNAME10515       J2    -142        A01X+033484Y+011476X0150Y0810     S2      
327PD_NODE1_DM4     J2    -140        A01X+033248Y+011476X0150Y0810     S2      
327GND              J2    -138        A01X+033012Y+011476X0150Y0810     S2      
327NNAME10583       J2    -136        A01X+032776Y+011476X0150Y0810     S2      
327NNAME10514       J2    -134        A01X+032539Y+011476X0150Y0810     S2      
327PV_VDDR_NODE1    J2    -132        A01X+032303Y+011476X0150Y0810     S2      
317GND              VIA   -     D0100PA00X+033245Y+012230               S3      
317PV_VDDR_NODE1    VIA   -     D0100PA00X+032303Y+012224               S3      
317PD_NODE1_DM4     VIA   -     D0100PA00X+033158Y+012872               S1      
327NNAME10455       VIA   -           A01X+032439Y+014698X0300Y0300     S2      
327NNAME10456       VIA   -           A01X+032897Y+014294X0300Y0300     S2      
327P1V05_NODE1      R113  -2          A01X+032444Y+029576X0180Y0200R270 S2      
327NNAME10619       R113  -1          A01X+032444Y+029261X0180Y0200R270 S2      
317NNAME10619       VIA   -     D0100PA00X+033650Y+029057               S3      
327NNAME10468       VIA   -           A10X+033187Y+029137X0260Y0260     S1      
327P1V05_NODE1      R127  -2          A10X+033067Y+031186X0180Y0200     S1      
327NNAME10668       R127  -1          A10X+032752Y+031186X0180Y0200     S1      
327P1V05_NODE1      R1049 -2          A01X+033235Y+030775X0180Y0200R090 S2      
327NNAME10536       R1049 -1          A01X+033235Y+031090X0180Y0200R090 S2      
317GND              VIA   -     D0100PA00X+033138Y+029988               S3      
317P1V05_NODE1      VIA   -     D0100PA00X+032853Y+030870               S3      
317P1V05_NODE1      VIA   -     D0100PA00X+033448Y+029960               S3      
327NNAME10538       VIA   -           A10X+033462Y+030286X0260Y0260     S1      
317PV_VCCP_NODE1    VIA   -     D0100PA00X+032312Y+031359               S3      
317NNAME10687       VIA   -     D0100PA00X+033672Y+031085               S1      
327NNAME10628       Y2    -2          A01X+033249Y+032851X0400Y0710R090 S2      
327GND              C89   -2          A01X+032264Y+031923X0180Y0200R270 S2      
327PV_VCCP_NODE1    C89   -1          A01X+032264Y+031608X0180Y0200R270 S2      
327GND              C88   -2          A01X+032664Y+031923X0180Y0200R270 S2      
327PV_VCCP_NODE1    C88   -1          A01X+032664Y+031608X0180Y0200R270 S2      
327GND              C90   -2          A01X+033064Y+031923X0180Y0200R270 S2      
327PV_VCCP_NODE1    C90   -1          A01X+033064Y+031608X0180Y0200R270 S2      
327GND              C24   -2          A01X+032570Y+032772X0180Y0200R090 S2      
317NNAME10470       VIA   -     D0100PA00X+033729Y+031666               S1      
317NNAME10536       VIA   -     D0100PA00X+033354Y+031559               S3      
327NNAME10630       Y2    -1          A01X+033249Y+033835X0400Y0710R270 S2      
327GND              C25   -2          A01X+032570Y+033795X0180Y0200R270 S2      
327NNAME10630       C25   -1          A01X+032570Y+033480X0180Y0200R270 S2      
327NNAME10628       C24   -1          A01X+032570Y+033087X0180Y0200R090 S2      
317GND              VIA   -     D0100PA00X+033270Y+033309               S3      
327NNAME10545       R138  -2          A01X+032706Y+035380X0180Y0200     S2      
327P3V3_SUS_NODE1   R138  -1          A01X+033021Y+035380X0180Y0200     S2      
327NNAME10546       R136  -2          A01X+032701Y+034922X0180Y0200     S2      
327P3V3_SUS_NODE1   R136  -1          A01X+033016Y+034922X0180Y0200     S2      
317P3V3_SUS_NODE1   VIA   -     D0100PA00X+033373Y+035380               S3      
317P3V3_SUS_NODE1   VIA   -     D0100PA00X+033344Y+034922               S3      
317NNAME10545       VIA   -     D0100PA00X+032706Y+035838               S1      
317NNAME10546       VIA   -     D0100PA00X+032304Y+035449               S3      
327P3V3_SUS_NODE1   C110  -1          A01X+032470Y+036365X0280Y0320R270 S2      
327GND              C110  -2          A01X+033050Y+036365X0280Y0320R270 S2      
327P3V3_SUS_NODE1   C109  -1          A01X+032470Y+036915X0280Y0320R270 S2      
327GND              C109  -2          A01X+033050Y+036915X0280Y0320R270 S2      
327P3V3_SUS_NODE1   C108  -1          A01X+032473Y+037464X0280Y0320R270 S2      
327GND              C108  -2          A01X+033053Y+037464X0280Y0320R270 S2      
317GND              VIA   -     D0100PA00X+033482Y+036779               S3      
317GND              VIA   -     D0100PA00X+033732Y+036776               S3      
317GND              VIA   -     D0100PA00X+033733Y+037268               S3      
317GND              VIA   -     D0100PA00X+033482Y+037261               S3      
327NNAME10690       C841  -1          A01X+033244Y+038033X0280Y0320R090 S2      
327P3V3_SUS_NODE1   C841  -2          A01X+032664Y+038033X0280Y0320R090 S2      
327NNAME10690       Q31   -4          A01X+032652Y+038613X0140Y0200     S2      
327P3V3_SUS_NODE1   Q31   -3          A01X+032396Y+038613X0140Y0200     S2      
317NNAME10690       VIA   -     D0100PA00X+033685Y+038033               S1      
327NNAME10690       Q32   -D          A01X+032525Y+040776X0320Y0360R180 S2      
317P3V3_STB_NODE1   VIA   -     D0100PA00X+032628Y+039974               S3      
317P3V3_STB_NODE1   VIA   -     D0100PA00X+032364Y+039964               S3      
327NNAME10691       R1235 -2          A01X+032260Y+042164X0180Y0200     S2      
327GND              R1235 -1          A01X+032575Y+042164X0180Y0200     S2      
327NNAME10699       Q32   -G          A01X+032899Y+041563X0320Y0360R180 S2      
317GND              VIA   -     D0100PA00X+032575Y+041870               S3      
317NNAME10699       VIA   -     D0100PA00X+033109Y+042430               S1      
317NNAME10420       VIA   -     D0100PA00X+033190Y+041932               S1      
317NNAME10490       VIA   -     D0100PA00X+033674Y+041707               S1      
317P3V3_STB_NODE1   VIA   -     D0100PA00X+032829Y+042430               S3      
317NNAME10026       VIA   -     D0100PA00X+032494Y+041390               S3      
327GND              C842  -2          A01X+032575Y+042958X0180Y0200R180 S2      
327NNAME10691       C842  -1          A01X+032260Y+042958X0180Y0200R180 S2      
327P3V3_STB_NODE1   R1100 -2          A01X+032575Y+042559X0180Y0200R180 S2      
327NNAME10691       R1100 -1          A01X+032260Y+042559X0180Y0200R180 S2      
327P3V3_STB_NODE1   R1101 -2          A01X+033130Y+042992X0180Y0200R270 S2      
327NNAME10699       R1101 -1          A01X+033130Y+042677X0180Y0200R270 S2      
317GND              VIA   -     D0100PA00X+033622Y+042485               S3      
317GND              VIA   -     D0100PA00X+032518Y+043258               S3      
317P3V3_STB_NODE1   VIA   -     D0100PA00X+033442Y+042866               S3      
317GND              VIA   -     D0100PA00X+033609Y+045451               S3      
317P1V8_NODE1       VIA   -     D0100PA00X+032619Y+044862               S3      
317P1V8_NODE1       VIA   -     D0100PA00X+032912Y+044920               S3      
317P1V8_NODE1       VIA   -     D0100PA00X+032778Y+044582               S3      
317P1V8_NODE1       VIA   -     D0100PA00X+033136Y+044731               S3      
327GND              U115  -13         A01X+033609Y+045902X0090Y0550R180 S2      
327P3V3_NODE1       U115  -12         A01X+032999Y+046512X0090Y0550R270 S2      
327N53313175        U115  -11         A01X+032999Y+046709X0090Y0550R270 S2      
327N/C              U115  -10         A01X+032999Y+046906X0090Y0550R270 S2      
327N/C              U115  -9          A01X+032999Y+047103X0090Y0550R270 S2      
317N53313175        TP175 -1    D0100PA00X+032299Y+046711               S1      
327N/C              U115  -8          A01X+032999Y+047300X0090Y0550R270 S2      
327N/C              U115  -7          A01X+032999Y+047497X0090Y0550R270 S2      
327P3V3_NODE1       U115  -6          A01X+032999Y+047694X0090Y0550R270 S2      
327GND              U115  -5          A01X+032999Y+047890X0090Y0550R270 S2      
327NNAME10419       U115  -4          A01X+032999Y+048087X0090Y0550R270 S2      
327NNAME10422       U115  -3          A01X+032999Y+048284X0090Y0550R270 S2      
327PORT80_LOUT0     U115  -2          A01X+032999Y+048481X0090Y0550R270 S2      
327N53313325        U115  -1          A01X+032999Y+048678X0090Y0550R270 S2      
317GND              VIA   -     D0100PA00X+032504Y+048013               S3      
327PORT80_LOUT1     U115  -48         A01X+033609Y+049288X0090Y0550     S2      
317N53313325        TP174 -1    D0100PA00X+033012Y+049030               S1      
317PORT80_LOUT2     VIA   -     D0100PA00X+033516Y+050279               S1      
317PORT80_LOUT0     VIA   -     D0100PA00X+032674Y+049576               S1      
317PORT80_LOUT1     VIA   -     D0100PA00X+032967Y+050206               S1      
327N53313479        R1254 -2          A01X+033701Y+050944X0180Y0200R270 S2      
327PORT80_LOUT2     R1254 -1          A01X+033701Y+050629X0180Y0200R270 S2      
327N53313464        R1253 -2          A01X+033251Y+050944X0180Y0200R270 S2      
327PORT80_LOUT1     R1253 -1          A01X+033251Y+050629X0180Y0200R270 S2      
327N53313646        R1260 -2          A01X+032774Y+050966X0180Y0200R270 S2      
327PORT80_LOUT0     R1260 -1          A01X+032774Y+050651X0180Y0200R270 S2      
317N53313464        VIA   -     D0100PA00X+032617Y+051839               S1      
317N53313479        VIA   -     D0100PA00X+033586Y+051649               S1      
327N53313464        D32   -C          A01X+032418Y+052151X0320Y0320R270 S2      
327P3V3_NODE1       D32   -A          A01X+032418Y+052741X0320Y0320R270 S2      
327N53313479        D33   -C          A01X+033018Y+052151X0320Y0320R270 S2      
327P3V3_NODE1       D33   -A          A01X+033018Y+052741X0320Y0320R270 S2      
327N53313501        D34   -C          A01X+033618Y+052151X0320Y0320R270 S2      
327P3V3_NODE1       D34   -A          A01X+033618Y+052741X0320Y0320R270 S2      
317P3V3_NODE1       VIA   -     D0100PA00X+033601Y+053160               S3      
317NNAME10700       VIA   -     D0100PA00X+032935Y+053340               S1      
327P3V3_STB_NODE1   R1096 -2          A01X+033669Y+053783X0180Y0200R090 S2      
327NNAME10701       R1096 -1          A01X+033669Y+054098X0180Y0200R090 S2      
327NNAME10692       R1097 -2          A01X+033209Y+054108X0180Y0200R270 S2      
327NNAME10700       R1097 -1          A01X+033209Y+053793X0180Y0200R270 S2      
327NNAME10317       J23   -2          A01X+032530Y+053676X0180Y0200     S2      
327NNAME10700       J23   -1          A01X+032845Y+053676X0200Y0400R270 S2      
327NNAME10701       U122  -5          A01X+033436Y+055020X0110Y0360R180 S2      
327NNAME10317       U122  -1          A01X+032649Y+055020X0110Y0360     S2      
327NNAME10692       U122  -4          A01X+033239Y+055020X0110Y0360     S2      
327NNAME10317       U122  -3          A01X+033043Y+055020X0110Y0360     S2      
327NNAME10317       U122  -2          A01X+032846Y+055020X0110Y0360     S2      
317NNAME10317       VIA   -     D0100PA00X+032493Y+054601               S3      
317NNAME10317       VIA   -     D0100PA00X+032859Y+054115               S3      
317NNAME10317       VIA   -     D0100PA00X+032835Y+054541               S3      
317NNAME10317       VIA   -     D0100PA00X+032559Y+054145               S3      
317NNAME10692       VIA   -     D0100PA00X+033241Y+054410               S1      
327P5V_STB_NODE1    U122  -10         A01X+032649Y+056241X0110Y0360     S2      
327NNAME10702       U122  -6          A01X+033436Y+056241X0110Y0360R180 S2      
327P1V8_NODE1       U122  -9          A01X+032846Y+056241X0110Y0360     S2      
327P1V8_NODE1       U122  -8          A01X+033043Y+056241X0110Y0360     S2      
327P1V8_NODE1       U122  -7          A01X+033239Y+056241X0110Y0360     S2      
327GND              U122  -TH         A01X+033043Y+055631X0690Y1050R090 S2      
317GND              VIA   -     D0100PA00X+032315Y+055637               S3      
317GND              VIA   -     D0100PA00X+032315Y+055887               S3      
317GND              VIA   -     D0100PA00X+032315Y+055387               S3      
317GND              VIA   -     D0100PA00X+033755Y+055862               S3      
317GND              VIA   -     D0100PA00X+033755Y+055612               S3      
317GND              VIA   -     D0100PA00X+033755Y+055362               S3      
317P5V_STB_NODE1    VIA   -     D0100PA00X+032309Y+056150               S3      
317P5V_STB_NODE1    VIA   -     D0100PA00X+032319Y+056450               S3      
317P1V8_NODE1       VIA   -     D0100PA00X+033039Y+056580               S3      
327P1V8_NODE1       C836  -1          A01X+032933Y+057180X0440Y0540     S2      
327GND              C837  -2          A01X+033627Y+057268X0180Y0200R270 S2      
327NNAME10702       C837  -1          A01X+033627Y+056953X0180Y0200R270 S2      
317GND              VIA   -     D0100PA00X+033606Y+057566               S1      
317P1V8_NODE1       VIA   -     D0100PA00X+033239Y+056770               S3      
317P1V8_NODE1       VIA   -     D0100PA00X+032809Y+056750               S3      
327P5V_STB_NODE1    PR3   -2          A01X+032295Y+059720X0180Y0200     S2      
327NNAME10695       PR3   -1          A01X+032610Y+059720X0180Y0200     S2      
317P5V_STB_NODE1    VIA   -     D0100PA00X+032393Y+058973               S1      
327GND              PC8   -2          A01X+032672Y+060948X0180Y0200R180 S2      
327NNAME10694       PC8   -1          A01X+032357Y+060948X0180Y0200R180 S2      
327P5V_STB_NODE1    PC10  -2          A01X+032295Y+060112X0180Y0200     S2      
327NNAME10695       PC10  -1          A01X+032610Y+060112X0180Y0200     S2      
327GND              PR4   -2          A01X+032663Y+060536X0180Y0200R180 S2      
327NNAME10695       PR4   -1          A01X+032348Y+060536X0180Y0200R180 S2      
317GND              VIA   -     D0100PA00X+032926Y+060338               S3      
317GND              VIA   -     D0100PA00X+032893Y+061169               S3      
327NNAME10693       PC9   -2          A01X+032304Y+061401X0180Y0200R090 S2      
327GND              PC9   -1          A01X+032304Y+061716X0180Y0200R090 S2      
317NNAME10694       VIA   -     D0100PA00X+032335Y+062193               S1      
317NNAME10207       VIA   -     D0100PA00X+032911Y+062351               S3      
327NNAME10682       R935  -2          A01X+032358Y+063644X0180Y0200R090 S2      
327NNAME10703       R935  -1          A01X+032358Y+063959X0180Y0200R090 S2      
317NNAME10682       VIA   -     D0100PA00X+033044Y+063950               S3      
317NNAME10679       VIA   -     D0100PA00X+032803Y+064267               S3      
317NNAME10697       VIA   -     D0100PA00X+033707Y+063976               S1      
317NNAME10703       VIA   -     D0100PA00X+032635Y+063897               S1      
317NNAME10658       VIA   -     D0100PA00X+033271Y+064269               S3      
327NNAME10655       U128  -74         A01X+033659Y+064714X0110Y0590     S2      
327NNAME10658       U128  -73         A01X+033463Y+064714X0110Y0590     S2      
327NNAME10656       U128  -72         A01X+033266Y+064714X0110Y0590     S2      
327NNAME10679       U128  -71         A01X+033069Y+064714X0110Y0590     S2      
327NNAME10681       U128  -70         A01X+032872Y+064714X0110Y0590     S2      
327NNAME10697       U128  -69         A01X+032675Y+064714X0110Y0590     S2      
327NNAME10703       U128  -68         A01X+032478Y+064714X0110Y0590     S2      
327NNAME10573       U128  -67         A01X+032281Y+064714X0110Y0590     S2      
317UART_SDC_RX      VIA   -     D0100PA00X+032876Y+065714               S3      
317P3V3_NODE1       VIA   -     D0100PA00X+032754Y+065343               S3      
317NNAME10655       VIA   -     D0100PA00X+033561Y+065818               S3      
317NNAME10656       VIA   -     D0100PA00X+033275Y+065564               S3      
317NNAME10681       VIA   -     D0100PA00X+033219Y+065988               S3      
317UART_SDC_TX      VIA   -     D0100PA00X+032991Y+066238               S3      
317I2C_COM3_SDA     VIA   -     D0100PA00X+033592Y+067501               S3      
317SDC_RST_N        VIA   -     D0100PA00X+033539Y+066790               S3      
317SDC_RST_N        VIA   -     D0100PA00X+032689Y+067616               S3      
317N21700927        VIA   -     D0100PA00X+032726Y+067241               S3      
317UART_SW_S2_N     VIA   -     D0100PA00X+033318Y+066561               S3      
317UART_SW_S1_N     VIA   -     D0100PA00X+033513Y+067074               S3      
317UART_SW_S3_N     VIA   -     D0100PA00X+033431Y+066311               S3      
317UART_SW_S5_N     VIA   -     D0100PA00X+032750Y+066724               S3      
317UART_SW_S4_N     VIA   -     D0100PA00X+032497Y+066513               S3      
317I2C_COM3_SCL     VIA   -     D0100PA00X+033703Y+067789               S3      
317NNAME10704       VIA   -     D0100PA00X+033780Y+068672               S3      
327P3V3_NODE1       U128  -9          A01X+032281Y+070817X0110Y0590     S2      
327SDC_RST_N        U128  -8          A01X+032478Y+070817X0110Y0590     S2      
327UART_SW_S5_N     U128  -7          A01X+032675Y+070817X0110Y0590     S2      
327UART_SW_S4_N     U128  -6          A01X+032872Y+070817X0110Y0590     S2      
327UART_SW_S3_N     U128  -5          A01X+033069Y+070817X0110Y0590     S2      
327UART_SW_S2_N     U128  -4          A01X+033266Y+070817X0110Y0590     S2      
327UART_SW_S1_N     U128  -3          A01X+033463Y+070817X0110Y0590     S2      
327UART_SW_S0_N     U128  -2          A01X+033659Y+070817X0110Y0590     S2      
317SDC_RST_N        VIA   -     D0100PA00X+032412Y+070311               S1      
317NNAME10705       VIA   -     D0100PA00X+033611Y+069393               S3      
317T4_NODE2_EN      VIA   -     D0100PA00X+033152Y+070164               S3      
317T4_NODE1_EN      VIA   -     D0100PA00X+033272Y+069817               S3      
327T3_NODE3_EN      VIA   -           A10X+033267Y+070603X0260Y0260     S1      
327GND              C586  -2          A01X+032294Y+071973X0180Y0200R270 S2      
327P3V3_NODE1       C586  -1          A01X+032294Y+071658X0180Y0200R270 S2      
317GND              VIA   -     D0100PA00X+032584Y+071973               S3      
317T3_NODE2_EN      VIA   -     D0100PA00X+033041Y+071290               S3      
327T4_NODE1_EN      VIA   -           A01X+033530Y+071717X0300Y0300     S2      
317T4_NODE3_EN      VIA   -     D0100PA00X+032556Y+071339               S1      
327T3_NODE1_EN      VIA   -           A10X+033094Y+071913X0260Y0260     S1      
327GND              C658  -2          A01X+032494Y+073908X0180Y0200R090 S2      
327GND              C593  -2          A01X+033394Y+073908X0180Y0200R090 S2      
327GND              C591  -2          A01X+032944Y+073908X0180Y0200R090 S2      
327T4_NODE1_EN_R    R895  -2          A01X+032494Y+073073X0180Y0200R270 S2      
327T4_NODE1_EN      R895  -1          A01X+032494Y+072758X0180Y0200R270 S2      
327I2C_PSU2_R_SCL   R824  -2          A01X+033394Y+073073X0180Y0200R270 S2      
327I2C_PSU2_SCL     R824  -1          A01X+033394Y+072758X0180Y0200R270 S2      
327I2C_PSU2_R_SDA   R822  -2          A01X+032944Y+073073X0180Y0200R270 S2      
327I2C_PSU2_SDA     R822  -1          A01X+032944Y+072758X0180Y0200R270 S2      
317GND              VIA   -     D0100PA00X+033699Y+073570               S3      
317GND              VIA   -     D0100PA00X+032494Y+073607               S3      
317GND              VIA   -     D0100PA00X+032944Y+073581               S3      
317GND              VIA   -     D0100PA00X+033394Y+073590               S3      
317I2C_PSU2_SDA     VIA   -     D0100PA00X+032959Y+072428               S3      
317I2C_PSU2_SCL     VIA   -     D0100PA00X+033464Y+072504               S3      
317NNAME10706       VIA   -     D0100PA00X+033827Y+073339               S3      
317NNAME10705       VIA   -     D0100PA00X+033846Y+072459               S1      
327T4_NODE1_EN_R    C658  -1          A01X+032494Y+074223X0180Y0200R090 S2      
327I2C_PSU2_R_SCL   C593  -1          A01X+033394Y+074223X0180Y0200R090 S2      
327I2C_PSU2_R_SDA   C591  -1          A01X+032944Y+074223X0180Y0200R090 S2      
327NNAME10707       VIA   -           A10X+032828Y+077006X0260Y0260     S1      
317T4_NODE1_EN_R    VIA   -     D0100PA00X+032628Y+077598               S1      
317I2C_PSU2_R_SDA   VIA   -     D0100PA00X+033780Y+077468               S1      
327NNAME10698       VIA   -           A10X+032287Y+078509X0260Y0260     S1      
327NNAME10707       J35   -A12        A10X+032683Y+080787X0300Y1660R180 S1      
327T4_NODE1_EN_R    J35   -B12        A01X+032683Y+080787X0300Y1660R180 S2      
327NNAME10708       J35   -A11        A10X+033864Y+080787X0300Y1660R180 S1      
327I2C_PSU2_R_SDA   J35   -B11        A01X+033864Y+080787X0300Y1660R180 S2      
317GND              VIA   -     D0100PA00X+033916Y+000930               S3      
317GND              VIA   -     D0100PA00X+033916Y+001190               S3      
327GND              J1    -14         A01X+035041Y+003019X0400Y1090R180 S2      
317GND              VIA   -     D0100PA00X+035041Y+002128               S3      
317GND              VIA   -     D0100PA00X+033924Y+002423               S3      
317GND              VIA   -     D0100PA00X+033947Y+001937               S3      
317GND              VIA   -     D0100PA00X+033947Y+001677               S3      
317GND              VIA   -     D0100PA00X+033924Y+002683               S3      
317N/C              J1    -H2   D0420UA00X+035435Y+003855               S0      
327N20512383        J1    -13         A01X+035041Y+004692X0400Y1090R180 S2      
317P5V_STB_NODE1    VIA   -     D0100PA00X+034660Y+003856               S3      
317P5V_STB_NODE1    VIA   -     D0100PA00X+034615Y+003603               S3      
327N20512383        R194  -2          A01X+034949Y+006065X0180Y0200R090 S2      
317NNAME10559       VIA   -     D0100PA00X+035306Y+006150               S3      
317N20512383        VIA   -     D0100PA00X+034949Y+005770               S1      
327PD_NODE1_DM5     R207  -2          A01X+035258Y+006931X0180Y0200     S2      
327NNAME10559       R194  -1          A01X+034949Y+006380X0180Y0200R090 S2      
317PD_NODE1_DM5     VIA   -     D0100PA00X+035258Y+007429               S1      
317NNAME10052       VIA   -     D0100PA00X+033975Y+007338               S1      
327PD_NODE1_DM5     J2    -157        A01X+035256Y+008248X0150Y0810     S2      
327GND              J2    -155        A01X+035020Y+008248X0150Y0810     S2      
327NNAME10591       J2    -153        A01X+034784Y+008248X0150Y0810     S2      
327NNAME10587       J2    -151        A01X+034547Y+008248X0150Y0810     S2      
327GND              J2    -149        A01X+034311Y+008248X0150Y0810     S2      
327NNAME10582       J2    -147        A01X+034075Y+008248X0150Y0810     S2      
327NNAME10510       J2    -145        A01X+033839Y+008248X0150Y0810     S2      
317GND              VIA   -     D0100PA00X+035020Y+008828               S3      
317GND              VIA   -     D0100PA00X+034311Y+008843               S3      
317NNAME10582       VIA   -     D0100PA00X+034054Y+008865               S3      
317NNAME10587       VIA   -     D0100PA00X+034546Y+009084               S3      
317NNAME10588       VIA   -     D0100PA00X+035371Y+009306               S1      
317GND              VIA   -     D0100PA00X+034477Y+010172               S3      
317GND              VIA   -     D0100PA00X+035179Y+010540               S3      
317NNAME10591       VIA   -     D0100PA00X+034487Y+009485               S1      
317NNAME10510       VIA   -     D0100PA00X+034307Y+009937               S3      
317NNAME10521       VIA   -     D0100PA00X+034045Y+010191               S1      
327GND              R208  -1          A10X+033895Y+011730X0180Y0200R180 S1      
327GND              J2    -158        A01X+035374Y+011476X0150Y0810     S2      
327NNAME10584       J2    -156        A01X+035138Y+011476X0150Y0810     S2      
327NNAME10585       J2    -154        A01X+034902Y+011476X0150Y0810     S2      
327GND              J2    -152        A01X+034665Y+011476X0150Y0810     S2      
327NNAME10592       J2    -150        A01X+034429Y+011476X0150Y0810     S2      
327NNAME10521       J2    -148        A01X+034193Y+011476X0150Y0810     S2      
327GND              J2    -146        A01X+033957Y+011476X0150Y0810     S2      
317GND              VIA   -     D0100PA00X+034407Y+012440               S3      
317GND              VIA   -     D0100PA00X+035153Y+012470               S3      
317NNAME10592       VIA   -     D0100PA00X+034374Y+012097               S1      
317GND              VIA   -     D0100PA00X+035137Y+013437               S3      
317NNAME10585       VIA   -     D0100PA00X+035150Y+013097               S3      
317NNAME10584       VIA   -     D0100PA00X+035150Y+012797               S1      
317N/C              H4    -1    D1180UA00X+035433Y+024724               S0      
327NNAME10464       R174  -2          A10X+035110Y+028010X0180Y0200     S1      
327GND              R174  -1          A10X+034795Y+028010X0180Y0200     S1      
327NNAME10464       VIA   -           A10X+034322Y+028042X0260Y0260     S1      
327NNAME10468       R161  -2          A10X+035110Y+029010X0180Y0200     S1      
327GND              R161  -1          A10X+034795Y+029010X0180Y0200     S1      
327NNAME10467       R168  -2          A10X+035110Y+028410X0180Y0200     S1      
327GND              R168  -1          A10X+034795Y+028410X0180Y0200     S1      
327NNAME10533       R162  -2          A10X+035110Y+029410X0180Y0200     S1      
327GND              R162  -1          A10X+034795Y+029410X0180Y0200     S1      
327NNAME10537       R167  -2          A10X+034795Y+029810X0180Y0200R180 S1      
327GND              R167  -1          A10X+035110Y+029810X0180Y0200R180 S1      
317GND              VIA   -     D0100PA00X+034530Y+028485               S3      
317GND              VIA   -     D0100PA00X+034296Y+029152               S3      
317NNAME10527       VIA   -     D0100PA00X+034169Y+028601               S1      
327NNAME10533       VIA   -           A10X+034275Y+029533X0260Y0260     S1      
327GND              C61   -2          A01X+034680Y+029927X0180Y0200R180 S2      
327NNAME10469       C61   -1          A01X+034365Y+029927X0180Y0200R180 S2      
327NNAME10469       C60   -1          A01X+034252Y+030394X0280Y0320R270 S2      
327GND              C60   -2          A01X+034832Y+030394X0280Y0320R270 S2      
327NNAME10470       L6    -2          A01X+034270Y+031271X0180Y0200     S2      
327P1V05_NODE1      L6    -1          A01X+034585Y+031271X0180Y0200     S2      
327NNAME10469       L4    -2          A01X+034338Y+030873X0180Y0200     S2      
327P1V05_NODE1      L4    -1          A01X+034653Y+030873X0180Y0200     S2      
327NNAME10618       R141  -2          A10X+034452Y+030188X0180Y0200R180 S1      
327GND              R141  -1          A10X+034767Y+030188X0180Y0200R180 S1      
327NNAME10474       R171  -2          A10X+035110Y+030610X0180Y0200     S1      
327NNAME10538       R171  -1          A10X+034795Y+030610X0180Y0200     S1      
327P1V05_NODE1      R115  -2          A10X+035087Y+031410X0180Y0200     S1      
327NNAME10687       R115  -1          A10X+034772Y+031410X0180Y0200     S1      
327NNAME10538       R173  -2          A10X+034795Y+031010X0180Y0200R180 S1      
327GND              R173  -1          A10X+035110Y+031010X0180Y0200R180 S1      
317GND              VIA   -     D0100PA00X+035417Y+030892               S3      
317GND              VIA   -     D0100PA00X+035150Y+030180               S3      
317NNAME10469       VIA   -     D0100PA00X+034079Y+030711               S1      
317P1V05_NODE1      VIA   -     D0100PA00X+035390Y+031408               S3      
317NNAME10474       VIA   -     D0100PA00X+035384Y+030619               S3      
327NNAME10618       VIA   -           A10X+033949Y+030104X0260Y0260     S1      
327GND              C813  -2          A01X+035191Y+033118X0440Y0540R180 S2      
327NNAME10474       C813  -1          A01X+034443Y+033118X0440Y0540R180 S2      
327GND              C79   -2          A01X+034557Y+032247X0180Y0200R180 S2      
327NNAME10470       C79   -1          A01X+034242Y+032247X0180Y0200R180 S2      
327NNAME10470       C78   -1          A01X+034093Y+031760X0280Y0320R270 S2      
327GND              C78   -2          A01X+034673Y+031760X0280Y0320R270 S2      
327GND              C34   -2          A10X+035191Y+033118X0440Y0540     S1      
327P3V3_RTC_NODE1   C34   -1          A10X+034443Y+033118X0440Y0540     S1      
327P1V05_NODE1      R119  -2          A10X+035134Y+031823X0180Y0200     S1      
327NNAME10688       R119  -1          A10X+034819Y+031823X0180Y0200     S1      
317NNAME10474       VIA   -     D0100PA00X+033937Y+032918               S3      
317P3V3_RTC_NODE1   VIA   -     D0100PA00X+034191Y+032574               S3      
317P3V3_RTC_NODE1   VIA   -     D0100PA00X+034472Y+032574               S3      
317N/C              H2    -1    D1180UA00X+035433Y+034961               S0      
317NNAME10474       VIA   -     D0100PA00X+033960Y+033208               S3      
317NNAME10319       VIA   -     D0100PA00X+034388Y+035699               S3      
317NNAME10691       VIA   -     D0100PA00X+034911Y+037577               S3      
317NNAME10559       VIA   -     D0100PA00X+035242Y+037567               S3      
317P3V3_STB_NODE1   VIA   -     D0100PA00X+034602Y+037408               S3      
327NNAME10709       U5    -2          A01X+035208Y+038228X0260Y0760R180 S2      
327NNAME10425       U5    -1          A01X+034708Y+038228X0260Y0760R180 S2      
327NNAME10709       U4    -2          A01X+035208Y+038132X0220Y0680     S2      
327NNAME10425       U4    -1          A01X+034708Y+038132X0220Y0680     S2      
317P3V3_NODE1       VIA   -     D0100PA00X+034343Y+038594               S3      
317NNAME10421       VIA   -     D0100PA00X+034377Y+038217               S3      
327P3V3_NODE1       U5    -8          A01X+034708Y+040890X0260Y0760R180 S2      
327NNAME10710       U5    -7          A01X+035208Y+040890X0260Y0760R180 S2      
327P3V3_NODE1       U4    -8          A01X+034708Y+040995X0220Y0680     S2      
327NNAME10710       U4    -7          A01X+035208Y+040995X0220Y0680     S2      
317NNAME10710       VIA   -     D0100PA00X+035165Y+042027               S1      
327GND              C42   -2          A01X+033954Y+042485X0180Y0200     S2      
327P3V3_NODE1       C42   -1          A01X+034269Y+042485X0180Y0200     S2      
327NNAME10710       R177  -2          A01X+035103Y+042456X0180Y0200     S2      
317P3V3_NODE1       VIA   -     D0100PA00X+034686Y+042485               S3      
317NNAME10559       VIA   -     D0100PA00X+034527Y+045275               S1      
327N/C              U115  -21         A01X+035184Y+045902X0090Y0550R180 S2      
327NNAME10559       U115  -20         A01X+034987Y+045902X0090Y0550R180 S2      
327NNAME10421       U115  -19         A01X+034790Y+045902X0090Y0550R180 S2      
327NNAME10711       U115  -18         A01X+034593Y+045902X0090Y0550R180 S2      
327N/C              U115  -17         A01X+034396Y+045902X0090Y0550R180 S2      
327N/C              U115  -16         A01X+034199Y+045902X0090Y0550R180 S2      
327N/C              U115  -15         A01X+034003Y+045902X0090Y0550R180 S2      
327N/C              U115  -14         A01X+033806Y+045902X0090Y0550R180 S2      
317NNAME10421       VIA   -     D0100PA00X+034675Y+046653               S3      
317P1V8_NODE1       VIA   -     D0100PA00X+035289Y+047966               S3      
317P1V8_NODE1       VIA   -     D0100PA00X+034800Y+047915               S3      
317P1V8_NODE1       VIA   -     D0100PA00X+035226Y+048303               S3      
317NNAME10419       VIA   -     D0100PA00X+033876Y+047964               S3      
317NNAME10422       VIA   -     D0100PA00X+033951Y+048284               S1      
317NNAME10423       VIA   -     D0100PA00X+034822Y+048648               S1      
327PORT80_LOUT2     U115  -47         A01X+033806Y+049288X0090Y0550     S2      
327PORT80_LOUT3     U115  -46         A01X+034003Y+049288X0090Y0550     S2      
327PORT80_LOUT4     U115  -45         A01X+034199Y+049288X0090Y0550     S2      
327PORT80_LOUT7     U115  -44         A01X+034396Y+049288X0090Y0550     S2      
327CLK_33M_PORT80   U115  -43         A01X+034593Y+049288X0090Y0550     S2      
327NNAME10423       U115  -42         A01X+034790Y+049288X0090Y0550     S2      
327N/C              U115  -41         A01X+034987Y+049288X0090Y0550     S2      
327N/C              U115  -40         A01X+035184Y+049288X0090Y0550     S2      
317P1V8_NODE1       VIA   -     D0100PA00X+035216Y+050214               S3      
317P1V8_NODE1       VIA   -     D0100PA00X+035125Y+049975               S3      
317PORT80_LOUT7     VIA   -     D0100PA00X+034887Y+050157               S1      
317PORT80_LOUT4     VIA   -     D0100PA00X+034342Y+049797               S1      
327N53313501        R1255 -2          A01X+034151Y+050944X0180Y0200R270 S2      
327PORT80_LOUT3     R1255 -1          A01X+034151Y+050629X0180Y0200R270 S2      
327N53313513        R1256 -2          A01X+034601Y+050944X0180Y0200R270 S2      
327PORT80_LOUT4     R1256 -1          A01X+034601Y+050629X0180Y0200R270 S2      
327N53313596        R1259 -2          A01X+035051Y+050944X0180Y0200R270 S2      
327PORT80_LOUT7     R1259 -1          A01X+035051Y+050629X0180Y0200R270 S2      
317P1V8_NODE1       VIA   -     D0100PA00X+035340Y+050726               S3      
317P1V8_NODE1       VIA   -     D0100PA00X+035346Y+050454               S3      
317P1V8_NODE1       VIA   -     D0100PA00X+034819Y+051155               S3      
317P1V8_NODE1       VIA   -     D0100PA00X+035312Y+051000               S3      
317N53313558        VIA   -     D0100PA00X+035069Y+051638               S3      
317PORT80_LOUT3     VIA   -     D0100PA00X+034090Y+050374               S1      
317N53313577        VIA   -     D0100PA00X+035294Y+051803               S3      
317N53313501        VIA   -     D0100PA00X+034151Y+051243               S1      
317N53313596        VIA   -     D0100PA00X+035090Y+051252               S1      
317N53313513        VIA   -     D0100PA00X+034635Y+051729               S1      
327N53313513        D35   -C          A01X+034218Y+052151X0320Y0320R270 S2      
327P3V3_NODE1       D35   -A          A01X+034218Y+052741X0320Y0320R270 S2      
327N53313577        D37   -C          A01X+035418Y+052151X0320Y0320R270 S2      
327P3V3_NODE1       D37   -A          A01X+035418Y+052741X0320Y0320R270 S2      
327N53313558        D36   -C          A01X+034818Y+052151X0320Y0320R270 S2      
327P3V3_NODE1       D36   -A          A01X+034818Y+052741X0320Y0320R270 S2      
317P3V3_NODE1       VIA   -     D0100PA00X+034018Y+053179               S3      
317P3V3_NODE1       VIA   -     D0100PA00X+035111Y+053184               S3      
317NNAME10701       VIA   -     D0100PA00X+034033Y+054193               S3      
317P3V3_STB_NODE1   VIA   -     D0100PA00X+034101Y+053783               S3      
317NNAME10702       VIA   -     D0100PA00X+034219Y+056585               S3      
327NNAME10702       R1234 -2          A01X+034039Y+056957X0180Y0200R090 S2      
327GND              R1234 -1          A01X+034039Y+057272X0180Y0200R090 S2      
327GND              PC37  -2          A01X+034363Y+061301X0440Y0540     S2      
327P1V8_STB_NODE1   PC37  -1          A01X+035111Y+061301X0440Y0540     S2      
327GND              PC39  -2          A01X+034575Y+059921X0180Y0200     S2      
327P1V8_STB_NODE1   PC39  -1          A01X+034890Y+059921X0180Y0200     S2      
327GND              PC38  -2          A01X+034363Y+060501X0440Y0540     S2      
327P1V8_STB_NODE1   PC38  -1          A01X+035111Y+060501X0440Y0540     S2      
317GND              VIA   -     D0100PA00X+034276Y+059919               S3      
317GND              VIA   -     D0100PA00X+033962Y+060344               S3      
317GND              VIA   -     D0100PA00X+033962Y+060594               S3      
317GND              VIA   -     D0100PA00X+033938Y+061154               S3      
317P1V8_STB_NODE1   VIA   -     D0100PA00X+035196Y+059933               S1      
327GND              PC130 -2          A01X+034363Y+062101X0440Y0540     S2      
327P1V8_STB_NODE1   PC130 -1          A01X+035111Y+062101X0440Y0540     S2      
317GND              VIA   -     D0100PA00X+033960Y+062129               S3      
317GND              VIA   -     D0100PA00X+033960Y+061869               S3      
317GND              VIA   -     D0100PA00X+033938Y+061414               S3      
327I2C_SDC_SCL      U73   -8          A10X+034547Y+064451X0140Y0590R090 S1      
327P3V3_STB_NODE1   R801  -2          A01X+035367Y+064417X0180Y0200     S2      
327GND              U104  -S          A01X+035330Y+063803X0400Y0500R180 S2      
317GND              VIA   -     D0100PA00X+035330Y+063390               S3      
317I2C_PSU2_SDA     VIA   -     D0100PA00X+034034Y+063805               S3      
327I2C_SDC_SDA      VIA   -           A10X+035172Y+064419X0260Y0260     S1      
317NNAME10657       VIA   -     D0100PA00X+034067Y+064483               S3      
317NNAME10712       VIA   -     D0100PA00X+034848Y+063856               S1      
317CLK_33K_CPLD23   VIA   -     D0100PA00X+034558Y+063811               S3      
317P3V3_STB_NODE1   VIA   -     D0100PA00X+034767Y+064229               S3      
327I2C_SDC_SDA      U73   -7          A10X+034547Y+064706X0140Y0590R090 S1      
327UART_SW_S3_N     U73   -6          A10X+034547Y+064962X0140Y0590R090 S1      
327UART_SW_S2_N     U73   -5          A10X+034547Y+065218X0140Y0590R090 S1      
327GND              U73   -4          A10X+034547Y+065474X0140Y0590R090 S1      
327SDC_RST_N        U73   -3          A10X+034547Y+065730X0140Y0590R090 S1      
327UART_SW_S1_N     U73   -2          A10X+034547Y+065986X0140Y0590R090 S1      
327NNAME10657       U128  -75         A01X+033856Y+064714X0110Y0590     S2      
327GND              U128  -79         A01X+034545Y+065994X0110Y0590R270 S2      
327NNAME10713       U128  -78         A01X+034545Y+065797X0110Y0590R270 S2      
327NNAME10714       U128  -77         A01X+034545Y+065600X0110Y0590R270 S2      
327NNAME10712       U128  -76         A01X+034545Y+065403X0110Y0590R270 S2      
317GND              VIA   -     D0100PA00X+035173Y+065386               S3      
317P3V3_NODE1       VIA   -     D0100PA00X+035172Y+065932               S3      
317NNAME10714       VIA   -     D0100PA00X+034063Y+065509               S3      
317NNAME10713       VIA   -     D0100PA00X+035173Y+064921               S1      
327UART_SW_S0_N     U73   -1          A10X+034547Y+066242X0140Y0590R090 S1      
327P3V3_NODE1       U62   -24         A10X+034544Y+066858X0140Y0590R270 S1      
327I2C_COM3_SDA     U62   -23         A10X+034544Y+067114X0140Y0590R270 S1      
327I2C_COM3_SCL     U62   -22         A10X+034544Y+067370X0140Y0590R270 S1      
327NNAME10715       U128  -87         A01X+034545Y+067569X0110Y0590R270 S2      
327NNAME10716       U128  -86         A01X+034545Y+067372X0110Y0590R270 S2      
327NNAME10717       U128  -85         A01X+034545Y+067175X0110Y0590R270 S2      
327NNAME10706       U128  -84         A01X+034545Y+066978X0110Y0590R270 S2      
327NNAME10718       U128  -83         A01X+034545Y+066781X0110Y0590R270 S2      
327NNAME10719       U128  -82         A01X+034545Y+066585X0110Y0590R270 S2      
327NNAME10720       U128  -81         A01X+034545Y+066388X0110Y0590R270 S2      
327P3V3_NODE1       U128  -80         A01X+034545Y+066191X0110Y0590R270 S2      
317GND              VIA   -     D0100PA00X+033993Y+066122               S3      
317P3V3_NODE1       VIA   -     D0100PA00X+035390Y+066713               S3      
327N21700927        VIA   -           A10X+035173Y+067506X0260Y0260     S1      
317NNAME10720       VIA   -     D0100PA00X+035173Y+066345               S1      
317NNAME10716       VIA   -     D0100PA00X+034053Y+067566               S3      
317NNAME10706       VIA   -     D0100PA00X+035172Y+067002               S1      
317NNAME10721       VIA   -     D0100PA00X+033897Y+067078               S3      
317UART_SW_S0_N     VIA   -     D0100PA00X+034087Y+066504               S3      
327N21700927        U62   -21         A10X+034544Y+067626X0140Y0590R270 S1      
327T4_NODE4_EN      U62   -20         A10X+034544Y+067882X0140Y0590R270 S1      
327T4_NODE3_EN      U62   -19         A10X+034544Y+068138X0140Y0590R270 S1      
327T4_NODE2_EN      U62   -18         A10X+034544Y+068394X0140Y0590R270 S1      
327T4_NODE1_EN      U62   -17         A10X+034544Y+068650X0140Y0590R270 S1      
327T3_NODE4_EN      U62   -16         A10X+034544Y+068905X0140Y0590R270 S1      
327T3_NODE3_EN      U62   -15         A10X+034544Y+069161X0140Y0590R270 S1      
327NNAME10705       U128  -95         A01X+034545Y+069144X0110Y0590R270 S2      
327P3V3_NODE1       U128  -94         A01X+034545Y+068947X0110Y0590R270 S2      
327GND              U128  -93         A01X+034545Y+068750X0110Y0590R270 S2      
327NNAME10722       U128  -92         A01X+034545Y+068553X0110Y0590R270 S2      
327NNAME10704       U128  -91         A01X+034545Y+068356X0110Y0590R270 S2      
327NNAME10723       U128  -90         A01X+034545Y+068159X0110Y0590R270 S2      
327NNAME10724       U128  -89         A01X+034545Y+067962X0110Y0590R270 S2      
327NNAME10721       U128  -88         A01X+034545Y+067766X0110Y0590R270 S2      
317GND              VIA   -     D0100PA00X+034053Y+068660               S3      
317P3V3_NODE1       VIA   -     D0100PA00X+035326Y+068876               S3      
327T3_NODE2_EN      U62   -14         A10X+034544Y+069417X0140Y0590R270 S1      
327T3_NODE1_EN      U62   -13         A10X+034544Y+069673X0140Y0590R270 S1      
327NNAME10725       U128  -1          A01X+033856Y+070817X0110Y0590     S2      
327NNAME10726       U128  -100        A01X+034545Y+070128X0110Y0590R270 S2      
327NNAME10727       U128  -99         A01X+034545Y+069931X0110Y0590R270 S2      
327NNAME10728       U128  -98         A01X+034545Y+069734X0110Y0590R270 S2      
327NNAME10729       U128  -97         A01X+034545Y+069537X0110Y0590R270 S2      
327NNAME10730       U128  -96         A01X+034545Y+069340X0110Y0590R270 S2      
317P3V3_NODE1       VIA   -     D0100PA00X+035181Y+070680               S3      
317NNAME10728       VIA   -     D0100PA00X+033975Y+069527               S3      
317NNAME10729       VIA   -     D0100PA00X+033901Y+070041               S3      
317NNAME10727       VIA   -     D0100PA00X+033893Y+069775               S3      
327GND              R1177 -2          A01X+034761Y+071335X0180Y0200R270 S2      
327NNAME10725       R1177 -1          A01X+034761Y+071020X0180Y0200R270 S2      
317GND              VIA   -     D0100PA00X+034478Y+071335               S3      
317NNAME10698       VIA   -     D0100PA00X+035240Y+072213               S3      
317NNAME10716       VIA   -     D0100PA00X+033930Y+071680               S1      
317NNAME10704       VIA   -     D0100PA00X+034223Y+072094               S1      
317UART_SW_S0_N     VIA   -     D0100PA00X+034119Y+071238               S3      
317NNAME10725       VIA   -     D0100PA00X+035201Y+071397               S3      
317NNAME10725       VIA   -     D0100PA00X+034223Y+070938               S3      
327GND              C711  -2          A01X+034694Y+073908X0180Y0200R090 S2      
327GND              C714  -2          A01X+034294Y+072758X0180Y0200R090 S2      
327NNAME10730       C714  -1          A01X+034294Y+073073X0180Y0200R090 S2      
327GND              C717  -2          A01X+033844Y+073908X0180Y0200R090 S2      
327GND              C708  -2          A01X+035194Y+072758X0180Y0200R090 S2      
327NNAME10722       C708  -1          A01X+035194Y+073073X0180Y0200R090 S2      
327NNAME10730       R951  -1          A01X+034294Y+073908X0180Y0200R270 S2      
327NNAME10731       R948  -2          A01X+034744Y+073073X0180Y0200R270 S2      
327NNAME10704       R948  -1          A01X+034744Y+072758X0180Y0200R270 S2      
327NNAME10732       R954  -2          A01X+033844Y+073073X0180Y0200R270 S2      
327NNAME10705       R954  -1          A01X+033844Y+072758X0180Y0200R270 S2      
327NNAME10722       R945  -1          A01X+035094Y+073908X0180Y0200R270 S2      
317GND              VIA   -     D0100PA00X+034373Y+072458               S3      
317GND              VIA   -     D0100PA00X+035018Y+073588               S3      
317GND              VIA   -     D0100PA00X+035058Y+072443               S3      
317NNAME10730       VIA   -     D0100PA00X+034561Y+073398               S3      
317NNAME10722       VIA   -     D0100PA00X+035406Y+073479               S3      
327NNAME10731       C711  -1          A01X+034694Y+074223X0180Y0200R090 S2      
327NNAME10732       C717  -1          A01X+033844Y+074223X0180Y0200R090 S2      
327NNAME10733       R951  -2          A01X+034294Y+074223X0180Y0200R270 S2      
327NNAME10734       R945  -2          A01X+035094Y+074223X0180Y0200R270 S2      
317NNAME10735       VIA   -     D0100PA00X+035072Y+074572               S3      
317I2C_PSU2_R_SCL   VIA   -     D0100PA00X+034471Y+078578               S1      
317NNAME10732       VIA   -     D0100PA00X+035045Y+078498               S1      
327NNAME10708       VIA   -           A10X+033864Y+078572X0260Y0260     S1      
327NNAME10736       VIA   -           A10X+034337Y+077972X0260Y0260     S1      
327NNAME10735       VIA   -           A10X+034510Y+077191X0260Y0260     S1      
327NNAME10737       VIA   -           A10X+035063Y+077719X0260Y0260     S1      
327NNAME10736       J35   -A10        A10X+034258Y+080787X0300Y1660R180 S1      
327NNAME10735       J35   -A9         A10X+034652Y+080787X0300Y1660R180 S1      
327NNAME10737       J35   -A8         A10X+035045Y+080787X0300Y1660R180 S1      
327GND              J35   -A7         A10X+035439Y+080787X0300Y1660R180 S1      
327I2C_PSU2_R_SCL   J35   -B10        A01X+034258Y+080787X0300Y1660R180 S2      
327GND              J35   -B9         A01X+034652Y+080787X0300Y1660R180 S2      
327NNAME10732       J35   -B8         A01X+035045Y+080787X0300Y1660R180 S2      
327NNAME10733       J35   -B7         A01X+035439Y+080787X0300Y1660R180 S2      
317GND              VIA   -     D0100PA00X+034652Y+079029               S3      
317NNAME10424       VIA   -     D0100PA00X+036303Y+001293               S1      
327NNAME10738       R179  -2          A01X+036618Y+001572X0180Y0200R180 S2      
327NNAME10424       R179  -1          A01X+036303Y+001572X0180Y0200R180 S2      
327GND              J1    -12         A01X+035829Y+003019X0400Y1090R180 S2      
327NNAME10738       J1    -10         A01X+036616Y+003019X0400Y1090R180 S2      
317GND              VIA   -     D0100PA00X+035829Y+002133               S3      
317NNAME10738       VIA   -     D0100PA00X+036616Y+002182               S1      
327NNAME10739       J1    -11         A01X+035829Y+004692X0400Y1090R180 S2      
327NNAME10740       J1    -9          A01X+036616Y+004692X0400Y1090R180 S2      
327NNAME10739       R189  -2          A01X+035894Y+006065X0180Y0200R090 S2      
317NNAME10739       VIA   -     D0100PA00X+036193Y+006003               S1      
317NNAME10740       VIA   -     D0100PA00X+036730Y+006044               S1      
327GND              R207  -1          A01X+035573Y+006931X0180Y0200     S2      
327NNAME10422       R189  -1          A01X+035894Y+006380X0180Y0200R090 S2      
317GND              VIA   -     D0100PA00X+035655Y+007477               S3      
317NNAME10422       VIA   -     D0100PA00X+036567Y+006446               S3      
327NNAME10598       J2    -171        A01X+036910Y+008248X0150Y0810     S2      
327GND              J2    -169        A01X+036673Y+008248X0150Y0810     S2      
327NNAME10602       J2    -167        A01X+036437Y+008248X0150Y0810     S2      
327NNAME10666       J2    -165        A01X+036201Y+008248X0150Y0810     S2      
327GND              J2    -163        A01X+035965Y+008248X0150Y0810     S2      
327NNAME10586       J2    -161        A01X+035728Y+008248X0150Y0810     S2      
327NNAME10588       J2    -159        A01X+035492Y+008248X0150Y0810     S2      
317GND              VIA   -     D0100PA00X+036673Y+008848               S3      
317GND              VIA   -     D0100PA00X+035965Y+008817               S3      
317NNAME10666       VIA   -     D0100PA00X+036213Y+009088               S3      
317NNAME10598       VIA   -     D0100PA00X+036778Y+009175               S1      
317NNAME10586       VIA   -     D0100PA00X+035834Y+009095               S1      
317GND              VIA   -     D0100PA00X+036083Y+010854               S3      
317GND              VIA   -     D0100PA00X+036230Y+009867               S3      
317NNAME10602       VIA   -     D0100PA00X+036967Y+009985               S3      
317NNAME10590       VIA   -     D0100PA00X+036147Y+010176               S1      
317NNAME10603       VIA   -     D0100PA00X+035494Y+010419               S3      
317NNAME10516       VIA   -     D0100PA00X+035445Y+010809               S3      
327GND              J2    -170        A01X+036791Y+011476X0150Y0810     S2      
327NNAME10603       J2    -168        A01X+036555Y+011476X0150Y0810     S2      
327NNAME10604       J2    -166        A01X+036319Y+011476X0150Y0810     S2      
327GND              J2    -164        A01X+036083Y+011476X0150Y0810     S2      
327NNAME10517       J2    -162        A01X+035847Y+011476X0150Y0810     S2      
327NNAME10516       J2    -160        A01X+035610Y+011476X0150Y0810     S2      
317GND              VIA   -     D0100PA00X+036756Y+012082               S3      
317NNAME10604       VIA   -     D0100PA00X+036735Y+012393               S1      
317NNAME10517       VIA   -     D0100PA00X+036528Y+012813               S3      
327NNAME10474       R172  -2          A10X+036171Y+028032X0180Y0200     S1      
327NNAME10464       R172  -1          A10X+035856Y+028032X0180Y0200     S1      
327NNAME10474       R158  -2          A10X+036171Y+029032X0180Y0200     S1      
327NNAME10468       R158  -1          A10X+035856Y+029032X0180Y0200     S1      
327NNAME10474       R165  -2          A10X+036171Y+028432X0180Y0200     S1      
327NNAME10467       R165  -1          A10X+035856Y+028432X0180Y0200     S1      
327NNAME10474       R159  -2          A10X+036171Y+029432X0180Y0200     S1      
327NNAME10533       R159  -1          A10X+035856Y+029432X0180Y0200     S1      
327NNAME10474       R164  -2          A10X+036171Y+029832X0180Y0200     S1      
327NNAME10537       R164  -1          A10X+035856Y+029832X0180Y0200     S1      
317GND              VIA   -     D0100PA00X+035458Y+029810               S3      
317P1V05_NODE1      VIA   -     D0100PA00X+036422Y+029680               S3      
317GND              VIA   -     D0100PA00X+035740Y+030761               S3      
317P1V05_NODE1      VIA   -     D0100PA00X+036597Y+029919               S3      
317P1V05_NODE1      VIA   -     D0100PA00X+035684Y+031389               S1      
317NNAME10474       VIA   -     D0100PA00X+036928Y+030092               S3      
317NNAME10535       VIA   -     D0100PA00X+036722Y+030320               S1      
327P1V05_NODE1      R1215 -2          A01X+036503Y+032962X0180Y0200R270 S2      
327N45787194        R1215 -1          A01X+036503Y+032647X0180Y0200R270 S2      
327N45787194        Q42   -B          A01X+036993Y+032675X0320Y0360R180 S2      
317GND              VIA   -     D0100PA00X+036266Y+031699               S3      
317GND              VIA   -     D0100PA00X+035711Y+032921               S3      
317GND              VIA   -     D0100PA00X+035941Y+031708               S3      
317P3V3_RTC_NODE1   VIA   -     D0100PA00X+036904Y+031674               S3      
317N45787194        VIA   -     D0100PA00X+036993Y+032295               S1      
317GND              VIA   -     D0100PA00X+035912Y+033116               S3      
317GND              VIA   -     D0100PA00X+035704Y+033297               S3      
317P1V05_NODE1      VIA   -     D0100PA00X+036503Y+033248               S3      
317P3V3_STB_NODE1   VIA   -     D0100PA00X+036254Y+036144               S3      
327NNAME10709       R178  -2          A01X+036874Y+037051X0180Y0200     S2      
317NNAME10419       VIA   -     D0100PA00X+035469Y+037700               S3      
317NNAME10422       VIA   -     D0100PA00X+036465Y+037707               S3      
327GND              U5    -4          A01X+036208Y+038228X0260Y0760R180 S2      
327NNAME10689       U5    -3          A01X+035708Y+038228X0260Y0760R180 S2      
327GND              U4    -4          A01X+036208Y+038132X0220Y0680     S2      
327NNAME10689       U4    -3          A01X+035708Y+038132X0220Y0680     S2      
317GND              VIA   -     D0100PA00X+036096Y+038908               S3      
317NNAME10423       VIA   -     D0100PA00X+036488Y+038446               S3      
317NNAME10709       VIA   -     D0100PA00X+036458Y+039127               S1      
327NNAME10420       U5    -6          A01X+035708Y+040890X0260Y0760R180 S2      
327NNAME10490       U5    -5          A01X+036208Y+040890X0260Y0760R180 S2      
327NNAME10420       U4    -6          A01X+035708Y+040995X0220Y0680     S2      
327NNAME10490       U4    -5          A01X+036208Y+040995X0220Y0680     S2      
317P12V_AUX         VIA   -     D0100PA00X+036614Y+040764               S3      
317P12V_AUX         VIA   -     D0100PA00X+036035Y+039587               S3      
317GND              VIA   -     D0100PA00X+036928Y+041560               S3      
317P3V3_NODE1       VIA   -     D0100PA00X+035525Y+042068               S3      
317NNAME10257       VIA   -     D0100PA00X+036585Y+041487               S1      
327P3V3_NODE1       R177  -1          A01X+035418Y+042456X0180Y0200     S2      
327N53313577        R1257 -2          A01X+035821Y+044634X0180Y0200R090 S2      
327PORT80_LOUT6     R1257 -1          A01X+035821Y+044949X0180Y0200R090 S2      
317NNAME10474       VIA   -     D0100PA00X+036866Y+044948               S3      
317NNAME10474       VIA   -     D0100PA00X+036950Y+044587               S3      
317PORT80_LOUT6     VIA   -     D0100PA00X+035457Y+045156               S1      
317N53313577        VIA   -     D0100PA00X+035475Y+044533               S1      
327N/C              U115  -28         A01X+036384Y+047103X0090Y0550R270 S2      
327N/C              U115  -27         A01X+036384Y+046906X0090Y0550R270 S2      
327PORT80_LOUT5     U115  -26         A01X+036384Y+046709X0090Y0550R270 S2      
327N53313289        U115  -25         A01X+036384Y+046512X0090Y0550R270 S2      
327N/C              U115  -24         A01X+035774Y+045902X0090Y0550R180 S2      
327N/C              U115  -23         A01X+035577Y+045902X0090Y0550R180 S2      
327PORT80_LOUT6     U115  -22         A01X+035381Y+045902X0090Y0550R180 S2      
317N53313289        TP173 -1    D0100PA00X+036951Y+046439               S1      
327P3V3_NODE1       U115  -36         A01X+036384Y+048678X0090Y0550R270 S2      
327N53313389        U115  -35         A01X+036384Y+048481X0090Y0550R270 S2      
327N/C              U115  -34         A01X+036384Y+048284X0090Y0550R270 S2      
327N/C              U115  -33         A01X+036384Y+048087X0090Y0550R270 S2      
327N/C              U115  -32         A01X+036384Y+047890X0090Y0550R270 S2      
327N/C              U115  -31         A01X+036384Y+047694X0090Y0550R270 S2      
327P3V3_NODE1       U115  -30         A01X+036384Y+047497X0090Y0550R270 S2      
327GND              U115  -29         A01X+036384Y+047300X0090Y0550R270 S2      
317GND              VIA   -     D0100PA00X+035515Y+048676               S3      
317GND              VIA   -     D0100PA00X+036879Y+047300               S3      
327N/C              U115  -39         A01X+035381Y+049288X0090Y0550     S2      
327N/C              U115  -38         A01X+035577Y+049288X0090Y0550     S2      
327GND              U115  -37         A01X+035774Y+049288X0090Y0550     S2      
327GND              C811  -2          A01X+036894Y+050932X0180Y0200R090 S2      
327NNAME10741       C811  -1          A01X+036894Y+051247X0180Y0200R090 S2      
327NNAME10741       R1104 -2          A01X+036824Y+051638X0180Y0200R090 S2      
317GND              VIA   -     D0100PA00X+036894Y+050636               S3      
327N53313596        D38   -C          A01X+036018Y+052151X0320Y0320R270 S2      
327P3V3_NODE1       D38   -A          A01X+036018Y+052741X0320Y0320R270 S2      
327GND              R1104 -1          A01X+036824Y+051953X0180Y0200R090 S2      
317GND              VIA   -     D0100PA00X+036643Y+052772               S3      
317GND              VIA   -     D0100PA00X+036643Y+053022               S3      
317GND              VIA   -     D0100PA00X+036643Y+053272               S3      
317GND              VIA   -     D0100PA00X+036824Y+052267               S3      
317P3V3_NODE1       VIA   -     D0100PA00X+035818Y+053123               S3      
317P3V3_STB_NODE1   VIA   -     D0100PA00X+035782Y+053456               S3      
327NNAME10742       C816  -2          A01X+036543Y+054009X0180Y0200R090 S2      
327GND              C816  -1          A01X+036543Y+054324X0180Y0200R090 S2      
327NNAME10742       R1084 -2          A01X+036143Y+054009X0180Y0200R090 S2      
327P3V3_STB_NODE1   R1084 -1          A01X+036143Y+054324X0180Y0200R090 S2      
327GND              R1086 -1          A01X+036948Y+054347X0180Y0200R180 S2      
317GND              VIA   -     D0100PA00X+036533Y+054612               S3      
317GND              VIA   -     D0100PA00X+036869Y+054616               S3      
317NNAME10742       VIA   -     D0100PA00X+036883Y+053978               S1      
317NNAME10063       VIA   -     D0100PA00X+036992Y+059225               S3      
317NNAME10063       VIA   -     D0100PA00X+036985Y+058890               S3      
327P1V8_STB_NODE1   PL4   -2          A01X+036114Y+061135X0848Y1300R180 S2      
317P1V8_STB_NODE1   VIA   -     D0100PA00X+036065Y+060264               S3      
317P1V8_STB_NODE1   VIA   -     D0100PA00X+035497Y+060559               S3      
317P1V8_STB_NODE1   VIA   -     D0100PA00X+035497Y+060259               S3      
317P1V8_STB_NODE1   VIA   -     D0100PA00X+035497Y+061159               S3      
327P3V3_STB_NODE1   R800  -2          A01X+036748Y+062766X0180Y0200R090 S2      
327N52410998        U104  -D          A01X+035730Y+062923X0400Y0500R180 S2      
317P1V8_STB_NODE1   VIA   -     D0100PA00X+036147Y+062059               S1      
317P1V8_STB_NODE1   VIA   -     D0100PA00X+035497Y+061459               S3      
317P1V8_STB_NODE1   VIA   -     D0100PA00X+035497Y+062059               S3      
317P1V8_STB_NODE1   VIA   -     D0100PA00X+035497Y+062359               S3      
327GND              C886  -1          A01X+036753Y+064151X0280Y0320R180 S2      
327N52410998        C886  -2          A01X+036753Y+063571X0280Y0320R180 S2      
327NNAME10743       R801  -1          A01X+035682Y+064417X0180Y0200     S2      
327N52410998        R800  -1          A01X+036748Y+063081X0180Y0200R090 S2      
327NNAME10744       R912  -2          A10X+035911Y+063713X0180Y0200     S1      
327NNAME10712       R912  -1          A10X+035596Y+063713X0180Y0200     S1      
327P3V3_NODE1       R781  -2          A10X+035911Y+064113X0180Y0200     S1      
327I2C_SDC_SCL      R781  -1          A10X+035596Y+064113X0180Y0200     S1      
327NNAME10743       U104  -G          A01X+036130Y+063803X0400Y0500R180 S2      
317P3V3_NODE1       VIA   -     D0100PA00X+036156Y+064518               S3      
327I2C_SDC_SCL      VIA   -           A10X+036495Y+063910X0260Y0260     S1      
317P3V3_STB_NODE1   VIA   -     D0100PA00X+036353Y+062973               S3      
327GND              C581  -2          A01X+035911Y+065913X0180Y0200R180 S2      
327P3V3_NODE1       C581  -1          A01X+035596Y+065913X0180Y0200R180 S2      
327P3V3_NODE1       R785  -2          A10X+035911Y+065713X0180Y0200     S1      
327UART_SW_S1_N     R785  -1          A10X+035596Y+065713X0180Y0200     S1      
327P3V3_NODE1       R786  -2          A10X+035911Y+065313X0180Y0200     S1      
327UART_SW_S2_N     R786  -1          A10X+035596Y+065313X0180Y0200     S1      
327P3V3_NODE1       R787  -2          A10X+035911Y+064913X0180Y0200     S1      
327UART_SW_S3_N     R787  -1          A10X+035596Y+064913X0180Y0200     S1      
327P3V3_NODE1       R780  -2          A10X+035911Y+064518X0180Y0200     S1      
327I2C_SDC_SDA      R780  -1          A10X+035596Y+064518X0180Y0200     S1      
317GND              VIA   -     D0100PA00X+036786Y+065757               S3      
317GND              VIA   -     D0100PA00X+036507Y+065807               S3      
317FAN6_TACH        VIA   -     D0100PA00X+036599Y+064527               S1      
317FAN5_TACH        VIA   -     D0100PA00X+036787Y+065024               S1      
317NNAME10744       VIA   -     D0100PA00X+036498Y+065527               S1      
317NNAME10743       VIA   -     D0100PA00X+036334Y+065051               S1      
317P3V3_NODE1       VIA   -     D0100PA00X+036165Y+065854               S3      
317P3V3_NODE1       VIA   -     D0100PA00X+036158Y+065276               S3      
327P3V3_NODE1       C568  -2          A10X+035596Y+066513X0180Y0200R180 S1      
327GND              C568  -1          A10X+035911Y+066513X0180Y0200R180 S1      
327P5V_NODE1        R709  -2          A10X+035911Y+067313X0180Y0200     S1      
327T4_NODE4_EN      R709  -1          A10X+035596Y+067313X0180Y0200     S1      
327GND              R687  -2          A10X+035911Y+066913X0180Y0200     S1      
327N21700927        R687  -1          A10X+035596Y+066913X0180Y0200     S1      
327P3V3_NODE1       R784  -2          A10X+035911Y+066113X0180Y0200     S1      
327UART_SW_S0_N     R784  -1          A10X+035596Y+066113X0180Y0200     S1      
327NNAME10745       R936  -2          A01X+035910Y+067513X0180Y0200R180 S2      
327NNAME10715       R936  -1          A01X+035595Y+067513X0180Y0200R180 S2      
327NNAME10735       R918  -2          A01X+035911Y+066313X0180Y0200R180 S2      
327NNAME10720       R918  -1          A01X+035596Y+066313X0180Y0200R180 S2      
317GND              VIA   -     D0100PA00X+036217Y+066513               S3      
317FAN3_TACH        VIA   -     D0100PA00X+036820Y+067213               S3      
317FAN1_TACH        VIA   -     D0100PA00X+036810Y+066813               S3      
317NNAME10745       VIA   -     D0100PA00X+036181Y+067501               S3      
317NNAME10735       VIA   -     D0100PA00X+036562Y+066307               S1      
317P5V_NODE1        VIA   -     D0100PA00X+036166Y+067131               S3      
317NNAME10719       VIA   -     D0100PA00X+036538Y+066897               S1      
317NNAME10717       VIA   -     D0100PA00X+036516Y+067292               S3      
317NNAME10718       VIA   -     D0100PA00X+036176Y+066872               S3      
327GND              C909  -2          A01X+035909Y+069062X0180Y0200R180 S2      
327P3V3_NODE1       C909  -1          A01X+035594Y+069062X0180Y0200R180 S2      
327P5V_NODE1        R700  -2          A10X+035911Y+068913X0180Y0200     S1      
327T3_NODE4_EN      R700  -1          A10X+035596Y+068913X0180Y0200     S1      
327P5V_NODE1        R703  -2          A10X+035911Y+068513X0180Y0200     S1      
327T4_NODE1_EN      R703  -1          A10X+035596Y+068513X0180Y0200     S1      
327NNAME10746       R942  -2          A01X+035910Y+067913X0180Y0200R180 S2      
327NNAME10724       R942  -1          A01X+035595Y+067913X0180Y0200R180 S2      
327P5V_NODE1        R705  -2          A10X+035911Y+068113X0180Y0200     S1      
327T4_NODE2_EN      R705  -1          A10X+035596Y+068113X0180Y0200     S1      
327P5V_NODE1        R707  -2          A10X+035911Y+067713X0180Y0200     S1      
327T4_NODE3_EN      R707  -1          A10X+035596Y+067713X0180Y0200     S1      
317GND              VIA   -     D0100PA00X+036740Y+068465               S3      
317GND              VIA   -     D0100PA00X+036787Y+067733               S3      
317GND              VIA   -     D0100PA00X+036165Y+068923               S3      
317I2C_COM3_SCL     VIA   -     D0100PA00X+036707Y+068109               S3      
317NNAME10746       VIA   -     D0100PA00X+036432Y+068043               S3      
317P3V3_NODE1       VIA   -     D0100PA00X+036750Y+069025               S3      
317P5V_NODE1        VIA   -     D0100PA00X+036151Y+068089               S3      
317P5V_NODE1        VIA   -     D0100PA00X+036204Y+068488               S3      
317NNAME10723       VIA   -     D0100PA00X+036465Y+068402               S3      
327NNAME10724       VIA   -           A01X+035652Y+068374X0300Y0300     S2      
317NNAME10722       VIA   -     D0100PA00X+036477Y+068796               S1      
317NNAME10715       VIA   -     D0100PA00X+036509Y+067692               S1      
327P3V3_NODE1       R1252 -2          A01X+035596Y+070713X0180Y0200     S2      
327NNAME10728       R1252 -1          A01X+035911Y+070713X0180Y0200     S2      
327P5V_NODE1        R697  -2          A10X+035911Y+070113X0180Y0200     S1      
327T3_NODE1_EN      R697  -1          A10X+035596Y+070113X0180Y0200     S1      
327P5V_NODE1        R698  -2          A10X+035911Y+069713X0180Y0200     S1      
327T3_NODE2_EN      R698  -1          A10X+035596Y+069713X0180Y0200     S1      
327P5V_NODE1        R699  -2          A10X+035911Y+069313X0180Y0200     S1      
327T3_NODE3_EN      R699  -1          A10X+035596Y+069313X0180Y0200     S1      
327GND              R810  -2          A01X+035911Y+070313X0180Y0200R180 S2      
327NNAME10728       R810  -1          A01X+035596Y+070313X0180Y0200R180 S2      
327GND              R809  -2          A01X+035911Y+069913X0180Y0200R180 S2      
327NNAME10729       R809  -1          A01X+035596Y+069913X0180Y0200R180 S2      
327GND              R1178 -2          A01X+035911Y+069513X0180Y0200R180 S2      
327NNAME10729       R1178 -1          A01X+035596Y+069513X0180Y0200R180 S2      
317GND              VIA   -     D0100PA00X+036484Y+069833               S3      
317GND              VIA   -     D0100PA00X+036179Y+069913               S3      
317GND              VIA   -     D0100PA00X+036172Y+069513               S3      
317P3V3_NODE1       VIA   -     D0100PA00X+036748Y+070517               S3      
317P3V3_NODE1       VIA   -     D0100PA00X+036761Y+069305               S3      
317P5V_NODE1        VIA   -     D0100PA00X+036158Y+070386               S3      
317P5V_NODE1        VIA   -     D0100PA00X+036359Y+070232               S3      
317NNAME10730       VIA   -     D0100PA00X+036412Y+069299               S1      
317NNAME10726       VIA   -     D0100PA00X+036752Y+070171               S1      
327GND              C693  -2          A01X+036025Y+072354X0180Y0200R180 S2      
327NNAME10698       C693  -1          A01X+035710Y+072354X0180Y0200R180 S2      
327NNAME10698       R930  -2          A10X+035710Y+072354X0180Y0200R180 S1      
327NNAME10717       R930  -1          A10X+036025Y+072354X0180Y0200R180 S1      
327P3V3_NODE1       R1196 -2          A10X+036892Y+071691X0180Y0200R270 S1      
327PCA_CPLD_WDT2    R1196 -1          A10X+036892Y+072006X0180Y0200R270 S1      
327P3V3_NODE1       R812  -2          A10X+036492Y+071691X0180Y0200R270 S1      
327TACKOVER_EN_N    R812  -1          A10X+036492Y+072006X0180Y0200R270 S1      
327GND              R811  -2          A01X+035911Y+071113X0180Y0200R180 S2      
327NNAME10725       R811  -1          A01X+035596Y+071113X0180Y0200R180 S2      
327T5_NODE3_EN      R902  -1          A01X+036943Y+072362X0180Y0200R180 S2      
317GND              VIA   -     D0100PA00X+036651Y+072362               S3      
317GND              VIA   -     D0100PA00X+036135Y+072072               S3      
317GND              VIA   -     D0100PA00X+036149Y+071251               S3      
317P3V3_NODE1       VIA   -     D0100PA00X+036735Y+071366               S3      
317NNAME10717       VIA   -     D0100PA00X+035783Y+071868               S1      
327GND              C678  -2          A01X+036934Y+073146X0180Y0200     S2      
327GND              C684  -2          A01X+035710Y+073554X0180Y0200     S2      
327NNAME10706       C684  -1          A01X+036025Y+073554X0180Y0200     S2      
327GND              C687  -2          A01X+036025Y+072754X0180Y0200R180 S2      
327NNAME10708       C687  -1          A01X+035710Y+072754X0180Y0200R180 S2      
327GND              C690  -2          A01X+036934Y+072746X0180Y0200     S2      
327GND              C665  -2          A10X+036943Y+072762X0180Y0200R180 S1      
327NNAME10737       R915  -2          A10X+036934Y+073546X0180Y0200R180 S1      
327NNAME10736       R921  -2          A10X+035710Y+073554X0180Y0200R180 S1      
327NNAME10706       R921  -1          A10X+036025Y+073554X0180Y0200R180 S1      
327NNAME10707       R927  -2          A10X+036934Y+073146X0180Y0200R180 S1      
327NNAME10708       R924  -2          A10X+035710Y+072754X0180Y0200R180 S1      
327NNAME10718       R924  -1          A10X+036025Y+072754X0180Y0200R180 S1      
327T5_NODE4_EN_R    R905  -2          A01X+036934Y+073546X0180Y0200     S2      
317GND              VIA   -     D0100PA00X+036316Y+073954               S3      
317GND              VIA   -     D0100PA00X+036643Y+073146               S3      
317GND              VIA   -     D0100PA00X+035710Y+073298               S3      
317GND              VIA   -     D0100PA00X+036025Y+073082               S3      
317NNAME10708       VIA   -     D0100PA00X+035452Y+072870               S3      
317NNAME10706       VIA   -     D0100PA00X+036346Y+073539               S3      
317NNAME10718       VIA   -     D0100PA00X+036475Y+072782               S1      
327GND              C681  -2          A01X+036025Y+073954X0180Y0200R180 S2      
327NNAME10735       C681  -1          A01X+035710Y+073954X0180Y0200R180 S2      
327GND              C675  -2          A10X+036025Y+073954X0180Y0200     S1      
327NNAME10744       C675  -1          A10X+035710Y+073954X0180Y0200     S1      
327NNAME10746       C705  -1          A01X+036934Y+073946X0180Y0200R180 S2      
327GND              C702  -2          A10X+036934Y+074346X0180Y0200R180 S1      
327T5_NODE4_EN_R    C668  -1          A10X+036934Y+073946X0180Y0200     S1      
327GND              C672  -2          A01X+036025Y+074354X0180Y0200R180 S2      
327NNAME10714       C672  -1          A01X+035710Y+074354X0180Y0200R180 S2      
327NNAME10747       R909  -2          A10X+036025Y+074354X0180Y0200     S1      
327NNAME10714       R909  -1          A10X+035710Y+074354X0180Y0200     S1      
327NNAME10748       R939  -2          A01X+036934Y+074346X0180Y0200     S2      
317GND              VIA   -     D0100PA00X+036336Y+074354               S3      
317NNAME10746       VIA   -     D0100PA00X+036409Y+074857               S1      
317NNAME10744       VIA   -     D0100PA00X+035442Y+074920               S3      
317NNAME10714       VIA   -     D0100PA00X+035761Y+074830               S1      
317T5_NODE4_EN_R    VIA   -     D0100PA00X+036686Y+073996               S3      
317NNAME10733       VIA   -     D0100PA00X+035487Y+077139               S1      
317NNAME10731       VIA   -     D0100PA00X+036016Y+077552               S1      
317NNAME10734       VIA   -     D0100PA00X+036330Y+078130               S1      
317NNAME10748       VIA   -     D0100PA00X+036790Y+077833               S1      
327NNAME10744       VIA   -           A10X+035660Y+078209X0260Y0260     S1      
327NNAME10747       VIA   -           A10X+036226Y+078642X0260Y0260     S1      
327NNAME10744       J35   -A6         A10X+035833Y+080787X0300Y1660R180 S1      
327NNAME10747       J35   -A5         A10X+036226Y+080787X0300Y1660R180 S1      
327GND              J35   -A4         A10X+036620Y+080787X0300Y1660R180 S1      
327T5_NODE4_EN_R    J35   -A3         A10X+037014Y+080787X0300Y1660R180 S1      
327NNAME10731       J35   -B6         A01X+035833Y+080787X0300Y1660R180 S2      
327NNAME10734       J35   -B5         A01X+036226Y+080787X0300Y1660R180 S2      
327GND              J35   -B4         A01X+036620Y+080787X0300Y1660R180 S2      
327NNAME10746       J35   -B3         A01X+037014Y+080787X0300Y1660R180 S2      
317GND              VIA   -     D0100PA00X+036620Y+078798               S3      
317GND              VIA   -     D0100PA00X+035439Y+079029               S3      
317GND              VIA   -     D0100PA00X+036620Y+079098               S3      
327P5V_NODE1        C135  -2          A01X+037403Y+001779X0180Y0200     S2      
327GND              C135  -1          A01X+037718Y+001779X0180Y0200     S2      
327P5V_NODE1        J1    -8          A01X+037403Y+003019X0400Y1090R180 S2      
327NNAME10749       J1    -6          A01X+038191Y+003019X0400Y1090R180 S2      
317GND              VIA   -     D0100PA00X+037994Y+001779               S3      
317GND              VIA   -     D0100PA00X+038299Y+001752               S3      
317P5V_NODE1        VIA   -     D0100PA00X+037118Y+001779               S3      
317P5V_NODE1        VIA   -     D0100PA00X+037096Y+002058               S3      
317NNAME10749       VIA   -     D0100PA00X+038191Y+002151               S1      
327NNAME10750       J1    -7          A01X+037403Y+004692X0400Y1090R180 S2      
327NNAME10751       J1    -5          A01X+038191Y+004692X0400Y1090R180 S2      
327NNAME10750       R191  -2          A01X+037905Y+006099X0180Y0200R090 S2      
327NNAME10740       R192  -2          A01X+037005Y+006082X0180Y0200R090 S2      
317NNAME10751       VIA   -     D0100PA00X+038328Y+005994               S1      
317NNAME10750       VIA   -     D0100PA00X+037601Y+006099               S1      
327NNAME10421       R191  -1          A01X+037905Y+006414X0180Y0200R090 S2      
327NNAME10419       R192  -1          A01X+037005Y+006397X0180Y0200R090 S2      
317NNAME10421       VIA   -     D0100PA00X+038325Y+006414               S3      
317NNAME10419       VIA   -     D0100PA00X+037356Y+006397               S3      
327NNAME10605       J2    -183        A01X+038327Y+008248X0150Y0810     S2      
327GND              J2    -181        A01X+038091Y+008248X0150Y0810     S2      
327NNAME10594       J2    -179        A01X+037854Y+008248X0150Y0810     S2      
327NNAME10589       J2    -177        A01X+037618Y+008248X0150Y0810     S2      
327GND              J2    -175        A01X+037382Y+008248X0150Y0810     S2      
327NNAME10600       J2    -173        A01X+037146Y+008248X0150Y0810     S2      
317GND              VIA   -     D0100PA00X+038091Y+008813               S3      
317GND              VIA   -     D0100PA00X+037382Y+008840               S3      
317NNAME10600       VIA   -     D0100PA00X+037278Y+009175               S1      
317GND              VIA   -     D0100PA00X+038445Y+010883               S3      
317GND              VIA   -     D0100PA00X+037262Y+009836               S3      
317GND              VIA   -     D0100PA00X+038409Y+009874               S3      
317GND              VIA   -     D0100PA00X+037916Y+010292               S3      
317GND              VIA   -     D0100PA00X+037403Y+009500               S3      
317NNAME10610       VIA   -     D0100PA00X+038209Y+010365               S3      
317NNAME10594       VIA   -     D0100PA00X+038048Y+009905               S1      
317NNAME10615       VIA   -     D0100PA00X+037873Y+010599               S1      
317NNAME10605       VIA   -     D0100PA00X+038486Y+009544               S1      
317NNAME10599       VIA   -     D0100PA00X+037610Y+010878               S3      
317NNAME10589       VIA   -     D0100PA00X+037672Y+009418               S3      
327PD_NODE1_DM6     R206  -2          A10X+037851Y+011782X0180Y0200     S1      
327GND              R206  -1          A10X+037536Y+011782X0180Y0200     S1      
327GND              J2    -184        A01X+038445Y+011476X0150Y0810     S2      
327NNAME10610       J2    -182        A01X+038209Y+011476X0150Y0810     S2      
327NNAME10615       J2    -180        A01X+037973Y+011476X0150Y0810     S2      
327GND              J2    -178        A01X+037736Y+011476X0150Y0810     S2      
327NNAME10599       J2    -176        A01X+037500Y+011476X0150Y0810     S2      
327NNAME10590       J2    -174        A01X+037264Y+011476X0150Y0810     S2      
327PD_NODE1_DM6     J2    -172        A01X+037028Y+011476X0150Y0810     S2      
317GND              VIA   -     D0100PA00X+037736Y+012111               S3      
317PD_NODE1_DM6     VIA   -     D0100PA00X+037818Y+012490               S1      
317P1V05_NODE1      VIA   -     D0100PA00X+037404Y+030498               S3      
317P1V05_NODE1      VIA   -     D0100PA00X+037364Y+030108               S3      
317NNAME10474       VIA   -     D0100PA00X+037046Y+030591               S3      
317NNAME10474       VIA   -     D0100PA00X+037109Y+030349               S3      
327NNAME10687       Q42   -E          A01X+037741Y+032675X0320Y0360R180 S2      
317NNAME10687       VIA   -     D0100PA00X+038425Y+031916               S3      
327NNAME10553       Q42   -C          A01X+037367Y+033462X0320Y0360R180 S2      
317NNAME10553       VIA   -     D0100PA00X+037208Y+033057               S1      
327NNAME10405       R178  -1          A01X+037189Y+037051X0180Y0200     S2      
317NNAME10422       VIA   -     D0100PA00X+037956Y+037496               S3      
317NNAME10559       VIA   -     D0100PA00X+037972Y+037226               S3      
317P3V3_NODE1       VIA   -     D0100PA00X+037883Y+038635               S3      
317NNAME10561       VIA   -     D0100PA00X+038262Y+039188               S3      
317NNAME10421       VIA   -     D0100PA00X+037930Y+038086               S3      
317NNAME10419       VIA   -     D0100PA00X+037929Y+037802               S3      
317NNAME10423       VIA   -     D0100PA00X+037975Y+038397               S3      
317NNAME10560       VIA   -     D0100PA00X+038219Y+038808               S1      
317NNAME10424       VIA   -     D0100PA00X+037660Y+040805               S3      
317NNAME10405       VIA   -     D0100PA00X+038268Y+040820               S3      
317GND              VIA   -     D0100PA00X+037456Y+041242               S3      
317NNAME10138       VIA   -     D0100PA00X+037126Y+041288               S1      
317GND              VIA   -     D0100PA00X+037615Y+043041               S3      
317LAN2_DISABLE_N   VIA   -     D0100PA00X+038375Y+043706               S3      
317NNAME10474       VIA   -     D0100PA00X+037232Y+043951               S3      
317NNAME10474       VIA   -     D0100PA00X+037195Y+043053               S1      
317CLK_33M_PORT80   VIA   -     D0100PA00X+037891Y+043087               S3      
317NNAME10474       VIA   -     D0100PA00X+037108Y+044828               S3      
317NNAME10474       VIA   -     D0100PA00X+037271Y+044571               S3      
327N53313558        R1258 -2          A01X+037806Y+046708X0180Y0200R180 S2      
327PORT80_LOUT5     R1258 -1          A01X+037491Y+046708X0180Y0200R180 S2      
317PORT80_LOUT5     VIA   -     D0100PA00X+037519Y+046400               S1      
317N53313558        VIA   -     D0100PA00X+038124Y+046717               S1      
327GND              C1122 -2          A01X+037421Y+047337X0180Y0200R090 S2      
327P3V3_NODE1       C1122 -1          A01X+037421Y+047652X0180Y0200R090 S2      
327GND              C1119 -1          A01X+037420Y+048487X0180Y0200R270 S2      
317N53313389        TP172 -1    D0100PA00X+037108Y+048159               S1      
317GND              VIA   -     D0100PA00X+037420Y+048208               S3      
317GND              VIA   -     D0100PA00X+037728Y+047337               S3      
317P3V3_NODE1       VIA   -     D0100PA00X+037421Y+047933               S3      
327P3V3_NODE1       C1119 -2          A01X+037420Y+048802X0180Y0200R270 S2      
317GND              VIA   -     D0100PA00X+037385Y+049659               S3      
317P1V05_NODE1      VIA   -     D0100PA00X+038176Y+049600               S3      
317P3V3_NODE1       VIA   -     D0100PA00X+037420Y+049103               S3      
317CLK_33M_PORT80   VIA   -     D0100PA00X+037654Y+049839               S1      
327GND              C810  -2          A01X+037479Y+050828X0440Y0540R090 S2      
327P1V8_STB_NODE1   C810  -1          A01X+037479Y+051576X0440Y0540R090 S2      
327GND              C809  -2          A01X+038079Y+051480X0180Y0200R090 S2      
327P5V_STB_NODE1    C809  -1          A01X+038079Y+051795X0180Y0200R090 S2      
317GND              VIA   -     D0100PA00X+037918Y+050980               S3      
317GND              VIA   -     D0100PA00X+038392Y+051480               S3      
317P5V_STB_NODE1    VIA   -     D0100PA00X+038362Y+051786               S1      
327P5V_STB_NODE1    U119  -10         A01X+037929Y+052417X0110Y0360R180 S2      
327NNAME10741       U119  -6          A01X+037141Y+052417X0110Y0360     S2      
327P1V8_STB_NODE1   U119  -9          A01X+037732Y+052417X0110Y0360R180 S2      
327P1V8_STB_NODE1   U119  -8          A01X+037535Y+052417X0110Y0360R180 S2      
327P1V8_STB_NODE1   U119  -7          A01X+037338Y+052417X0110Y0360R180 S2      
327GND              U119  -TH         A01X+037535Y+053027X0690Y1050R270 S2      
317GND              VIA   -     D0100PA00X+038504Y+052175               S3      
317GND              VIA   -     D0100PA00X+038459Y+052607               S3      
317GND              VIA   -     D0100PA00X+038263Y+053032               S3      
317GND              VIA   -     D0100PA00X+038263Y+052782               S3      
317GND              VIA   -     D0100PA00X+038263Y+053282               S3      
317P1V8_STB_NODE1   VIA   -     D0100PA00X+037354Y+052021               S3      
317P1V8_STB_NODE1   VIA   -     D0100PA00X+037653Y+052014               S1      
327NNAME10752       R1086 -2          A01X+037263Y+054347X0180Y0200R180 S2      
327NNAME10753       R1085 -2          A01X+037604Y+054758X0180Y0200R180 S2      
327NNAME10752       R1085 -1          A01X+037289Y+054758X0180Y0200R180 S2      
327NNAME10753       J21   -2          A01X+038070Y+054658X0180Y0200R270 S2      
327NNAME10474       J21   -1          A01X+038070Y+054343X0200Y0400R180 S2      
327NNAME10742       U119  -5          A01X+037141Y+053637X0110Y0360     S2      
327NNAME10474       U119  -1          A01X+037929Y+053637X0110Y0360R180 S2      
327NNAME10752       U119  -4          A01X+037338Y+053637X0110Y0360R180 S2      
327NNAME10474       U119  -3          A01X+037535Y+053637X0110Y0360R180 S2      
327NNAME10474       U119  -2          A01X+037732Y+053637X0110Y0360R180 S2      
317NNAME10753       VIA   -     D0100PA00X+037973Y+054939               S1      
317NNAME10752       VIA   -     D0100PA00X+037031Y+055032               S1      
317NNAME10474       VIA   -     D0100PA00X+037715Y+054315               S3      
317NNAME10474       VIA   -     D0100PA00X+037649Y+054057               S3      
317NNAME10474       VIA   -     D0100PA00X+038260Y+053738               S3      
317NNAME10474       VIA   -     D0100PA00X+038233Y+054041               S1      
327NNAME10753       C815  -2          A01X+037604Y+055158X0180Y0200R180 S2      
327NNAME10752       C815  -1          A01X+037289Y+055158X0180Y0200R180 S2      
317GND              VIA   -     D0100PA00X+038449Y+055237               S3      
317GND              VIA   -     D0100PA00X+038260Y+055417               S3      
317P3V3_NODE1       VIA   -     D0100PA00X+038541Y+056612               S3      
317GND              VIA   -     D0100PA00X+038334Y+059066               S3      
317GND              VIA   -     D0100PA00X+038334Y+059326               S3      
317NNAME10063       VIA   -     D0100PA00X+037345Y+058905               S3      
317NNAME10063       VIA   -     D0100PA00X+037352Y+059240               S3      
327NNAME10754       PL4   -1          A01X+038417Y+061135X0848Y1300R180 S2      
327GND              U105  -S          A01X+038122Y+063000X0400Y0500     S2      
327N52410998        U105  -G          A01X+037322Y+063000X0400Y0500     S2      
327N52411040        U105  -D          A01X+037722Y+063880X0400Y0500     S2      
317GND              VIA   -     D0100PA00X+038557Y+063000               S1      
317GND              VIA   -     D0100PA00X+037141Y+064151               S3      
317P12V_AUX         VIA   -     D0100PA00X+038303Y+064027               S3      
317N52410998        VIA   -     D0100PA00X+037322Y+063422               S1      
317N52411040        VIA   -     D0100PA00X+038258Y+063741               S1      
327N/C              U70   -8          A01X+038476Y+064524X0140Y0610R270 S2      
327FAN6_TACH_IN     U70   -7          A01X+038476Y+064774X0140Y0610R270 S2      
327FAN5_TACH_IN     U70   -6          A01X+038476Y+065024X0140Y0610R270 S2      
327N/C              U70   -5          A01X+038476Y+065274X0140Y0610R270 S2      
327PU_FAN_TACH      U70   -4          A01X+038476Y+065524X0140Y0610R270 S2      
327P3V3_NODE1       U70   -3          A01X+038476Y+065774X0140Y0610R270 S2      
327GND              U70   -2          A01X+038476Y+066024X0140Y0610R270 S2      
327GND              C577  -2          A01X+037034Y+065812X0180Y0200     S2      
327P3V3_NODE1       C577  -1          A01X+037349Y+065812X0180Y0200     S2      
327GND              C584  -2          A01X+037036Y+065416X0180Y0200     S2      
327P3V3_NODE1       C584  -1          A01X+037351Y+065416X0180Y0200     S2      
327TMP05_FUNC2      R766  -1          A10X+038386Y+065809X0180Y0200R090 S1      
327FAN5_TACH        R768  -2          A01X+037028Y+065016X0180Y0200     S2      
327FAN5_TACH_IN     R768  -1          A01X+037343Y+065016X0180Y0200     S2      
327FAN6_TACH        R770  -2          A01X+037028Y+064616X0180Y0200     S2      
327FAN6_TACH_IN     R770  -1          A01X+037343Y+064616X0180Y0200     S2      
317GND              VIA   -     D0100PA00X+038010Y+066024               S3      
327FNACTRL2_T_ST    VIA   -           A10X+038515Y+065233X0260Y0260     S1      
327TMP05_FUNC2      VIA   -           A10X+038363Y+064625X0260Y0260     S1      
317P3V3_NODE1       VIA   -     D0100PA00X+037909Y+065774               S3      
317P3V3_NODE1       VIA   -     D0100PA00X+037665Y+065416               S3      
317FAN5_TACH_IN     VIA   -     D0100PA00X+037949Y+065024               S1      
317FAN6_TACH_IN     VIA   -     D0100PA00X+037609Y+064616               S1      
327NNAME10755       U70   -1          A01X+038476Y+066274X0140Y0610R270 S2      
327N/C              U69   -8          A01X+038476Y+066794X0140Y0610R270 S2      
327FAN2_TACH_IN     U69   -7          A01X+038476Y+067044X0140Y0610R270 S2      
327FAN1_TACH_IN     U69   -6          A01X+038476Y+067294X0140Y0610R270 S2      
327N/C              U69   -5          A01X+038476Y+067544X0140Y0610R270 S2      
327P3V3_NODE1       R766  -2          A10X+038386Y+066124X0180Y0200R090 S1      
327FAN2_TACH        R757  -2          A01X+037028Y+066616X0180Y0200     S2      
327FAN2_TACH_IN     R757  -1          A01X+037343Y+066616X0180Y0200     S2      
327FAN1_TACH        R756  -2          A01X+037028Y+067016X0180Y0200     S2      
327FAN1_TACH_IN     R756  -1          A01X+037343Y+067016X0180Y0200     S2      
327FAN3_TACH        R758  -2          A01X+037028Y+067421X0180Y0200     S2      
327FAN3_TACH_IN     R758  -1          A01X+037343Y+067421X0180Y0200     S2      
317FAN2_TACH        VIA   -     D0100PA00X+037368Y+066242               S1      
317FAN1_TACH_IN     VIA   -     D0100PA00X+037609Y+067016               S1      
317P3V3_NODE1       VIA   -     D0100PA00X+037721Y+067320               S3      
317FAN3_TACH_IN     VIA   -     D0100PA00X+037946Y+067525               S1      
327N21701263        VIA   -           A10X+038487Y+067543X0260Y0260     S1      
317FAN2_TACH_IN     VIA   -     D0100PA00X+037946Y+066616               S1      
327FAN3_TACH_IN     U69   -4          A01X+038476Y+067794X0140Y0610R270 S2      
327P3V3_NODE1       U69   -3          A01X+038476Y+068044X0140Y0610R270 S2      
327GND              U69   -2          A01X+038476Y+068294X0140Y0610R270 S2      
327NNAME10756       U69   -1          A01X+038476Y+068544X0140Y0610R270 S2      
327N/C              U65   -5          A10X+038394Y+069132X0140Y0590R270 S1      
327N/C              U65   -4          A10X+038394Y+068876X0140Y0590R270 S1      
327N21701261        U65   -3          A10X+038394Y+068620X0140Y0590R270 S1      
327N21699606        U65   -2          A10X+038394Y+068364X0140Y0590R270 S1      
327N21701263        U65   -1          A10X+038394Y+068108X0140Y0590R270 S1      
327GND              U67   -4          A01X+038512Y+069116X0220Y0680R270 S2      
327GND              C575  -2          A01X+037028Y+067822X0180Y0200     S2      
327P3V3_NODE1       C575  -1          A01X+037343Y+067822X0180Y0200     S2      
327GND              R754  -2          A01X+037028Y+068625X0180Y0200     S2      
327N21698906        R754  -1          A01X+037343Y+068625X0180Y0200     S2      
327P3V3_NODE1       R739  -2          A01X+037028Y+069025X0180Y0200     S2      
327N21698906        R739  -1          A01X+037343Y+069025X0180Y0200     S2      
327N21701261        R708  -2          A10X+037343Y+068566X0180Y0200     S1      
327P3V3_NODE1       R708  -1          A10X+037028Y+068566X0180Y0200     S1      
327GND              R719  -2          A10X+037028Y+068166X0180Y0200R180 S1      
327N21699606        R719  -1          A10X+037343Y+068166X0180Y0200R180 S1      
327I2C_COM3_SCL     R764  -2          A01X+037028Y+068225X0180Y0200     S2      
327NNAME10756       R764  -1          A01X+037343Y+068225X0180Y0200     S2      
327N21701263        R701  -2          A10X+037343Y+067766X0180Y0200     S1      
327P3V3_NODE1       R701  -1          A10X+037028Y+067766X0180Y0200     S1      
327NNAME10756       VIA   -           A01X+037809Y+068392X0300Y0300     S2      
317P3V3_NODE1       VIA   -     D0100PA00X+037979Y+067945               S3      
327N21701261        VIA   -           A10X+037767Y+068636X0260Y0260     S1      
327N21699606        VIA   -           A10X+037768Y+068136X0260Y0260     S1      
317TACKOVER_EN_N    VIA   -     D0100PA00X+037695Y+068999               S3      
327NNAME10757       U65   -11         A10X+038394Y+070667X0140Y0590R270 S1      
327NNAME10758       U65   -10         A10X+038394Y+070411X0140Y0590R270 S1      
327N/C              U65   -9          A10X+038394Y+070155X0140Y0590R270 S1      
327N/C              U65   -8          A10X+038394Y+069900X0140Y0590R270 S1      
327N/C              U65   -7          A10X+038394Y+069644X0140Y0590R270 S1      
327N/C              U65   -6          A10X+038394Y+069388X0140Y0590R270 S1      
327N21698906        U67   -3          A01X+038512Y+069616X0220Y0680R270 S2      
327N21698939        U67   -2          A01X+038512Y+070116X0220Y0680R270 S2      
327N21700941        U67   -1          A01X+038512Y+070616X0220Y0680R270 S2      
327GND              R752  -2          A01X+037028Y+070225X0180Y0200     S2      
327N21700941        R752  -1          A01X+037343Y+070225X0180Y0200     S2      
327P3V3_NODE1       R737  -2          A01X+037028Y+070625X0180Y0200     S2      
327N21700941        R737  -1          A01X+037343Y+070625X0180Y0200     S2      
327GND              R753  -2          A01X+037028Y+069825X0180Y0200     S2      
327N21698939        R753  -1          A01X+037343Y+069825X0180Y0200     S2      
327P3V3_NODE1       R738  -2          A01X+037028Y+069425X0180Y0200     S2      
327N21698939        R738  -1          A01X+037343Y+069425X0180Y0200     S2      
317N21698906        VIA   -     D0100PA00X+037768Y+069424               S1      
317N21698939        VIA   -     D0100PA00X+037768Y+070117               S1      
317N21700941        VIA   -     D0100PA00X+037767Y+070624               S1      
317CPLD_WDT2        VIA   -     D0100PA00X+037710Y+069722               S3      
327NNAME10758       VIA   -           A10X+037236Y+070477X0260Y0260     S1      
327GND              U65   -12         A10X+038394Y+070923X0140Y0590R270 S1      
327P3V3_NODE1       R145  -2          A10X+037349Y+071503X0180Y0200R180 S1      
327NNAME10757       R145  -1          A10X+037664Y+071503X0180Y0200R180 S1      
327P3V3_NODE1       R146  -2          A01X+038450Y+071544X0180Y0200     S2      
327T5_NODE3_EN_R    R902  -2          A01X+037258Y+072362X0180Y0200R180 S2      
327CPLD_WDT2        R755  -1          A10X+038433Y+071525X0180Y0200     S1      
317P3V3_NODE1       VIA   -     D0100PA00X+037117Y+071157               S3      
317P3V3_NODE1       VIA   -     D0100PA00X+038296Y+071143               S3      
317T5_NODE3_EN      VIA   -     D0100PA00X+037211Y+072031               S3      
317P3V3_STB_NODE1   VIA   -     D0100PA00X+037619Y+071126               S3      
327NNAME10719       C678  -1          A01X+037249Y+073146X0180Y0200     S2      
327NNAME10716       C690  -1          A01X+037249Y+072746X0180Y0200     S2      
327T5_NODE3_EN_R    C665  -1          A10X+037258Y+072762X0180Y0200R180 S1      
327NNAME10719       R915  -1          A10X+037249Y+073546X0180Y0200R180 S1      
327NNAME10716       R927  -1          A10X+037249Y+073146X0180Y0200R180 S1      
327T5_NODE4_EN      R905  -1          A01X+037249Y+073546X0180Y0200     S2      
317GND              VIA   -     D0100PA00X+037558Y+073946               S3      
317NNAME10719       VIA   -     D0100PA00X+037555Y+073146               S3      
317NNAME10716       VIA   -     D0100PA00X+037583Y+072746               S3      
317T5_NODE3_EN_R    VIA   -     D0100PA00X+037784Y+072439               S3      
317T5_NODE4_EN      VIA   -     D0100PA00X+037677Y+073490               S1      
327GND              C705  -2          A01X+037249Y+073946X0180Y0200R180 S2      
327NNAME10723       C702  -1          A10X+037249Y+074346X0180Y0200R180 S1      
327GND              C668  -2          A10X+037249Y+073946X0180Y0200     S1      
327NNAME10723       R939  -1          A01X+037249Y+074346X0180Y0200     S2      
317GND              VIA   -     D0100PA00X+037043Y+074914               S3      
317NNAME10723       VIA   -     D0100PA00X+037350Y+074846               S1      
327T5_NODE4_EN_R    VIA   -           A10X+037013Y+077011X0260Y0260     S1      
327T5_NODE3_EN_R    VIA   -           A10X+037337Y+078393X0260Y0260     S1      
327T5_NODE3_EN_R    J35   -A2         A10X+037408Y+080787X0300Y1660R180 S1      
327GND              J35   -A1         A10X+037801Y+080590X0300Y1260R180 S1      
327NNAME10748       J35   -B2         A01X+037408Y+080787X0300Y1660R180 S2      
327GND              J35   -B1         A01X+037801Y+080787X0300Y1660R180 S2      
317GND              VIA   -     D0100PA00X+037696Y+078858               S3      
317GND              VIA   -     D0100PA00X+037696Y+079158               S3      
327GND              C334  -2          A01X+038572Y+001752X0180Y0200     S2      
327P3V3_NODE1       C334  -1          A01X+038887Y+001752X0180Y0200     S2      
327P3V3_NODE1       C134  -2          A01X+039279Y+001752X0180Y0200     S2      
327GND              C134  -1          A01X+039594Y+001752X0180Y0200     S2      
327P3V3_NODE1       J1    -4          A01X+038978Y+003019X0400Y1090R180 S2      
327NNAME10759       J1    -2          A01X+039766Y+003019X0400Y1090R180 S2      
317GND              VIA   -     D0100PA00X+039900Y+001752               S3      
317P3V3_NODE1       VIA   -     D0100PA00X+039260Y+002055               S3      
317P3V3_NODE1       VIA   -     D0100PA00X+038924Y+002055               S3      
317NNAME10759       VIA   -     D0100PA00X+039766Y+002134               S1      
317N/C              J1    -H1   D0420UA00X+039372Y+003855               S0      
327NNAME10711       J1    -3          A01X+038978Y+004692X0400Y1090R180 S2      
327N20512395        J1    -1          A01X+039766Y+004692X0400Y1090R180 S2      
327NNAME10751       R190  -2          A01X+038700Y+006119X0180Y0200R090 S2      
327N20512395        R193  -2          A01X+039508Y+006136X0180Y0200R090 S2      
317NNAME10711       VIA   -     D0100PA00X+039225Y+005990               S3      
317NNAME10423       VIA   -     D0100PA00X+038969Y+006067               S3      
317NNAME10560       VIA   -     D0100PA00X+040131Y+006144               S3      
317N20512395        VIA   -     D0100PA00X+039779Y+006136               S1      
327P3V3_NODE1       C140  -1          A01X+040059Y+006961X0180Y0200R180 S2      
327PD_NODE1_DM7     R205  -2          A01X+039022Y+006964X0180Y0200     S2      
327GND              R205  -1          A01X+039337Y+006964X0180Y0200     S2      
327NNAME10423       R190  -1          A01X+038700Y+006434X0180Y0200R090 S2      
327NNAME10560       R193  -1          A01X+039508Y+006451X0180Y0200R090 S2      
317GND              VIA   -     D0100PA00X+039337Y+007292               S3      
317P3V3_NODE1       VIA   -     D0100PA00X+039779Y+006961               S3      
317PD_NODE1_DM7     VIA   -     D0100PA00X+039036Y+007578               S1      
317NNAME10015       VIA   -     D0100PA00X+040122Y+006516               S3      
327GND              J2    -197        A01X+039980Y+008248X0150Y0810     S2      
327GND              J2    -195        A01X+039744Y+008248X0150Y0810     S2      
327NNAME10611       J2    -193        A01X+039508Y+008248X0150Y0810     S2      
327NNAME10667       J2    -191        A01X+039272Y+008248X0150Y0810     S2      
327PD_NODE1_DM7     J2    -189        A01X+039036Y+008248X0150Y0810     S2      
327GND              J2    -187        A01X+038799Y+008248X0150Y0810     S2      
327NNAME10601       J2    -185        A01X+038563Y+008248X0150Y0810     S2      
317GND              VIA   -     D0100PA00X+039980Y+008878               S3      
317GND              VIA   -     D0100PA00X+039744Y+009067               S3      
317GND              VIA   -     D0100PA00X+038940Y+008923               S3      
317NNAME10667       VIA   -     D0100PA00X+039249Y+009265               S1      
317GND              VIA   -     D0100PA00X+039965Y+010836               S3      
317GND              VIA   -     D0100PA00X+039154Y+010899               S3      
317GND              VIA   -     D0100PA00X+039882Y+009582               S3      
317GND              VIA   -     D0100PA00X+039119Y+010417               S3      
317GND              VIA   -     D0100PA00X+038886Y+009801               S3      
317NNAME10609       VIA   -     D0100PA00X+040016Y+009918               S1      
317NNAME10611       VIA   -     D0100PA00X+039131Y+009957               S1      
317NNAME10614       VIA   -     D0100PA00X+039961Y+010466               S3      
317NNAME10601       VIA   -     D0100PA00X+039123Y+009609               S3      
327NNAME10760       J2    -198        A01X+040099Y+011476X0150Y0810     S2      
327GND              J2    -196        A01X+039862Y+011476X0150Y0810     S2      
327NNAME10614       J2    -194        A01X+039626Y+011476X0150Y0810     S2      
327NNAME10609       J2    -192        A01X+039390Y+011476X0150Y0810     S2      
327GND              J2    -190        A01X+039154Y+011476X0150Y0810     S2      
327NNAME10612       J2    -188        A01X+038917Y+011476X0150Y0810     S2      
327NNAME10613       J2    -186        A01X+038681Y+011476X0150Y0810     S2      
317GND              VIA   -     D0100PA00X+039915Y+013177               S3      
317GND              VIA   -     D0100PA00X+039188Y+013169               S3      
317NNAME10612       VIA   -     D0100PA00X+039809Y+012846               S1      
317NNAME10613       VIA   -     D0100PA00X+039309Y+012846               S1      
317GND              VIA   -     D0100PA00X+039986Y+024971               S3      
317GND              VIA   -     D0100PA00X+039930Y+025723               S3      
317GND              VIA   -     D0100PA00X+039200Y+025825               S3      
317NNAME10520       VIA   -     D0100PA00X+039960Y+026025               S1      
317NNAME10597       VIA   -     D0100PA00X+039826Y+025234               S1      
317NNAME10519       VIA   -     D0100PA00X+039438Y+026050               S1      
317GND              VIA   -     D0100PA00X+039267Y+027251               S3      
317NNAME10526       VIA   -     D0100PA00X+039961Y+027521               S3      
317NNAME10528       VIA   -     D0100PA00X+039346Y+028293               S1      
317NNAME10525       VIA   -     D0100PA00X+039251Y+027558               S1      
317GND              VIA   -     D0100PA00X+040093Y+029315               S3      
317GND              VIA   -     D0100PA00X+039610Y+028393               S3      
317NNAME10619       VIA   -     D0100PA00X+039804Y+029257               S1      
317NNAME10536       VIA   -     D0100PA00X+039988Y+031957               S3      
317NNAME10052       VIA   -     D0100PA00X+039008Y+033158               S1      
317GND              H5    -4    D0220PA00X+039961Y+037717               S0      
317LAN2_DISABLE_N   VIA   -     D0100PA00X+038974Y+040473               S3      
317PCIE_SW_P0_ERR   VIA   -     D0100PA00X+039574Y+040753               S1      
317NNAME10562       VIA   -     D0100PA00X+039337Y+041162               S3      
317GND              VIA   -     D0100PA00X+039906Y+045432               S3      
317GND              VIA   -     D0100PA00X+039905Y+045097               S3      
317GND              VIA   -     D0100PA00X+039880Y+046225               S3      
317GND              VIA   -     D0100PA00X+039880Y+045806               S3      
317P3V3_NODE1       VIA   -     D0100PA00X+039208Y+047097               S1      
317P1V8_NODE1       VIA   -     D0100PA00X+038708Y+048640               S3      
317P1V8_NODE1       VIA   -     D0100PA00X+038594Y+048248               S3      
317P1V8_NODE1       VIA   -     D0100PA00X+038889Y+048044               S3      
317P1V8_NODE1       VIA   -     D0100PA00X+038641Y+047758               S3      
317P1V8_NODE1       VIA   -     D0100PA00X+038967Y+047726               S3      
317GND              VIA   -     D0100PA00X+038911Y+049210               S3      
317NNAME10741       VIA   -     D0100PA00X+038898Y+049694               S1      
327P1V05_NODE1      PR45  -1          A01X+039566Y+051630X0180Y0200R270 S2      
327P1V05_NODE1      PR50  -1          A01X+039984Y+051630X0180Y0200R270 S2      
317P1V05_NODE1      VIA   -     D0100PA00X+039569Y+051277               S3      
327GND              C814  -2          A01X+038722Y+053126X0180Y0200R090 S2      
327NNAME10474       C814  -1          A01X+038722Y+053441X0180Y0200R090 S2      
327P1V05_NODE1      R137  -2          A01X+040015Y+053202X0180Y0200     S2      
327NNAME10668       PR46  -1          A01X+040006Y+052802X0180Y0200R180 S2      
327NNAME10622       PR44  -1          A01X+040003Y+052409X0180Y0200R180 S2      
327NNAME10668       PR45  -2          A01X+039566Y+051945X0180Y0200R270 S2      
327NNAME10622       PR50  -2          A01X+039984Y+051945X0180Y0200R270 S2      
317P1V05_NODE1      VIA   -     D0100PA00X+039635Y+053202               S3      
317NNAME10622       VIA   -     D0100PA00X+039656Y+052225               S1      
317NNAME10668       VIA   -     D0100PA00X+039647Y+052785               S1      
327GND              C812  -2          A01X+038736Y+054868X0440Y0540R270 S2      
327NNAME10474       C812  -1          A01X+038736Y+054120X0440Y0540R270 S2      
327P3V3_NODE1       PR52  -2          A01X+040004Y+053613X0180Y0200     S2      
327P3V3_NODE1       PR54  -2          A01X+040024Y+054013X0180Y0200     S2      
317P3V3_NODE1       VIA   -     D0100PA00X+039605Y+054013               S3      
317P3V3_NODE1       VIA   -     D0100PA00X+039592Y+053613               S3      
317NNAME10761       VIA   -     D0100PA00X+039659Y+054931               S1      
317NNAME10762       VIA   -     D0100PA00X+039959Y+055350               S1      
317P12V_AUX         VIA   -     D0100PA00X+039000Y+056735               S3      
317NNAME10763       VIA   -     D0100PA00X+039652Y+056744               S3      
317NNAME10764       VIA   -     D0100PA00X+039360Y+056763               S1      
327GND              PC34  -2          A10X+038768Y+059182X0460Y0620R180 S1      
327P12V_AUX         PC34  -1          A10X+039928Y+059182X0460Y0620R180 S1      
327GND              PC32  -2          A01X+038766Y+059184X0460Y0620     S2      
327P12V_AUX         PC32  -1          A01X+039926Y+059184X0460Y0620     S2      
317GND              VIA   -     D0100PA00X+039163Y+059790               S3      
317P12V_AUX         VIA   -     D0100PA00X+040109Y+058705               S3      
317P12V_AUX         VIA   -     D0100PA00X+039839Y+058713               S3      
317P12V_AUX         VIA   -     D0100PA00X+040142Y+059727               S3      
327GND              PU4   -TH         A01X+040292Y+060935X0670Y0670R270 S2      
327P12V_AUX         PU4   -13         A01X+039997Y+060354X0100Y0330R180 S2      
327NNAME10765       PU4   -12         A01X+039711Y+060640X0100Y0330R270 S2      
327NNAME10754       PU4   -11         A01X+039711Y+060837X0100Y0330R270 S2      
327NNAME10754       PU4   -10         A01X+039711Y+061033X0100Y0330R270 S2      
327NNAME10754       PU4   -9          A01X+039711Y+061230X0100Y0330R270 S2      
327NNAME10754       PC36  -2          A01X+039156Y+060913X0180Y0200R270 S2      
327NNAME10765       PC36  -1          A01X+039156Y+060598X0180Y0200R270 S2      
327GND              PC33  -2          A01X+039429Y+059794X0180Y0200     S2      
327P12V_AUX         PC33  -1          A01X+039744Y+059794X0180Y0200     S2      
317GND              VIA   -     D0100PA00X+040059Y+061167               S3      
317GND              VIA   -     D0100PA00X+040059Y+060702               S3      
327P12V_AUX         VIA   -           A10X+040119Y+060364X0260Y0260R090 S1      
317P12V_AUX         VIA   -     D0100PA00X+040142Y+059977               S3      
317P12V_AUX         VIA   -     D0100PA00X+039882Y+060040               S3      
317NNAME10754       VIA   -     D0100PA00X+039145Y+061197               S1      
317NNAME10765       VIA   -     D0100PA00X+039439Y+060405               S1      
327GND              PU4   -8          A01X+039997Y+061516X0100Y0330R180 S2      
327GND              PC30  -2          A01X+039460Y+062411X0180Y0200     S2      
327NNAME10766       PC30  -1          A01X+039775Y+062411X0180Y0200     S2      
327NNAME10766       R1232 -2          A01X+039774Y+062823X0180Y0200R180 S2      
327GND              R1232 -1          A01X+039459Y+062823X0180Y0200R180 S2      
317GND              VIA   -     D0100PA00X+039820Y+062082               S3      
317GND              VIA   -     D0100PA00X+040070Y+061832               S3      
317GND              VIA   -     D0100PA00X+039820Y+061832               S3      
317GND              VIA   -     D0100PA00X+040070Y+062082               S3      
317GND              VIA   -     D0100PA00X+039206Y+062411               S3      
317NNAME10766       VIA   -     D0100PA00X+040135Y+062401               S3      
327P12V_AUX         R655  -2          A01X+038646Y+064027X0180Y0200R270 S2      
327N52411040        R655  -1          A01X+038646Y+063712X0180Y0200R270 S2      
327N52411040        R1127 -2          A01X+039048Y+063712X0180Y0200R090 S2      
327N52411069        R1127 -1          A01X+039048Y+064027X0180Y0200R090 S2      
327N52411102        Q44   -2          A01X+039523Y+063314X0240Y0280R270 S2      
327N52411069        Q44   -1          A01X+039523Y+064062X0240Y0280R270 S2      
317NNAME10767       VIA   -     D0100PA00X+039922Y+064493               S1      
317P12V_AUX         VIA   -     D0100PA00X+039570Y+063743               S3      
317P12V_AUX         VIA   -     D0100PA00X+039944Y+063734               S3      
317N52411069        VIA   -     D0100PA00X+039438Y+064339               S1      
327P3V3_NODE1       U71   -5          A10X+040133Y+065060X0220Y0530R270 S1      
327GND              U71   -4          A10X+040133Y+065808X0220Y0530R270 S1      
327TMP05_FUNC2      U71   -3          A10X+039168Y+065808X0220Y0530R270 S1      
327FNACTRL2_T_ST    U71   -2          A10X+039168Y+065434X0220Y0530R270 S1      
327NNAME10767       U71   -1          A10X+039168Y+065060X0220Y0530R270 S1      
317GND              VIA   -     D0100PA00X+039694Y+065808               S3      
317FNACTRL2_T_ST    VIA   -     D0100PA00X+039637Y+065323               S3      
317CPLD_WDT2        VIA   -     D0100PA00X+039936Y+065359               S3      
317PU_FAN_TACH      VIA   -     D0100PA00X+038986Y+064571               S1      
327FAN_PWM          U133  -4          A10X+039641Y+066458X0130Y0460R090 S1      
327P3V3_NODE1       U133  -5          A10X+039641Y+066970X0130Y0460R090 S1      
327GND              C766  -2          A10X+039000Y+066528X0180Y0200R270 S1      
327P3V3_NODE1       C766  -1          A10X+039000Y+066843X0180Y0200R270 S1      
327FAN_PWM          R778  -2          A10X+039802Y+067621X0180Y0200     S1      
327P3V3_NODE1       R778  -1          A10X+039487Y+067621X0180Y0200     S1      
317GND              VIA   -     D0100PA00X+039648Y+066153               S3      
317GND              VIA   -     D0100PA00X+039991Y+066133               S3      
317P3V3_NODE1       VIA   -     D0100PA00X+038617Y+066507               S3      
317P3V3_NODE1       VIA   -     D0100PA00X+039194Y+067232               S3      
317P3V3_NODE1       VIA   -     D0100PA00X+039210Y+067623               S3      
317FAN_PWM_BUF      VIA   -     D0100PA00X+039987Y+066641               S3      
317GND              VIA   -     D0100PA00X+040027Y+068403               S3      
317GND              VIA   -     D0100PA00X+039000Y+068972               S3      
317GND              VIA   -     D0100PA00X+038996Y+068222               S3      
317FAN_PWM          VIA   -     D0100PA00X+039655Y+068027               S3      
317I2C_COM3_SCL     VIA   -     D0100PA00X+039983Y+069019               S3      
317I2C_COM3_SDA     VIA   -     D0100PA00X+040097Y+068670               S3      
317P3V3_NODE1       VIA   -     D0100PA00X+040041Y+068119               S3      
317P3V3_STB_NODE1   VIA   -     D0100PA00X+039066Y+068692               S3      
317NNAME10743       VIA   -     D0100PA00X+039191Y+069674               S3      
317NNAME10757       VIA   -     D0100PA00X+039208Y+069280               S3      
317NNAME10757       VIA   -     D0100PA00X+039174Y+070596               S3      
317NNAME10768       VIA   -     D0100PA00X+039862Y+070141               S3      
317NNAME10758       VIA   -     D0100PA00X+039095Y+070192               S3      
327NNAME10041       U131  -6          A01X+039934Y+071640X0160Y0200R270 S2      
327P3V3_NODE1       U131  -5          A01X+039934Y+071384X0160Y0200R270 S2      
327NNAME10769       U131  -4          A01X+039934Y+071128X0160Y0200R270 S2      
327NNAME10757       U131  -3          A01X+039186Y+071128X0160Y0200R270 S2      
327GND              U131  -2          A01X+039186Y+071384X0160Y0200R270 S2      
327NNAME10758       U131  -1          A01X+039186Y+071640X0160Y0200R270 S2      
327NNAME10758       R146  -1          A01X+038765Y+071544X0180Y0200     S2      
327NNAME10768       R1060 -1          A10X+039944Y+071625X0180Y0200     S1      
327PCA_CPLD_WDT2    R755  -2          A10X+038748Y+071525X0180Y0200     S1      
317GND              VIA   -     D0100PA00X+038935Y+071129               S3      
317NNAME10769       VIA   -     D0100PA00X+039615Y+070893               S3      
327PCA_CPLD_WDT2    VIA   -           A10X+039179Y+071525X0260Y0260     S1      
317NNAME10768       VIA   -     D0100PA00X+040073Y+072195               S1      
317NNAME10041       VIA   -     D0100PA00X+039484Y+071144               S3      
327GND              C140  -2          A01X+040374Y+006961X0180Y0200R180 S2      
327NNAME10770       C141  -1          A01X+040915Y+007191X0280Y0320R270 S2      
327GND              C141  -2          A01X+041495Y+007191X0280Y0320R270 S2      
317GND              VIA   -     D0100PA00X+041495Y+007529               S3      
317GND              VIA   -     D0100PA00X+040374Y+007278               S3      
317NNAME10014       VIA   -     D0100PA00X+040431Y+006521               S3      
317NNAME10770       VIA   -     D0100PA00X+041071Y+007619               S1      
327NNAME10770       J2    -203        A01X+040689Y+008248X0150Y0810     S2      
327GND              J2    -201        A01X+040453Y+008248X0150Y0810     S2      
327P3V3_NODE1       J2    -199        A01X+040217Y+008248X0150Y0810     S2      
317GND              VIA   -     D0100PA00X+040167Y+009381               S3      
317GND              VIA   -     D0100PA00X+040453Y+008870               S3      
317GND              VIA   -     D0100PA00X+040906Y+009210               S3      
317NNAME10015       VIA   -     D0100PA00X+040481Y+009389               S3      
317N/C              J2    -H2   D0460UA00X+041496Y+009862               S0      
317NNAME10014       VIA   -     D0100PA00X+040730Y+009512               S3      
317NNAME10770       VIA   -     D0100PA00X+040807Y+010915               S3      
327NNAME10770       J2    -204        A01X+040807Y+011476X0150Y0810     S2      
327NNAME10014       J2    -202        A01X+040571Y+011476X0150Y0810     S2      
327NNAME10015       J2    -200        A01X+040335Y+011476X0150Y0810     S2      
327GND              J3    -59         A01X+041233Y+024373X0900Y0110     S2      
327NNAME10620       J3    -57         A01X+041233Y+024569X0900Y0110     S2      
327N/C              J3    -55         A01X+041233Y+024766X0900Y0110     S2      
327NNAME10138       J3    -53         A01X+041233Y+024963X0900Y0110     S2      
327NNAME10771       C184  -2          A10X+041263Y+026468X0180Y0200     S1      
327GND              C184  -1          A10X+040948Y+026468X0180Y0200     S1      
327NNAME10772       R219  -2          A10X+040948Y+026049X0180Y0200R180 S1      
327NNAME10773       R219  -1          A10X+041263Y+026049X0180Y0200R180 S1      
327NNAME10774       R220  -2          A10X+041263Y+025649X0180Y0200     S1      
327P3V3_STB_NODE1   R220  -1          A10X+040948Y+025649X0180Y0200     S1      
327NNAME10775       R222  -2          A10X+040948Y+025249X0180Y0200R180 S1      
327NNAME10774       R222  -1          A10X+041263Y+025249X0180Y0200R180 S1      
327NNAME10257       J3    -51         A01X+041233Y+025160X0900Y0110     S2      
327GND              J3    -49         A01X+041233Y+025357X0900Y0110     S2      
327NNAME10771       J3    -47         A01X+041233Y+025554X0900Y0110     S2      
327N/C              J3    -45         A01X+041233Y+025751X0900Y0110     S2      
327NNAME10776       J3    -43         A01X+041233Y+025947X0900Y0110     S2      
327NNAME10774       J3    -41         A01X+041233Y+026144X0900Y0110     S2      
327NNAME10773       J3    -39         A01X+041233Y+026341X0900Y0110     S2      
327GND              J3    -37         A01X+041233Y+026538X0900Y0110     S2      
317GND              VIA   -     D0100PA00X+040569Y+025358               S3      
327NNAME10773       VIA   -           A10X+041725Y+026630X0260Y0260     S1      
317NNAME10595       VIA   -     D0100PA00X+040474Y+026042               S1      
317NNAME10596       VIA   -     D0100PA00X+040295Y+025325               S3      
317P3V3_STB_NODE1   VIA   -     D0100PA00X+040597Y+025649               S3      
327NNAME10771       R226  -2          A10X+041263Y+027273X0180Y0200     S1      
327P3V3_STB_NODE1   R226  -1          A10X+040948Y+027273X0180Y0200     S1      
327GND              R227  -2          A10X+040948Y+026868X0180Y0200R180 S1      
327NNAME10771       R227  -1          A10X+041263Y+026868X0180Y0200R180 S1      
327NNAME10606       J3    -35         A01X+041233Y+026735X0900Y0110     S2      
327NNAME10531       J3    -33         A01X+041233Y+026932X0900Y0110     S2      
327GND              J3    -31         A01X+041233Y+027128X0900Y0110     S2      
327NNAME10595       J3    -29         A01X+041233Y+027325X0900Y0110     S2      
327NNAME10596       J3    -27         A01X+041233Y+027522X0900Y0110     S2      
327GND              J3    -25         A01X+041233Y+027719X0900Y0110     S2      
327N/C              J3    -23         A01X+041233Y+027916X0900Y0110     S2      
327N/C              J3    -21         A01X+041233Y+028113X0900Y0110     S2      
317GND              VIA   -     D0100PA00X+040504Y+026752               S3      
317GND              VIA   -     D0100PA00X+040173Y+027725               S3      
317NNAME10606       VIA   -     D0100PA00X+040162Y+026735               S3      
317NNAME10531       VIA   -     D0100PA00X+040315Y+027019               S1      
317P3V3_STB_NODE1   VIA   -     D0100PA00X+040525Y+027273               S3      
327GND              J3    -19         A01X+041233Y+028310X0900Y0110     S2      
327NNAME10526       J3    -17         A01X+041233Y+028506X0900Y0110     S2      
327NNAME10520       J3    -15         A01X+041233Y+028703X0900Y0110     S2      
327GND              J3    -13         A01X+041233Y+028900X0900Y0110     S2      
327NNAME10597       J3    -11         A01X+041233Y+029097X0900Y0110     S2      
327NNAME10525       J3    -9          A01X+041233Y+029294X0900Y0110     S2      
327GND              J3    -7          A01X+041233Y+029491X0900Y0110     S2      
327NNAME10534       J3    -5          A01X+041233Y+029688X0900Y0110     S2      
317GND              VIA   -     D0100PA00X+040588Y+029407               S3      
317NNAME10534       VIA   -     D0100PA00X+040363Y+029220               S1      
327NNAME10619       J3    -3          A01X+041233Y+029884X0900Y0110     S2      
327GND              J3    -1          A01X+041233Y+030081X0900Y0110     S2      
317NNAME10138       VIA   -     D0100PA00X+040879Y+031705               S3      
317NNAME10257       VIA   -     D0100PA00X+041124Y+031648               S3      
317GND              H5    -6    D0220PA00X+041339Y+036339               S0      
317GND              H5    -5    D0220PA00X+040354Y+036732               S0      
317N/C              H5    -1    D1580UA00X+041339Y+037717               S0      
317GND              H5    -3    D0220PA00X+040354Y+038701               S0      
317GND              H5    -2    D0220PA00X+041339Y+039095               S0      
327PV_VCCP_NODE1    PC123 -2          A01X+041788Y+041283X0440Y0540R180 S2      
327GND              PC123 -1          A01X+041040Y+041283X0440Y0540R180 S2      
327PV_VCCP_NODE1    PC119 -2          A01X+041788Y+042083X0440Y0540R180 S2      
327GND              PC119 -1          A01X+041040Y+042083X0440Y0540R180 S2      
327PV_VCCP_NODE1    PC116 -2          A10X+041788Y+041283X0440Y0540     S1      
327GND              PC116 -1          A10X+041040Y+041283X0440Y0540     S1      
327PV_VCCP_NODE1    PC114 -2          A10X+041788Y+042083X0440Y0540     S1      
327GND              PC114 -1          A10X+041040Y+042083X0440Y0540     S1      
317GND              VIA   -     D0100PA00X+040313Y+041809               S3      
317GND              VIA   -     D0100PA00X+040620Y+041776               S3      
317GND              VIA   -     D0100PA00X+040598Y+041463               S3      
317GND              VIA   -     D0100PA00X+040593Y+041139               S3      
327PV_VCCP_NODE1    PC107 -2          A01X+041788Y+043683X0440Y0540R180 S2      
327GND              PC107 -1          A01X+041040Y+043683X0440Y0540R180 S2      
327PV_VCCP_NODE1    PC106 -2          A01X+041788Y+042883X0440Y0540R180 S2      
327GND              PC106 -1          A01X+041040Y+042883X0440Y0540R180 S2      
327PV_VCCP_NODE1    PC105 -2          A10X+041788Y+042883X0440Y0540     S1      
327GND              PC105 -1          A10X+041040Y+042883X0440Y0540     S1      
327PV_VCCP_NODE1    PC125 -2          A10X+041788Y+043683X0440Y0540     S1      
327GND              PC125 -1          A10X+041040Y+043683X0440Y0540     S1      
317GND              VIA   -     D0100PA00X+040614Y+042477               S3      
317GND              VIA   -     D0100PA00X+040615Y+043320               S3      
327PV_VCCP_NODE1    PC113 -2          A10X+041055Y+045283X0440Y0540     S1      
327GND              PC113 -1          A10X+040307Y+045283X0440Y0540     S1      
327PV_VCCP_NODE1    PC120 -2          A01X+041788Y+044483X0440Y0540R180 S2      
327GND              PC120 -1          A01X+041040Y+044483X0440Y0540R180 S2      
327PV_VCCP_NODE1    PC112 -2          A10X+041788Y+044483X0440Y0540     S1      
327GND              PC112 -1          A10X+041040Y+044483X0440Y0540     S1      
327PV_VCCP_NODE1    PC117 -2          A01X+041055Y+045283X0440Y0540R180 S2      
327GND              PC117 -1          A01X+040307Y+045283X0440Y0540R180 S2      
317GND              VIA   -     D0100PA00X+040653Y+044067               S3      
317GND              VIA   -     D0100PA00X+040600Y+044476               S3      
317GND              VIA   -     D0100PA00X+040290Y+044484               S3      
317PV_VCCP_NODE1    VIA   -     D0100PA00X+041487Y+045517               S3      
317PV_VCCP_NODE1    VIA   -     D0100PA00X+041487Y+045098               S3      
327PV_VCCP_NODE1    PC126 -2          A01X+041055Y+046057X0440Y0540R180 S2      
327GND              PC126 -1          A01X+040307Y+046057X0440Y0540R180 S2      
327PV_VCCP_NODE1    PC124 -2          A10X+041055Y+046057X0440Y0540     S1      
327GND              PC124 -1          A10X+040307Y+046057X0440Y0540     S1      
327NNAME10777       PR56  -2          A01X+041270Y+046693X0240Y0240R180 S2      
327NNAME10778       PR56  -1          A01X+040837Y+046693X0240Y0240R180 S2      
317NNAME10778       VIA   -     D0100PA00X+040635Y+047141               S1      
327NNAME10779       U124  -8          A01X+041766Y+048537X0300Y0410R090 S2      
327NNAME10762       PR75  -2          A01X+041245Y+047190X0240Y0240R090 S2      
327NNAME10761       PR75  -1          A01X+041245Y+047623X0240Y0240R090 S2      
317GND              VIA   -     D0100PA00X+040905Y+048308               S3      
317GND              VIA   -     D0100PA00X+041226Y+048288               S3      
317NNAME10779       VIA   -     D0100PA00X+041061Y+048562               S1      
317NNAME10779       VIA   -     D0100PA00X+041361Y+048562               S3      
327GND              U124  -7          A01X+041766Y+049037X0300Y0410R090 S2      
327GND              U124  -6          A01X+041766Y+049537X0300Y0410R090 S2      
327GND              U124  -5          A01X+041766Y+050037X0300Y0410R090 S2      
317GND              VIA   -     D0100PA00X+041373Y+049078               S3      
317GND              VIA   -     D0100PA00X+041073Y+049078               S3      
317GND              VIA   -     D0100PA00X+040773Y+049078               S3      
317GND              VIA   -     D0100PA00X+040773Y+049378               S3      
317GND              VIA   -     D0100PA00X+040773Y+049678               S3      
317GND              VIA   -     D0100PA00X+040773Y+049978               S3      
317GND              VIA   -     D0100PA00X+041073Y+049378               S3      
317GND              VIA   -     D0100PA00X+041373Y+049378               S3      
317GND              VIA   -     D0100PA00X+041073Y+049678               S3      
317GND              VIA   -     D0100PA00X+041373Y+049678               S3      
317GND              VIA   -     D0100PA00X+041073Y+049978               S3      
317GND              VIA   -     D0100PA00X+041373Y+049978               S3      
327NNAME10780       PR79  -2          A01X+041161Y+051402X0180Y0200R270 S2      
327P3V3_NODE1       PR79  -1          A01X+041161Y+051087X0180Y0200R270 S2      
327NNAME10781       PR48  -1          A01X+041629Y+051268X0280Y0320R180 S2      
327P5V_STB_NODE1    PR48  -2          A01X+041629Y+050688X0280Y0320R180 S2      
327NNAME10780       PJ16  -2          A01X+040615Y+051396X0180Y0200R270 S2      
327NNAME10782       PJ16  -1          A01X+040615Y+051081X0200Y0400R180 S2      
317P3V3_NODE1       VIA   -     D0100PA00X+040999Y+050843               S3      
317P5V_STB_NODE1    VIA   -     D0100PA00X+041314Y+050481               S1      
317P5V_STB_NODE1    VIA   -     D0100PA00X+041322Y+050805               S3      
317NNAME10780       VIA   -     D0100PA00X+041144Y+051696               S3      
317NNAME10780       VIA   -     D0100PA00X+040787Y+051663               S1      
317NNAME10782       VIA   -     D0100PA00X+040535Y+050632               S3      
317NNAME10761       VIA   -     D0100PA00X+040246Y+050590               S3      
317NNAME10762       VIA   -     D0100PA00X+040156Y+050894               S3      
327GND              PU8   -31         A01X+041603Y+052108X0070Y0360R180 S2      
327P5V_STB_NODE1    PU8   -30         A01X+041311Y+052401X0070Y0360R090 S2      
327P5V_STB_NODE1    PU8   -29         A01X+041318Y+052558X0070Y0380R090 S2      
327N/C              PU8   -28         A01X+041318Y+052716X0070Y0380R090 S2      
327N/C              PU8   -27         A01X+041318Y+052873X0070Y0380R090 S2      
327GND              PU8   -26         A01X+041318Y+053031X0070Y0380R090 S2      
327NNAME10783       PU8   -25         A01X+041318Y+053188X0070Y0380R090 S2      
327NNAME10784       PU8   -24         A01X+041318Y+053346X0070Y0380R090 S2      
327NNAME10668       R137  -1          A01X+040330Y+053202X0180Y0200     S2      
327NNAME10784       PR46  -2          A01X+040321Y+052802X0180Y0200R180 S2      
327NNAME10783       PR44  -2          A01X+040318Y+052409X0180Y0200R180 S2      
317P5V_STB_NODE1    VIA   -     D0100PA00X+040925Y+052176               S3      
317P5V_STB_NODE1    VIA   -     D0100PA00X+041209Y+052172               S1      
317NNAME10783       VIA   -     D0100PA00X+040778Y+052743               S1      
317NNAME10784       VIA   -     D0100PA00X+040595Y+053250               S1      
327NNAME10763       PU8   -20         A01X+041603Y+054111X0070Y0360R180 S2      
327NNAME10688       PU8   -23         A01X+041318Y+053503X0070Y0380R090 S2      
327GND              PU8   -22         A01X+041318Y+053661X0070Y0380R090 S2      
327NNAME10764       PU8   -21         A01X+041311Y+053818X0070Y0360R090 S2      
327NNAME10785       PC115 -2          A01X+041183Y+054843X0180Y0200R270 S2      
327NNAME10786       PC115 -1          A01X+041183Y+054528X0180Y0200R270 S2      
327NNAME10786       PR78  -2          A01X+040783Y+054528X0180Y0200R090 S2      
327NNAME10785       PR78  -1          A01X+040783Y+054843X0180Y0200R090 S2      
327NNAME10761       PR76  -1          A01X+041601Y+055034X0180Y0200R180 S2      
327NNAME10764       PR52  -1          A01X+040319Y+053613X0180Y0200     S2      
327NNAME10763       PR54  -1          A01X+040339Y+054013X0180Y0200     S2      
317NNAME10786       VIA   -     D0100PA00X+040434Y+054528               S1      
327P5V_STB_NODE1    VIA   -           A10X+041106Y+054535X0260Y0260     S1      
317NNAME10688       VIA   -     D0100PA00X+040849Y+053733               S1      
317NNAME10761       VIA   -     D0100PA00X+041652Y+054760               S3      
327P1V05_NODE1      PC97  -2          A01X+040583Y+055440X0180Y0200     S2      
327NNAME10785       PC97  -1          A01X+040898Y+055440X0180Y0200     S2      
327NNAME10785       PR74  -2          A01X+041604Y+055902X0180Y0200     S2      
327NNAME10785       PR77  -1          A01X+041602Y+055439X0180Y0200R180 S2      
327GND              PJ17  -1          A01X+040312Y+055863X0280Y0740R090 S2      
327NNAME10785       PJ17  -2          A01X+040902Y+055863X0280Y0320R270 S2      
317GND              VIA   -     D0100PA00X+040250Y+055414               S3      
317P1V05_NODE1      VIA   -     D0100PA00X+040458Y+055184               S3      
317NNAME10785       VIA   -     D0100PA00X+040874Y+055153               S1      
317NNAME10785       VIA   -     D0100PA00X+041334Y+055622               S1      
327GND              PC35  -2          A01X+041035Y+059729X0180Y0200R180 S2      
327P5V_STB_NODE1    PC35  -1          A01X+040720Y+059729X0180Y0200R180 S2      
327P1V8_STB_NODE1   PR15  -2          A01X+041554Y+059730X0180Y0200     S2      
317GND              VIA   -     D0100PA00X+041052Y+059395               S3      
317GND              VIA   -     D0100PA00X+041302Y+059395               S3      
317P5V_STB_NODE1    VIA   -     D0100PA00X+040688Y+059418               S3      
317P5V_STB_NODE1    VIA   -     D0100PA00X+040688Y+059132               S3      
327P1V8_STB_NODE1   PU4   -16         A01X+040587Y+060354X0100Y0330R180 S2      
327P5V_STB_NODE1    PU4   -15         A01X+040390Y+060354X0100Y0330R180 S2      
327P12V_AUX         PU4   -14         A01X+040194Y+060354X0100Y0330R180 S2      
327GND              PU4   -4          A01X+040873Y+061230X0100Y0330R270 S2      
327NNAME10787       PU4   -3          A01X+040873Y+061033X0100Y0330R270 S2      
327NNAME10788       PU4   -2          A01X+040873Y+060837X0100Y0330R270 S2      
327NNAME10789       PU4   -1          A01X+040873Y+060640X0100Y0330R270 S2      
327NNAME10788       PC40  -1          A01X+041607Y+060954X0180Y0200R180 S2      
327P1V8_STB_NODE1   PC42  -2          A01X+041554Y+060126X0180Y0200     S2      
327NNAME10789       PR16  -1          A01X+041607Y+060550X0180Y0200R180 S2      
317GND              VIA   -     D0100PA00X+040523Y+061169               S3      
317GND              VIA   -     D0100PA00X+040525Y+060702               S3      
317NNAME10789       VIA   -     D0100PA00X+041278Y+060550               S1      
327GND              PU4   -7          A01X+040194Y+061516X0100Y0330R180 S2      
327NNAME10790       PU4   -6          A01X+040390Y+061516X0100Y0330R180 S2      
327NNAME10791       PU4   -5          A01X+040587Y+061516X0100Y0330R180 S2      
327NNAME10787       PC41  -2          A01X+041561Y+061504X0180Y0200R090 S2      
327GND              PC41  -1          A01X+041561Y+061819X0180Y0200R090 S2      
327NNAME10791       PR13  -2          A01X+041147Y+062156X0180Y0200R090 S2      
327NNAME10788       PR13  -1          A01X+041147Y+062471X0180Y0200R090 S2      
327GND              PR14  -2          A01X+040747Y+062471X0180Y0200R270 S2      
327NNAME10791       PR14  -1          A01X+040747Y+062156X0180Y0200R270 S2      
327NNAME10790       PJ4   -2          A01X+040392Y+062086X0180Y0200R090 S2      
327NNAME10766       PJ4   -1          A01X+040392Y+062401X0200Y0400     S2      
317GND              VIA   -     D0100PA00X+041296Y+061821               S3      
317GND              VIA   -     D0100PA00X+040543Y+062681               S3      
317GND              VIA   -     D0100PA00X+041032Y+061478               S3      
317NNAME10788       VIA   -     D0100PA00X+041645Y+062132               S1      
317NNAME10787       VIA   -     D0100PA00X+041311Y+061374               S1      
317NNAME10790       VIA   -     D0100PA00X+040390Y+061833               S1      
317NNAME10791       VIA   -     D0100PA00X+041009Y+061833               S3      
327NNAME10792       R1003 -2          A01X+040816Y+064087X0180Y0200     S2      
327GND              R1003 -1          A01X+041131Y+064087X0180Y0200     S2      
327PU_FAN_TACH      R769  -2          A01X+041650Y+064475X0180Y0200     S2      
327N52411102        R1129 -2          A01X+040994Y+063185X0440Y0540     S2      
327P12V_AUX         R1129 -1          A01X+041742Y+063185X0440Y0540     S2      
327NNAME10792       Q44   -3          A01X+040310Y+063688X0240Y0280R270 S2      
317GND              VIA   -     D0100PA00X+041393Y+063981               S3      
317P12V_AUX         VIA   -     D0100PA00X+040952Y+063739               S3      
317P12V_AUX         VIA   -     D0100PA00X+041476Y+063623               S3      
317NNAME10792       VIA   -     D0100PA00X+040397Y+064236               S1      
317N52411102        VIA   -     D0100PA00X+040610Y+063185               S1      
327N/C              U70   -15         A01X+040636Y+066024X0140Y0610R270 S2      
327NNAME10793       U70   -14         A01X+040636Y+065774X0140Y0610R270 S2      
327FNACTRL2_T_ST    U70   -13         A01X+040636Y+065524X0140Y0610R270 S2      
327NNAME10767       U70   -12         A01X+040636Y+065274X0140Y0610R270 S2      
327FNACTRL2_ADD     U70   -11         A01X+040636Y+065024X0140Y0610R270 S2      
327N/C              U70   -10         A01X+040636Y+064774X0140Y0610R270 S2      
327PU_FAN_TACH      U70   -9          A01X+040636Y+064524X0140Y0610R270 S2      
327GND              C576  -2          A10X+040751Y+065341X0180Y0200R090 S1      
327P3V3_NODE1       C576  -1          A10X+040751Y+065026X0180Y0200R090 S1      
327FNACTRL2_ADD     R771  -2          A01X+041642Y+065273X0180Y0200     S2      
327NNAME10793       R767  -1          A01X+041642Y+065688X0180Y0200R180 S2      
327FNACTRL2_ADD     R772  -1          A01X+041642Y+064870X0180Y0200R180 S2      
317GND              VIA   -     D0100PA00X+041099Y+065296               S3      
317FNACTRL2_ADD     VIA   -     D0100PA00X+041354Y+064680               S1      
317NNAME10794       VIA   -     D0100PA00X+041198Y+066029               S1      
317NNAME10793       VIA   -     D0100PA00X+041372Y+065527               S1      
317P3V3_NODE1       VIA   -     D0100PA00X+041092Y+064936               S3      
327NNAME10794       U70   -16         A01X+040636Y+066274X0140Y0610R270 S2      
327NNAME10795       U69   -12         A01X+040636Y+067544X0140Y0610R270 S2      
327FNACTRL1_ADD     U69   -11         A01X+040636Y+067294X0140Y0610R270 S2      
327N/C              U69   -10         A01X+040636Y+067044X0140Y0610R270 S2      
327FAN4_TACH_IN     U69   -9          A01X+040636Y+066794X0140Y0610R270 S2      
327GND              U133  -3          A10X+040399Y+066458X0130Y0460R090 S1      
327FAN_PWM_BUF      U133  -2          A10X+040399Y+066714X0130Y0460R090 S1      
327N/C              U133  -1          A10X+040399Y+066970X0130Y0460R090 S1      
327FAN_PWM_BUF      R799  -2          A10X+040534Y+067618X0180Y0200     S1      
327P3V3_NODE1       R799  -1          A10X+040219Y+067618X0180Y0200     S1      
327FNACTRL1_ADD     R763  -1          A01X+041642Y+067309X0180Y0200R180 S2      
327FAN4_TACH_IN     R761  -1          A01X+041642Y+066903X0180Y0200R180 S2      
317NNAME10795       VIA   -     D0100PA00X+041397Y+067562               S3      
317NNAME10755       VIA   -     D0100PA00X+041522Y+066420               S1      
317FNACTRL1_ADD     VIA   -     D0100PA00X+041168Y+067265               S1      
317FAN4_TACH_IN     VIA   -     D0100PA00X+041107Y+066752               S1      
327FAN_PWM_BUF      VIA   -           A10X+041694Y+066995X0260Y0260     S1      
327NNAME10796       U69   -16         A01X+040636Y+068544X0140Y0610R270 S2      
327FAN_PWM_BUF      U69   -15         A01X+040636Y+068294X0140Y0610R270 S2      
327NNAME10797       U69   -14         A01X+040636Y+068044X0140Y0610R270 S2      
327NNAME10713       U69   -13         A01X+040636Y+067794X0140Y0610R270 S2      
327P3V3_NODE1       U65   -24         A10X+040694Y+068108X0140Y0590R270 S1      
327I2C_COM3_SDA     U65   -23         A10X+040694Y+068364X0140Y0590R270 S1      
327I2C_COM3_SCL     U65   -22         A10X+040694Y+068620X0140Y0590R270 S1      
327N21698979        U65   -21         A10X+040694Y+068876X0140Y0590R270 S1      
327N/C              U65   -20         A10X+040694Y+069132X0140Y0590R270 S1      
327I2C_COM3_SDA     U67   -5          A01X+040592Y+069116X0220Y0680R270 S2      
327FNACTRL1_ADD     R762  -2          A01X+041642Y+067713X0180Y0200     S2      
327NNAME10797       R760  -1          A01X+041642Y+068112X0180Y0200R180 S2      
317NNAME10796       VIA   -     D0100PA00X+041418Y+068615               S1      
317I2C_COM3_SCL     VIA   -     D0100PA00X+041186Y+068803               S3      
317NNAME10797       VIA   -     D0100PA00X+041364Y+068000               S1      
317P3V3_NODE1       VIA   -     D0100PA00X+041225Y+068320               S3      
317NNAME10713       VIA   -     D0100PA00X+041115Y+067839               S3      
327N/C              U65   -19         A10X+040694Y+069388X0140Y0590R270 S1      
327N/C              U65   -18         A10X+040694Y+069644X0140Y0590R270 S1      
327NNAME10768       U65   -17         A10X+040694Y+069900X0140Y0590R270 S1      
327NNAME10798       U65   -16         A10X+040694Y+070155X0140Y0590R270 S1      
327NNAME10743       U65   -15         A10X+040694Y+070411X0140Y0590R270 S1      
327PCA_CPLD_WDT2    U65   -14         A10X+040694Y+070667X0140Y0590R270 S1      
327P3V3_NODE1       U67   -8          A01X+040592Y+070616X0220Y0680R270 S2      
327N21700943        U67   -7          A01X+040592Y+070116X0220Y0680R270 S2      
327I2C_COM3_SCL     U67   -6          A01X+040592Y+069616X0220Y0680R270 S2      
317GND              VIA   -     D0100PA00X+041583Y+069327               S3      
317I2C_COM3_SDA     VIA   -     D0100PA00X+041288Y+069318               S3      
317P3V3_NODE1       VIA   -     D0100PA00X+041455Y+070746               S3      
317N21700943        VIA   -     D0100PA00X+041432Y+070098               S1      
317P3V3_STB_NODE1   VIA   -     D0100PA00X+041481Y+069697               S3      
327TACKOVER_EN_N    U65   -13         A10X+040694Y+070923X0140Y0590R270 S1      
327GND              C776  -2          A01X+040665Y+071384X0180Y0200R180 S2      
327P3V3_NODE1       C776  -1          A01X+040350Y+071384X0180Y0200R180 S2      
327P3V3_STB_NODE1   R1060 -2          A10X+040259Y+071625X0180Y0200     S1      
317GND              VIA   -     D0100PA00X+040958Y+071164               S3      
317P3V3_NODE1       VIA   -     D0100PA00X+040254Y+071065               S3      
317T5_NODE4_EN      VIA   -     D0100PA00X+041208Y+071903               S3      
317T5_NODE3_EN      VIA   -     D0100PA00X+041408Y+072133               S1      
317UART_SW_S0_N     VIA   -     D0100PA00X+041573Y+071090               S3      
317P3V3_STB_NODE1   VIA   -     D0100PA00X+040672Y+072340               S3      
327GND              C662  -2          A10X+041394Y+073908X0180Y0200R270 S1      
327T5_NODE2_EN_R    R899  -2          A10X+041394Y+073073X0180Y0200R090 S1      
327T5_NODE2_EN      R899  -1          A10X+041394Y+072758X0180Y0200R090 S1      
317GND              VIA   -     D0100PA00X+041394Y+073567               S3      
317NNAME10721       VIA   -     D0100PA00X+040901Y+072615               S1      
327T5_NODE2_EN_R    C662  -1          A10X+041394Y+074223X0180Y0200R270 S1      
317NNAME10745       VIA   -     D0100PA00X+041578Y+074708               S1      
327T5_NODE2_EN_R    VIA   -           A10X+041413Y+077969X0260Y0260     S1      
327T5_NODE2_EN_R    J18   -A82        A10X+040951Y+080787X0300Y1660R180 S1      
327T5_NODE1_EN_R    J18   -A81        A10X+041345Y+080787X0300Y1660R180 S1      
327PSU_ALERT_R_N    J18   -A80        A10X+041738Y+080787X0300Y1660R180 S1      
327NNAME10745       J18   -B82        A01X+040951Y+080787X0300Y1660R180 S2      
327NNAME10799       J18   -B81        A01X+041345Y+080590X0300Y1260R180 S2      
327GND              J18   -B80        A01X+041738Y+080787X0300Y1660R180 S2      
317NNAME10760       VIA   -     D0100PA00X+042189Y+012354               S1      
327GND              J2    -G2         A01X+043091Y+014587X1820Y1850     S2      
317GND              VIA   -     D0100PA00X+042147Y+016056               S3      
317GND              VIA   -     D0100PA00X+042147Y+015756               S3      
317N/C              J3    -     D0470UA00X+043410Y+023264               S0      
317NNAME10081       VIA   -     D0100PA00X+042164Y+022840               S3      
317NNAME10082       VIA   -     D0100PA00X+042164Y+022340               S1      
327XDP_NODE1_P60    J3    -60         A01X+043488Y+024373X0900Y0110     S2      
327NNAME10623       J3    -58         A01X+043488Y+024569X0900Y0110     S2      
327NNAME10669       J3    -56         A01X+043488Y+024766X0900Y0110     S2      
327NNAME10621       J3    -54         A01X+043488Y+024963X0900Y0110     S2      
317GND              VIA   -     D0100PA00X+042270Y+024430               S3      
317GND              VIA   -     D0100PA00X+042229Y+025066               S3      
317GND              VIA   -     D0100PA00X+041904Y+024261               S3      
317NNAME10623       VIA   -     D0100PA00X+042841Y+024519               S1      
317NNAME10669       VIA   -     D0100PA00X+042496Y+024120               S1      
317NNAME10620       VIA   -     D0100PA00X+041891Y+024569               S1      
317NNAME10621       VIA   -     D0100PA00X+042699Y+025002               S1      
327NNAME10626       J3    -52         A01X+043488Y+025160X0900Y0110     S2      
327GND              J3    -50         A01X+043488Y+025357X0900Y0110     S2      
327NNAME10800       J3    -48         A01X+043488Y+025554X0900Y0110     S2      
327NNAME10319       J3    -46         A01X+043488Y+025751X0900Y0110     S2      
327NNAME10801       J3    -44         A01X+043488Y+025947X0900Y0110     S2      
327NNAME10802       J3    -42         A01X+043488Y+026144X0900Y0110     S2      
327NNAME10803       J3    -40         A01X+043488Y+026341X0900Y0110     S2      
327GND              J3    -38         A01X+043488Y+026538X0900Y0110     S2      
317GND              VIA   -     D0100PA00X+042777Y+025357               S3      
317GND              VIA   -     D0100PA00X+042218Y+026689               S3      
317GND              VIA   -     D0100PA00X+042821Y+026211               S3      
317NNAME10771       VIA   -     D0100PA00X+042253Y+025353               S1      
317NNAME10593       VIA   -     D0100PA00X+042634Y+026706               S1      
317NNAME10773       VIA   -     D0100PA00X+041858Y+026369               S3      
317NNAME10774       VIA   -     D0100PA00X+042086Y+026133               S1      
317NNAME10776       VIA   -     D0100PA00X+042782Y+025883               S1      
327NNAME10593       J3    -36         A01X+043488Y+026735X0900Y0110     S2      
327NNAME10522       J3    -34         A01X+043488Y+026932X0900Y0110     S2      
327GND              J3    -32         A01X+043488Y+027128X0900Y0110     S2      
327NNAME10529       J3    -30         A01X+043488Y+027325X0900Y0110     S2      
327NNAME10518       J3    -28         A01X+043488Y+027522X0900Y0110     S2      
327GND              J3    -26         A01X+043488Y+027719X0900Y0110     S2      
327N/C              J3    -24         A01X+043488Y+027916X0900Y0110     S2      
327N/C              J3    -22         A01X+043488Y+028113X0900Y0110     S2      
317GND              VIA   -     D0100PA00X+041860Y+027354               S3      
317GND              VIA   -     D0100PA00X+041870Y+027963               S3      
317GND              VIA   -     D0100PA00X+042695Y+028105               S3      
317NNAME10522       VIA   -     D0100PA00X+042173Y+027914               S1      
317NNAME10518       VIA   -     D0100PA00X+042875Y+027522               S1      
327GND              J3    -20         A01X+043488Y+028310X0900Y0110     S2      
327NNAME10530       J3    -18         A01X+043488Y+028506X0900Y0110     S2      
327NNAME10608       J3    -16         A01X+043488Y+028703X0900Y0110     S2      
327GND              J3    -14         A01X+043488Y+028900X0900Y0110     S2      
327NNAME10607       J3    -12         A01X+043488Y+029097X0900Y0110     S2      
327NNAME10523       J3    -10         A01X+043488Y+029294X0900Y0110     S2      
327GND              J3    -8          A01X+043488Y+029491X0900Y0110     S2      
327NNAME10528       J3    -6          A01X+043488Y+029688X0900Y0110     S2      
317GND              VIA   -     D0100PA00X+041900Y+028987               S3      
317GND              VIA   -     D0100PA00X+042292Y+028950               S3      
317NNAME10529       VIA   -     D0100PA00X+041859Y+028668               S1      
317NNAME10523       VIA   -     D0100PA00X+042113Y+029260               S1      
317NNAME10530       VIA   -     D0100PA00X+042318Y+028460               S1      
317NNAME10608       VIA   -     D0100PA00X+042791Y+028676               S1      
317NNAME10607       VIA   -     D0100PA00X+042747Y+029229               S1      
317N/C              J3    -     D0470UA00X+043410Y+031188               S0      
327NNAME10519       J3    -4          A01X+043488Y+029884X0900Y0110     S2      
327GND              J3    -2          A01X+043488Y+030081X0900Y0110     S2      
317GND              VIA   -     D0100PA00X+041872Y+030118               S3      
317GND              H5    -8    D0220PA00X+042717Y+037717               S0      
317GND              H5    -7    D0220PA00X+042323Y+036732               S0      
317GND              H5    -9    D0220PA00X+042323Y+038701               S0      
317PV_VCCP_NODE1    VIA   -     D0100PA00X+042171Y+042453               S3      
317PV_VCCP_NODE1    VIA   -     D0100PA00X+043034Y+041657               S3      
317PV_VCCP_NODE1    VIA   -     D0100PA00X+043245Y+041877               S3      
317PV_VCCP_NODE1    VIA   -     D0100PA00X+042212Y+041829               S3      
317PV_VCCP_NODE1    VIA   -     D0100PA00X+043296Y+041489               S3      
317PV_VCCP_NODE1    VIA   -     D0100PA00X+042208Y+041464               S3      
317PV_VCCP_NODE1    VIA   -     D0100PA00X+042208Y+041045               S3      
317PV_VCCP_NODE1    VIA   -     D0100PA00X+042177Y+043319               S3      
327PV_VCCP_NODE1    PL8   -1A         A01X+042875Y+045559X0720Y1350R090 S2      
317PV_VCCP_NODE1    VIA   -     D0100PA00X+042286Y+044179               S3      
317PV_VCCP_NODE1    VIA   -     D0100PA00X+042276Y+044558               S3      
317PV_VCCP_NODE1    VIA   -     D0100PA00X+042587Y+044951               S3      
317PV_VCCP_NODE1    VIA   -     D0100PA00X+042246Y+044947               S3      
317PV_VCCP_NODE1    VIA   -     D0100PA00X+042967Y+044955               S3      
317PV_VCCP_NODE1    VIA   -     D0100PA00X+041942Y+045317               S3      
327NNAME10777       PL8   -1B         A01X+042875Y+045869X0100Y0200R090 S2      
317NNAME10777       VIA   -     D0100PA00X+042875Y+046331               S1      
317PV_VCCP_NODE1    VIA   -     D0100PA00X+041942Y+045736               S3      
317NNAME10804       VIA   -     D0100PA00X+042875Y+046877               S1      
327NNAME10805       U124  -2_EP       A01X+042695Y+049287X1150Y1660     S2      
327NNAME10804       PL8   -2B         A01X+042875Y+047431X0100Y0200R090 S2      
327NNAME10805       PL8   -2A         A01X+042875Y+047740X0720Y1350R090 S2      
327NNAME10805       PC96  -2          A01X+042820Y+050732X0180Y0200     S2      
327NNAME10806       PC96  -1          A01X+043135Y+050732X0180Y0200     S2      
327NNAME10781       PC88  -1          A01X+042179Y+051268X0280Y0320R180 S2      
327GND              PC88  -2          A01X+042179Y+050688X0280Y0320R180 S2      
327NNAME10807       PR51  -2          A01X+043101Y+051158X0180Y0200R180 S2      
327NNAME10805       PR51  -1          A01X+042786Y+051158X0180Y0200R180 S2      
317GND              VIA   -     D0100PA00X+041907Y+050928               S3      
317NNAME10807       VIA   -     D0100PA00X+043128Y+051422               S3      
317NNAME10807       VIA   -     D0100PA00X+043136Y+051684               S3      
317NNAME10781       VIA   -     D0100PA00X+042205Y+051703               S1      
317NNAME10779       VIA   -     D0100PA00X+042600Y+051621               S3      
317NNAME10779       VIA   -     D0100PA00X+042487Y+051392               S3      
327NNAME10807       PU8   -40         A01X+043020Y+052108X0070Y0360R180 S2      
327NNAME10805       PU8   -39         A01X+042863Y+052115X0070Y0380R180 S2      
327NNAME10779       PU8   -38         A01X+042705Y+052115X0070Y0380R180 S2      
327NNAME10781       PU8   -37         A01X+042548Y+052115X0070Y0380R180 S2      
327N/C              PU8   -36         A01X+042390Y+052115X0070Y0380R180 S2      
327N/C              PU8   -35         A01X+042233Y+052115X0070Y0380R180 S2      
327N/C              PU8   -34         A01X+042075Y+052115X0070Y0380R180 S2      
327N/C              PU8   -33         A01X+041918Y+052115X0070Y0380R180 S2      
327NNAME10780       PU8   -32         A01X+041760Y+052115X0070Y0380R180 S2      
327NNAME10808       PU8   -7          A01X+043306Y+053346X0070Y0380R090 S2      
327NNAME10809       PU8   -6          A01X+043306Y+053188X0070Y0380R090 S2      
327NNAME10810       PU8   -5          A01X+043306Y+053031X0070Y0380R090 S2      
327NNAME10777       PU8   -4          A01X+043306Y+052873X0070Y0380R090 S2      
327NNAME10811       PU8   -3          A01X+043306Y+052716X0070Y0380R090 S2      
327NNAME10812       PU8   -2          A01X+043306Y+052558X0070Y0380R090 S2      
327NNAME10806       PU8   -1          A01X+043313Y+052401X0070Y0360R090 S2      
327GND              PU8   -TH         A01X+042312Y+053109X1340Y1340R180 S2      
327GND              PR53  -2          A10X+042708Y+052240X0180Y0200R090 S1      
327NNAME10779       PR53  -1          A10X+042708Y+051925X0180Y0200R090 S1      
317GND              VIA   -     D0100PA00X+042328Y+052516               S3      
317GND              VIA   -     D0100PA00X+042887Y+052519               S3      
317GND              VIA   -     D0100PA00X+041752Y+052513               S3      
317GND              VIA   -     D0100PA00X+042887Y+053063               S3      
317GND              VIA   -     D0100PA00X+041752Y+053118               S3      
327NNAME10786       PU8   -19         A01X+041760Y+054104X0070Y0380R180 S2      
327P5V_STB_NODE1    PU8   -18         A01X+041918Y+054104X0070Y0380R180 S2      
327NNAME10761       PU8   -17         A01X+042075Y+054104X0070Y0380R180 S2      
327NNAME10813       PU8   -16         A01X+042233Y+054104X0070Y0380R180 S2      
327NNAME10814       PU8   -15         A01X+042390Y+054104X0070Y0380R180 S2      
327P5V_STB_NODE1    PU8   -14         A01X+042548Y+054104X0070Y0380R180 S2      
327NNAME10815       PU8   -13         A01X+042705Y+054104X0070Y0380R180 S2      
327NNAME10816       PU8   -12         A01X+042863Y+054104X0070Y0380R180 S2      
327NNAME10817       PU8   -11         A01X+043020Y+054111X0070Y0360R180 S2      
327GND              PU8   -10         A01X+043313Y+053818X0070Y0360R090 S2      
327NNAME10761       PU8   -9          A01X+043306Y+053661X0070Y0380R090 S2      
327NNAME10785       PU8   -8          A01X+043306Y+053503X0070Y0380R090 S2      
327NNAME10813       PR76  -2          A01X+041916Y+055034X0180Y0200R180 S2      
327P5V_STB_NODE1    PR41  -1          A10X+042440Y+054101X0280Y0320R270 S1      
327NNAME10761       PR41  -2          A10X+043020Y+054101X0280Y0320R270 S1      
317GND              VIA   -     D0100PA00X+042875Y+053700               S3      
317GND              VIA   -     D0100PA00X+042333Y+053676               S3      
317GND              VIA   -     D0100PA00X+041762Y+053677               S3      
317P5V_STB_NODE1    VIA   -     D0100PA00X+042607Y+054605               S3      
317P5V_STB_NODE1    VIA   -     D0100PA00X+041798Y+054535               S3      
327P5V_STB_NODE1    VIA   -           A10X+041866Y+054142X0260Y0260     S1      
317NNAME10815       VIA   -     D0100PA00X+042804Y+054812               S1      
317NNAME10813       VIA   -     D0100PA00X+042146Y+054770               S1      
327NNAME10814       PC111 -2          A01X+042385Y+055097X0180Y0200R090 S2      
327NNAME10785       PC111 -1          A01X+042385Y+055412X0180Y0200R090 S2      
327NNAME10815       PR65  -2          A01X+042804Y+055095X0180Y0200R090 S2      
327NNAME10785       PR65  -1          A01X+042804Y+055410X0180Y0200R090 S2      
327NNAME10814       PR74  -1          A01X+041919Y+055902X0180Y0200     S2      
327NNAME10813       PR77  -2          A01X+041917Y+055439X0180Y0200R180 S2      
327NNAME10815       PR64  -2          A01X+042806Y+055911X0180Y0200R090 S2      
327NNAME10761       PR64  -1          A01X+042806Y+056226X0180Y0200R090 S2      
327NNAME10814       PR73  -2          A01X+042383Y+055903X0180Y0200R090 S2      
327NNAME10762       PR73  -1          A01X+042383Y+056218X0180Y0200R090 S2      
327NNAME10816       PR61  -2          A01X+043215Y+055910X0180Y0200R090 S2      
327NNAME10761       PR61  -1          A01X+043215Y+056225X0180Y0200R090 S2      
327NNAME10816       PR62  -2          A01X+043235Y+055093X0180Y0200R090 S2      
327NNAME10785       PR62  -1          A01X+043235Y+055408X0180Y0200R090 S2      
327NNAME10762       PR72  -2          A01X+042432Y+056613X0180Y0200     S2      
327NNAME10761       PR72  -1          A01X+042747Y+056613X0180Y0200     S2      
317NNAME10814       VIA   -     D0100PA00X+042088Y+055673               S1      
317NNAME10785       VIA   -     D0100PA00X+042804Y+055654               S3      
317NNAME10785       VIA   -     D0100PA00X+042386Y+055654               S3      
317NNAME10816       VIA   -     D0100PA00X+043115Y+055661               S1      
327NNAME10818       R1004 -2          A01X+043142Y+058758X0180Y0200     S2      
327NNAME10789       PR15  -1          A01X+041869Y+059730X0180Y0200     S2      
327N52411159        R1130 -2          A01X+042490Y+059830X0440Y0540R270 S2      
327P12V_AUX         R1130 -1          A01X+042490Y+059082X0440Y0540R270 S2      
317P12V_AUX         VIA   -     D0100PA00X+042490Y+058628               S3      
317N52411159        VIA   -     D0100PA00X+042934Y+059687               S1      
327GND              PC40  -2          A01X+041922Y+060954X0180Y0200R180 S2      
327NNAME10789       PC42  -1          A01X+041869Y+060126X0180Y0200     S2      
327P12V_AUX         R657  -2          A01X+042515Y+060452X0180Y0200     S2      
327N52411212        R657  -1          A01X+042830Y+060452X0180Y0200     S2      
327N52411212        R1128 -2          A01X+043217Y+060452X0180Y0200     S2      
327GND              PR16  -2          A01X+041922Y+060550X0180Y0200R180 S2      
327N52411159        Q45   -2          A01X+043134Y+059993X0240Y0280R180 S2      
327N52411212        U108  -D          A01X+043032Y+061107X0400Y0500R180 S2      
317GND              VIA   -     D0100PA00X+042221Y+060534               S3      
317GND              VIA   -     D0100PA00X+041922Y+061225               S3      
317P12V_AUX         VIA   -     D0100PA00X+042515Y+060843               S3      
317N52411212        VIA   -     D0100PA00X+043152Y+060704               S1      
327GND              U108  -S          A01X+042632Y+061987X0400Y0500R180 S2      
317GND              VIA   -     D0100PA00X+042222Y+061987               S3      
327NNAME10819       R646  -2          A01X+042831Y+064068X0180Y0200R180 S2      
327I2C_PSU2_SCL     R646  -1          A01X+042516Y+064068X0180Y0200R180 S2      
327P3V3_NODE1       R769  -1          A01X+041965Y+064475X0180Y0200     S2      
327I2C_PSU2_SCL     U126  -D          A01X+042588Y+063148X0400Y0500R090 S2      
317P12V_AUX         VIA   -     D0100PA00X+042025Y+063600               S3      
317P12V_AUX         VIA   -     D0100PA00X+041742Y+063759               S3      
327P3V3_NODE1       U68   -5          A01X+042470Y+066148X0220Y0530     S2      
327GND              U68   -4          A01X+043218Y+066148X0220Y0530     S2      
327TMP05_FUNC1      U68   -3          A01X+043218Y+065183X0220Y0530     S2      
327NNAME10713       U68   -2          A01X+042844Y+065183X0220Y0530     S2      
327NNAME10795       U68   -1          A01X+042470Y+065183X0220Y0530     S2      
327P3V3_NODE1       R759  -2          A01X+042627Y+064610X0180Y0200     S2      
327TMP05_FUNC1      R759  -1          A01X+042942Y+064610X0180Y0200     S2      
327P3V3_NODE1       R771  -1          A01X+041957Y+065273X0180Y0200     S2      
327P3V3_NODE1       R767  -2          A01X+041957Y+065688X0180Y0200R180 S2      
327GND              R772  -2          A01X+041957Y+064870X0180Y0200R180 S2      
317GND              VIA   -     D0100PA00X+042247Y+064785               S3      
317TMP05_FUNC1      VIA   -     D0100PA00X+043218Y+064746               S1      
317NNAME10795       VIA   -     D0100PA00X+042533Y+065642               S1      
317P3V3_NODE1       VIA   -     D0100PA00X+042201Y+065273               S3      
317P3V3_NODE1       VIA   -     D0100PA00X+042362Y+064540               S3      
317P3V3_NODE1       VIA   -     D0100PA00X+042203Y+065688               S3      
317NNAME10713       VIA   -     D0100PA00X+042982Y+065671               S3      
327GND              R763  -2          A01X+041957Y+067309X0180Y0200R180 S2      
327FAN4_TACH        R761  -2          A01X+041957Y+066903X0180Y0200R180 S2      
317GND              VIA   -     D0100PA00X+042515Y+067243               S3      
317GND              VIA   -     D0100PA00X+043014Y+066566               S3      
317GND              VIA   -     D0100PA00X+041797Y+066345               S3      
317FAN4_TACH        VIA   -     D0100PA00X+042108Y+066595               S1      
317P3V3_NODE1       VIA   -     D0100PA00X+042222Y+067523               S3      
317P3V3_NODE1       VIA   -     D0100PA00X+042610Y+066788               S3      
327P3V3_NODE1       C571  -2          A10X+041806Y+068157X0180Y0200R180 S1      
327GND              C571  -1          A10X+042121Y+068157X0180Y0200R180 S1      
327GND              C574  -2          A01X+042294Y+068543X0180Y0200     S2      
327P3V3_NODE1       C574  -1          A01X+042609Y+068543X0180Y0200     S2      
327I2C_COM3_SDA     R765  -2          A01X+041778Y+068929X0180Y0200R270 S2      
327NNAME10796       R765  -1          A01X+041778Y+068614X0180Y0200R270 S2      
327N21698979        R704  -2          A10X+041885Y+068565X0180Y0200R180 S1      
327P3V3_NODE1       R704  -1          A10X+042200Y+068565X0180Y0200R180 S1      
327P3V3_NODE1       R762  -1          A01X+041957Y+067713X0180Y0200     S2      
327P3V3_NODE1       R760  -2          A01X+041957Y+068112X0180Y0200R180 S2      
317GND              VIA   -     D0100PA00X+042251Y+067784               S3      
317GND              VIA   -     D0100PA00X+043087Y+068454               S3      
317GND              VIA   -     D0100PA00X+042517Y+068859               S3      
317P3V3_NODE1       VIA   -     D0100PA00X+042790Y+067971               S3      
317P3V3_NODE1       VIA   -     D0100PA00X+043086Y+067916               S3      
317P3V3_NODE1       VIA   -     D0100PA00X+042298Y+069035               S3      
327N21698979        VIA   -           A10X+041838Y+069088X0260Y0260     S1      
317P5V_NODE1        VIA   -     D0100PA00X+043086Y+069116               S3      
317P5V_NODE1        VIA   -     D0100PA00X+043081Y+068716               S3      
317UART_SW_S5_N     VIA   -     D0100PA00X+042721Y+069193               S3      
327P3V3_NODE1       C573  -2          A01X+041743Y+070466X0180Y0200     S2      
327GND              C573  -1          A01X+042058Y+070466X0180Y0200     S2      
327P3V3_STB_NODE1   R803  -2          A10X+042029Y+069751X0180Y0200R270 S1      
327NNAME10798       R803  -1          A10X+042029Y+070066X0180Y0200R270 S1      
327P3V3_NODE1       R735  -2          A01X+042058Y+069671X0180Y0200R180 S2      
327N21700943        R735  -1          A01X+041743Y+069671X0180Y0200R180 S2      
327GND              R751  -2          A01X+042058Y+070067X0180Y0200R180 S2      
327N21700943        R751  -1          A01X+041743Y+070067X0180Y0200R180 S2      
317GND              VIA   -     D0100PA00X+042332Y+070534               S3      
317P3V3_NODE1       VIA   -     D0100PA00X+042306Y+069671               S3      
317P5V_NODE1        VIA   -     D0100PA00X+043062Y+069916               S3      
317P5V_NODE1        VIA   -     D0100PA00X+043067Y+070316               S3      
317P5V_NODE1        VIA   -     D0100PA00X+043073Y+070716               S3      
317P5V_NODE1        VIA   -     D0100PA00X+043081Y+069516               S3      
317T6_NODE2_EN      VIA   -     D0100PA00X+042723Y+070738               S1      
317UART_SW_S2_N     VIA   -     D0100PA00X+042639Y+070117               S3      
317UART_SW_S1_N     VIA   -     D0100PA00X+042324Y+070795               S3      
317UART_SW_S3_N     VIA   -     D0100PA00X+042559Y+069590               S3      
317UART_SW_S4_N     VIA   -     D0100PA00X+042135Y+069400               S3      
317GND              VIA   -     D0100PA00X+042294Y+072380               S3      
317P5V_NODE1        VIA   -     D0100PA00X+043074Y+071116               S3      
317T6_NODE1_EN      VIA   -     D0100PA00X+042713Y+071787               S3      
317T5_NODE1_EN      VIA   -     D0100PA00X+042173Y+071740               S3      
317T6_NODE3_EN      VIA   -     D0100PA00X+042924Y+072101               S1      
317T6_NODE2_EN      VIA   -     D0100PA00X+042441Y+071843               S3      
317T5_NODE2_EN      VIA   -     D0100PA00X+041733Y+071742               S3      
317NNAME10820       VIA   -     D0100PA00X+043144Y+072396               S3      
327GND              C607  -2          A10X+042294Y+072758X0180Y0200R270 S1      
327PSU_ALERT_N      C607  -1          A10X+042294Y+073073X0180Y0200R270 S1      
327GND              C699  -2          A01X+041844Y+073908X0180Y0200R090 S2      
327GND              C739  -2          A10X+042694Y+073908X0180Y0200R270 S1      
327GND              C736  -2          A10X+042744Y+072758X0180Y0200R270 S1      
327NNAME10820       C736  -1          A10X+042744Y+073073X0180Y0200R270 S1      
327GND              C653  -2          A01X+043094Y+073908X0180Y0200R090 S2      
327GND              C659  -2          A10X+041844Y+073908X0180Y0200R270 S1      
327GND              C656  -2          A01X+042644Y+073908X0180Y0200R090 S2      
327GND              C696  -2          A01X+042194Y+072758X0180Y0200R090 S2      
327NNAME10721       C696  -1          A01X+042194Y+073073X0180Y0200R090 S2      
327PSU_ALERT_N      R838  -2          A10X+042294Y+073908X0180Y0200R270 S1      
327NNAME10721       R933  -1          A01X+042244Y+073908X0180Y0200R270 S2      
327NNAME10820       R973  -1          A10X+043144Y+073908X0180Y0200R090 S1      
327T6_NODE3_EN_R    R890  -2          A01X+043094Y+073073X0180Y0200R270 S2      
327T6_NODE3_EN      R890  -1          A01X+043094Y+072758X0180Y0200R270 S2      
327T5_NODE1_EN_R    R896  -2          A10X+041844Y+073073X0180Y0200R090 S1      
327T5_NODE1_EN      R896  -1          A10X+041844Y+072758X0180Y0200R090 S1      
327T6_NODE4_EN_R    R893  -2          A01X+042644Y+073073X0180Y0200R270 S2      
327T6_NODE4_EN      R893  -1          A01X+042644Y+072758X0180Y0200R270 S2      
317GND              VIA   -     D0100PA00X+042016Y+072431               S3      
317GND              VIA   -     D0100PA00X+043094Y+073590               S3      
317GND              VIA   -     D0100PA00X+042643Y+073513               S3      
317GND              VIA   -     D0100PA00X+041844Y+073593               S3      
317PSU_ALERT_N      VIA   -     D0100PA00X+042029Y+073374               S3      
317NNAME10821       VIA   -     D0100PA00X+042390Y+073606               S3      
317NNAME10721       VIA   -     D0100PA00X+042420Y+073340               S3      
317T6_NODE4_EN      VIA   -     D0100PA00X+042644Y+072424               S3      
327NNAME10745       C699  -1          A01X+041844Y+074223X0180Y0200R090 S2      
327NNAME10821       C739  -1          A10X+042694Y+074223X0180Y0200R270 S1      
327T6_NODE3_EN_R    C653  -1          A01X+043094Y+074223X0180Y0200R090 S2      
327T5_NODE1_EN_R    C659  -1          A10X+041844Y+074223X0180Y0200R270 S1      
327T6_NODE4_EN_R    C656  -1          A01X+042644Y+074223X0180Y0200R090 S2      
327PSU_ALERT_R_N    R838  -1          A10X+042294Y+074223X0180Y0200R270 S1      
327NNAME10799       R933  -2          A01X+042244Y+074223X0180Y0200R270 S2      
327NNAME10822       R973  -2          A10X+043144Y+074223X0180Y0200R090 S1      
327PSU_ALERT_R_N    VIA   -           A10X+042201Y+076669X0260Y0260     S1      
317T6_NODE4_EN_R    VIA   -     D0100PA00X+042169Y+077955               S1      
317NNAME10799       VIA   -     D0100PA00X+041788Y+078636               S1      
327NNAME10821       VIA   -           A10X+042554Y+078651X0260Y0260     S1      
327NNAME10822       VIA   -           A10X+043129Y+078548X0260Y0260     S1      
317T6_NODE2_EN_R    VIA   -     D0100PA00X+042825Y+077205               S1      
317T6_NODE3_EN_R    VIA   -     D0100PA00X+042690Y+077975               S1      
327T5_NODE1_EN_R    VIA   -           A10X+041755Y+077287X0260Y0260     S1      
327GND              J18   -A79        A10X+042132Y+080787X0300Y1660R180 S1      
327NNAME10821       J18   -A78        A10X+042526Y+080787X0300Y1660R180 S1      
327NNAME10822       J18   -A77        A10X+042920Y+080787X0300Y1660R180 S1      
327NNAME10823       J18   -A76        A10X+043313Y+080787X0300Y1660R180 S1      
327T6_NODE4_EN_R    J18   -B79        A01X+042132Y+080787X0300Y1660R180 S2      
327T6_NODE3_EN_R    J18   -B78        A01X+042526Y+080787X0300Y1660R180 S2      
327T6_NODE2_EN_R    J18   -B77        A01X+042920Y+080787X0300Y1660R180 S2      
327T6_NODE1_EN_R    J18   -B76        A01X+043313Y+080787X0300Y1660R180 S2      
317GND              VIA   -     D0100PA00X+042132Y+079148               S3      
317GND              VIA   -     D0100PA00X+041738Y+079148               S3      
327GND              C860  -2          A01X+044630Y+007185X0180Y0200R090 S2      
327NNAME10824       C860  -1          A01X+044630Y+007500X0180Y0200R090 S2      
317GND              VIA   -     D0100PA00X+044627Y+006907               S3      
317NNAME10424       VIA   -     D0100PA00X+044238Y+007551               S3      
317NNAME10424       VIA   -     D0100PA00X+043967Y+007004               S3      
317GND              VIA   -     D0100PA00X+044609Y+009016               S3      
317GND              VIA   -     D0100PA00X+044609Y+008516               S3      
317GND              VIA   -     D0100PA00X+044609Y+008766               S3      
317NNAME10824       VIA   -     D0100PA00X+044692Y+007836               S1      
327NNAME10770       C858  -1          A01X+044370Y+011043X0440Y0540R270 S2      
327NNAME10770       C859  -1          A01X+043594Y+011055X0440Y0540R270 S2      
327NNAME10770       J24   -1          A01X+045156Y+010168X0280Y0740R270 S2      
327NNAME10825       J24   -2          A01X+044566Y+010168X0280Y0320R090 S2      
317NNAME10825       VIA   -     D0100PA00X+044772Y+009793               S1      
327GND              C858  -2          A01X+044370Y+011791X0440Y0540R270 S2      
327GND              C859  -2          A01X+043594Y+011803X0440Y0540R270 S2      
317GND              VIA   -     D0100PA00X+043416Y+012227               S3      
317GND              VIA   -     D0100PA00X+044345Y+012455               S3      
317GND              VIA   -     D0100PA00X+044152Y+012224               S3      
317GND              VIA   -     D0100PA00X+043416Y+012509               S3      
317GND              VIA   -     D0100PA00X+044483Y+012213               S3      
327GND              OSC4  -2          A01X+044736Y+015714X0440Y0560     S2      
317P3V3_RTC_NODE1   VIA   -     D0100PA00X+044652Y+014693               S3      
317GND              VIA   -     D0100PA00X+043325Y+016074               S3      
317GND              VIA   -     D0100PA00X+043336Y+015761               S3      
327N21550241        OSC4  -1          A01X+044736Y+017714X0440Y0560     S2      
327N21550241        R619  -2          A01X+044703Y+018444X0180Y0200     S2      
317N21550241        VIA   -     D0100PA00X+044455Y+018406               S1      
317P3V3_RTC_NODE1   VIA   -     D0100PA00X+044252Y+022362               S3      
327NNAME10800       C183  -1          A01X+044776Y+024940X0180Y0200R180 S2      
327NNAME10626       R228  -1          A01X+044743Y+024516X0180Y0200R180 S2      
327NNAME10621       R229  -2          A01X+044743Y+024116X0180Y0200     S2      
327XDP_NODE1_P60    R225  -1          A01X+044743Y+023716X0180Y0200R180 S2      
317GND              VIA   -     D0100PA00X+044258Y+023646               S3      
317NNAME10626       VIA   -     D0100PA00X+044158Y+025073               S1      
317XDP_NODE1_P60    VIA   -     D0100PA00X+044321Y+024096               S1      
327NNAME10801       C197  -2          A01X+044818Y+026229X0280Y0320R090 S2      
327GND              C182  -1          A10X+043545Y+025193X0280Y0320     S1      
327NNAME10776       C182  -2          A10X+043545Y+025773X0280Y0320     S1      
327P1V05_NODE1      R224  -2          A10X+043577Y+026545X0180Y0200R090 S1      
327NNAME10776       R224  -1          A10X+043577Y+026230X0180Y0200R090 S1      
317GND              VIA   -     D0100PA00X+044790Y+026529               S3      
317P1V05_NODE1      VIA   -     D0100PA00X+044150Y+026673               S3      
317NNAME10801       VIA   -     D0100PA00X+044179Y+025947               S1      
317GND              VIA   -     D0100PA00X+044215Y+027936               S3      
317GND              VIA   -     D0100PA00X+044217Y+027128               S3      
317GND              VIA   -     D0100PA00X+044108Y+029491               S3      
317NNAME10771       VIA   -     D0100PA00X+044554Y+028885               S3      
317P3V3_RTC_NODE1   VIA   -     D0100PA00X+044589Y+028332               S1      
317GND              VIA   -     D0100PA00X+044136Y+030081               S3      
317P1V8_NODE1       VIA   -     D0100PA00X+043834Y+040338               S3      
317P1V8_NODE1       VIA   -     D0100PA00X+043915Y+040093               S3      
317P1V8_NODE1       VIA   -     D0100PA00X+044324Y+040198               S1      
317P1V8_NODE1       VIA   -     D0100PA00X+044683Y+040055               S3      
317P1V8_NODE1       VIA   -     D0100PA00X+044590Y+040346               S3      
327PV_VCCP_NODE1    PC118 -2          A10X+044784Y+042463X0440Y0540R180 S1      
327PV_VCCP_NODE1    PC100 -1          A01X+043957Y+041871X0950Y1110     S2      
317PV_VCCP_NODE1    VIA   -     D0100PA00X+043637Y+041054               S3      
317PV_VCCP_NODE1    VIA   -     D0100PA00X+044402Y+041037               S3      
317PV_VCCP_NODE1    VIA   -     D0100PA00X+043983Y+041037               S3      
317PV_VCCP_NODE1    VIA   -     D0100PA00X+044666Y+041333               S3      
317PV_VCCP_NODE1    VIA   -     D0100PA00X+044695Y+041716               S3      
327PV_VCCP_NODE1    PC121 -2          A10X+044784Y+043280X0440Y0540R180 S1      
327PV_VCCP_NODE1    PC99  -1          A01X+043957Y+043871X0950Y1110     S2      
317PV_VCCP_NODE1    VIA   -     D0100PA00X+044090Y+044626               S3      
317PV_VCCP_NODE1    VIA   -     D0100PA00X+043671Y+044626               S3      
317PV_VCCP_NODE1    VIA   -     D0100PA00X+044485Y+044634               S3      
317PV_VCCP_NODE1    VIA   -     D0100PA00X+043839Y+045613               S3      
317PV_VCCP_NODE1    VIA   -     D0100PA00X+043852Y+045232               S3      
317PV_VCCP_NODE1    VIA   -     D0100PA00X+043372Y+044947               S3      
317GND              VIA   -     D0100PA00X+043789Y+047107               S1      
327NNAME10807       U124  -1          A01X+044136Y+048537X0300Y0410R090 S2      
327NNAME10826       U124  -1_EP       A01X+043620Y+049287X0320Y1660R180 S2      
317NNAME10807       VIA   -     D0100PA00X+044492Y+048526               S1      
317NNAME10807       VIA   -     D0100PA00X+044777Y+048529               S3      
317NNAME10805       VIA   -     D0100PA00X+043772Y+047630               S1      
327NNAME10826       U124  -4          A01X+044136Y+050037X0300Y0410R090 S2      
327NNAME10826       U124  -3          A01X+044136Y+049537X0300Y0410R090 S2      
327NNAME10826       U124  -2          A01X+044136Y+049037X0300Y0410R090 S2      
317NNAME10826       VIA   -     D0100PA00X+044537Y+049066               S3      
317NNAME10826       VIA   -     D0100PA00X+044520Y+049459               S1      
327NNAME10785       PC95  -2          A01X+043975Y+050964X0180Y0200R090 S2      
327NNAME10827       PC95  -1          A01X+043975Y+051279X0180Y0200R090 S2      
327NNAME10804       PR55  -2          A01X+044377Y+051816X0180Y0200R090 S2      
327NNAME10827       PR42  -2          A01X+043976Y+051811X0180Y0200R090 S2      
327NNAME10778       PR58  -2          A01X+044776Y+051816X0180Y0200R090 S2      
327NNAME10826       PR43  -2          A01X+044385Y+050964X0180Y0200R090 S2      
327NNAME10827       PR43  -1          A01X+044385Y+051279X0180Y0200R090 S2      
317NNAME10785       VIA   -     D0100PA00X+043975Y+050652               S1      
317NNAME10827       VIA   -     D0100PA00X+043976Y+051554               S1      
327NNAME10785       PC108 -2          A01X+044573Y+053420X0180Y0200R270 S2      
327NNAME10810       PC108 -1          A01X+044573Y+053105X0180Y0200R270 S2      
327NNAME10777       PC101 -2          A01X+044519Y+052652X0180Y0200     S2      
327NNAME10785       PC101 -1          A01X+044834Y+052652X0180Y0200     S2      
327NNAME10809       PR68  -2          A01X+044165Y+053428X0180Y0200R270 S2      
327NNAME10810       PR68  -1          A01X+044165Y+053113X0180Y0200R270 S2      
327NNAME10811       PR55  -1          A01X+044377Y+052131X0180Y0200R090 S2      
327NNAME10812       PR42  -1          A01X+043976Y+052126X0180Y0200R090 S2      
327NNAME10811       PR58  -1          A01X+044776Y+052131X0180Y0200R090 S2      
317NNAME10812       VIA   -     D0100PA00X+043976Y+052376               S1      
317NNAME10785       VIA   -     D0100PA00X+044778Y+052389               S3      
317NNAME10806       VIA   -     D0100PA00X+043461Y+052149               S1      
327NNAME10785       PC122 -2          A01X+044303Y+054313X0180Y0200R090 S2      
327NNAME10780       PC122 -1          A01X+044303Y+054628X0180Y0200R090 S2      
327NNAME10761       PC87  -1          A01X+043826Y+054889X0280Y0320R180 S2      
327NNAME10785       PC87  -2          A01X+043826Y+054309X0280Y0320R180 S2      
327NNAME10400       PJ15  -2          A01X+044633Y+054650X0180Y0200R270 S2      
327NNAME10808       PJ15  -1          A01X+044633Y+054335X0200Y0400R180 S2      
317NNAME10780       VIA   -     D0100PA00X+044276Y+054960               S3      
317NNAME10809       VIA   -     D0100PA00X+044584Y+053809               S1      
317NNAME10761       VIA   -     D0100PA00X+043600Y+053973               S3      
317NNAME10761       VIA   -     D0100PA00X+043420Y+054290               S3      
317NNAME10785       VIA   -     D0100PA00X+043872Y+053884               S3      
317NNAME10785       VIA   -     D0100PA00X+044106Y+054056               S1      
317NNAME10785       VIA   -     D0100PA00X+044833Y+053500               S3      
327GND              PR71  -2          A01X+044654Y+055352X0180Y0200R270 S2      
327NNAME10400       PR71  -1          A01X+044654Y+055037X0180Y0200R270 S2      
327NNAME10817       PR57  -2          A01X+043622Y+055913X0180Y0200R090 S2      
327NNAME10761       PR57  -1          A01X+043622Y+056228X0180Y0200R090 S2      
327NNAME10817       PR60  -2          A01X+043629Y+055334X0180Y0200     S2      
327NNAME10785       PR60  -1          A01X+043944Y+055334X0180Y0200     S2      
317NNAME10761       VIA   -     D0100PA00X+044133Y+055605               S3      
317NNAME10817       VIA   -     D0100PA00X+043783Y+055637               S1      
317NNAME10785       VIA   -     D0100PA00X+043419Y+055644               S3      
317NNAME10785       VIA   -     D0100PA00X+044224Y+055334               S1      
327GND              R1004 -1          A01X+043457Y+058758X0180Y0200     S2      
327NNAME10818       Q45   -3          A01X+043508Y+059206X0240Y0280R180 S2      
317GND              VIA   -     D0100PA00X+043752Y+058758               S3      
317NNAME10063       VIA   -     D0100PA00X+044123Y+058734               S3      
317NNAME10063       VIA   -     D0100PA00X+044783Y+058874               S3      
317NNAME10063       VIA   -     D0100PA00X+044638Y+058268               S3      
327N52410978        C887  -2          A01X+044798Y+060452X0280Y0320R090 S2      
327N52411214        R1128 -1          A01X+043532Y+060452X0180Y0200     S2      
327P3V3_STB_NODE1   R802  -2          A01X+044004Y+060507X0180Y0200     S2      
327N52410978        R802  -1          A01X+044319Y+060507X0180Y0200     S2      
327N52411214        Q45   -1          A01X+043882Y+059993X0240Y0280R180 S2      
327N52410978        U107  -D          A01X+044414Y+061107X0400Y0500R180 S2      
317N52411214        VIA   -     D0100PA00X+043532Y+060012               S1      
317P3V3_STB_NODE1   VIA   -     D0100PA00X+044004Y+060854               S3      
317N52410978        VIA   -     D0100PA00X+043712Y+061293               S1      
327PMBUS2_EN        R1283 -2          A01X+044221Y+062905X0180Y0200R090 S2      
327PMBUS2_EN        U126  -G          A01X+043468Y+062748X0400Y0500R090 S2      
327GND              U107  -S          A01X+044014Y+061987X0400Y0500R180 S2      
327NNAME10798       U107  -G          A01X+044814Y+061987X0400Y0500R180 S2      
327N52410978        U108  -G          A01X+043432Y+061987X0400Y0500R180 S2      
317GND              VIA   -     D0100PA00X+044014Y+061581               S3      
317NNAME10798       VIA   -     D0100PA00X+044846Y+062596               S1      
317PMBUS2_EN        VIA   -     D0100PA00X+044560Y+062905               S3      
327P5V_NODE1        R1283 -1          A01X+044221Y+063220X0180Y0200R090 S2      
327I2C_PDB_SCL      R683  -2          A01X+043964Y+064284X0180Y0200     S2      
327I2C_COM3_SCL     R683  -1          A01X+044279Y+064284X0180Y0200     S2      
327NNAME10819       U126  -S          A01X+043468Y+063548X0400Y0500R090 S2      
317GND              VIA   -     D0100PA00X+043387Y+064512               S3      
317GND              VIA   -     D0100PA00X+044698Y+063877               S3      
317I2C_PSU2_SCL     VIA   -     D0100PA00X+043710Y+064379               S3      
317I2C_COM3_SDA     VIA   -     D0100PA00X+044650Y+064508               S3      
317P5V_NODE1        VIA   -     D0100PA00X+044385Y+063475               S3      
317P3V3_STB_NODE1   VIA   -     D0100PA00X+043925Y+063097               S3      
317NNAME10819       VIA   -     D0100PA00X+043468Y+064264               S3      
327P3V3_NODE1       R673  -2          A01X+043886Y+065560X0180Y0200     S2      
327UART3_RESET_N    R673  -1          A01X+044201Y+065560X0180Y0200     S2      
327PCA9535_INT_N    R677  -2          A01X+044201Y+065160X0180Y0200R180 S2      
327P3V3_NODE1       R677  -1          A01X+043886Y+065160X0180Y0200R180 S2      
327I2C_PDB_SDA      R681  -2          A01X+043964Y+064687X0180Y0200     S2      
327I2C_COM3_SDA     R681  -1          A01X+044279Y+064687X0180Y0200     S2      
317I2C_PDB_SCL      VIA   -     D0100PA00X+043542Y+064712               S3      
317I2C_PDB_SDA      VIA   -     D0100PA00X+043751Y+064900               S1      
317GND              VIA   -     D0100PA00X+044680Y+065753               S3      
317P3V3_NODE1       VIA   -     D0100PA00X+043597Y+065560               S3      
317PCA9535_INT_N    VIA   -     D0100PA00X+044470Y+065190               S1      
317NNAME10828       VIA   -     D0100PA00X+044527Y+066083               S3      
327NNAME10819       R667  -2          A01X+044202Y+066763X0180Y0200R180 S2      
327P3V3_NODE1       R667  -1          A01X+043887Y+066763X0180Y0200R180 S2      
327NNAME10829       R666  -2          A01X+044202Y+067163X0180Y0200R180 S2      
327P3V3_NODE1       R666  -1          A01X+043887Y+067163X0180Y0200R180 S2      
327I2C_COM3_SDA     R664  -2          A01X+044202Y+067563X0180Y0200R180 S2      
327P3V3_NODE1       R664  -1          A01X+043887Y+067563X0180Y0200R180 S2      
317GND              VIA   -     D0100PA00X+044440Y+066596               S3      
317I2C_PSU2_SCL     VIA   -     D0100PA00X+044721Y+066514               S1      
317P3V3_NODE1       VIA   -     D0100PA00X+043600Y+067571               S3      
317P3V3_NODE1       VIA   -     D0100PA00X+043554Y+067163               S3      
317P3V3_NODE1       VIA   -     D0100PA00X+043645Y+066763               S3      
317NNAME10830       VIA   -     D0100PA00X+044716Y+067356               S1      
317NNAME10819       VIA   -     D0100PA00X+044446Y+066935               S1      
327T5_NODE1_EN      U64   -4          A10X+044694Y+069126X0140Y0590R270 S1      
327N21699716        U64   -3          A10X+044694Y+068870X0140Y0590R270 S1      
327N21699716        U64   -2          A10X+044694Y+068614X0140Y0590R270 S1      
327N21699571        U64   -1          A10X+044694Y+068358X0140Y0590R270 S1      
327P5V_NODE1        R710  -2          A10X+043327Y+068716X0180Y0200R180 S1      
327T5_NODE1_EN      R710  -1          A10X+043642Y+068716X0180Y0200R180 S1      
327N21699571        R702  -2          A10X+043642Y+067916X0180Y0200     S1      
327P3V3_NODE1       R702  -1          A10X+043327Y+067916X0180Y0200     S1      
327I2C_COM3_SCL     R663  -2          A01X+044202Y+067963X0180Y0200R180 S2      
327P3V3_NODE1       R663  -1          A01X+043887Y+067963X0180Y0200R180 S2      
327GND              R718  -2          A10X+043327Y+068316X0180Y0200R180 S1      
327N21699716        R718  -1          A10X+043642Y+068316X0180Y0200R180 S1      
327P5V_NODE1        R711  -2          A10X+043327Y+069116X0180Y0200R180 S1      
327T5_NODE2_EN      R711  -1          A10X+043642Y+069116X0180Y0200R180 S1      
317N21699716        VIA   -     D0100PA00X+044069Y+068444               S1      
327N21699571        VIA   -           A10X+044292Y+067810X0260Y0260     S1      
317T5_NODE1_EN      VIA   -     D0100PA00X+044069Y+068944               S1      
327T6_NODE3_EN      U64   -10         A10X+044694Y+070661X0140Y0590R270 S1      
327T6_NODE2_EN      U64   -9          A10X+044694Y+070405X0140Y0590R270 S1      
327T6_NODE1_EN      U64   -8          A10X+044694Y+070150X0140Y0590R270 S1      
327T5_NODE4_EN      U64   -7          A10X+044694Y+069894X0140Y0590R270 S1      
327T5_NODE3_EN      U64   -6          A10X+044694Y+069638X0140Y0590R270 S1      
327T5_NODE2_EN      U64   -5          A10X+044694Y+069382X0140Y0590R270 S1      
327N31348569        D24   -C          A01X+044744Y+070320X0320Y0320R270 S2      
327P5V_NODE1        R715  -2          A10X+043327Y+070716X0180Y0200R180 S1      
327T6_NODE2_EN      R715  -1          A10X+043642Y+070716X0180Y0200R180 S1      
327P5V_NODE1        R714  -2          A10X+043327Y+070316X0180Y0200R180 S1      
327T6_NODE1_EN      R714  -1          A10X+043642Y+070316X0180Y0200R180 S1      
327P5V_NODE1        R713  -2          A10X+043327Y+069916X0180Y0200R180 S1      
327T5_NODE4_EN      R713  -1          A10X+043642Y+069916X0180Y0200R180 S1      
327P5V_NODE1        R712  -2          A10X+043327Y+069516X0180Y0200R180 S1      
327T5_NODE3_EN      R712  -1          A10X+043642Y+069516X0180Y0200R180 S1      
327N31348569        VIA   -           A01X+044744Y+069690X0300Y0300     S2      
317T6_NODE1_EN      VIA   -     D0100PA00X+044069Y+070239               S1      
317T5_NODE2_EN      VIA   -     D0100PA00X+044069Y+069444               S1      
327GND              U64   -12         A10X+044694Y+071173X0140Y0590R270 S1      
327T6_NODE4_EN      U64   -11         A10X+044694Y+070917X0140Y0590R270 S1      
327UART_SW_S5_N     D24   -A          A01X+044744Y+070911X0320Y0320R270 S2      
327P5V_NODE1        R716  -2          A10X+043327Y+071116X0180Y0200R180 S1      
327T6_NODE3_EN      R716  -1          A10X+043642Y+071116X0180Y0200R180 S1      
327P5V_NODE1        R717  -2          A10X+043327Y+071516X0180Y0200R180 S1      
327T6_NODE4_EN      R717  -1          A10X+043642Y+071516X0180Y0200R180 S1      
327NNAME10823       R970  -2          A10X+043428Y+071913X0180Y0200R180 S1      
327NNAME10831       R970  -1          A10X+043743Y+071913X0180Y0200R180 S1      
317GND              VIA   -     D0100PA00X+044690Y+071465               S3      
317I2C_PSU2_SCL     VIA   -     D0100PA00X+044265Y+071949               S3      
317NNAME10821       VIA   -     D0100PA00X+044626Y+072201               S3      
317NNAME10832       VIA   -     D0100PA00X+044453Y+072392               S3      
317T6_NODE4_EN      VIA   -     D0100PA00X+044066Y+071207               S1      
317NNAME10833       VIA   -     D0100PA00X+043920Y+072209               S3      
327GND              C724  -2          A10X+044544Y+072758X0180Y0200R270 S1      
327NNAME10834       C724  -1          A10X+044544Y+073073X0180Y0200R270 S1      
327GND              C733  -2          A10X+043594Y+073908X0180Y0200R270 S1      
327GND              C730  -2          A10X+043644Y+072758X0180Y0200R270 S1      
327NNAME10833       C730  -1          A10X+043644Y+073073X0180Y0200R270 S1      
327GND              C727  -2          A10X+044494Y+073908X0180Y0200R270 S1      
327GND              C763  -2          A01X+044394Y+073908X0180Y0200R090 S2      
327GND              C760  -2          A01X+044844Y+072758X0180Y0200R090 S2      
327NNAME10835       C760  -1          A01X+044844Y+073073X0180Y0200R090 S2      
327GND              C647  -2          A01X+043994Y+073908X0180Y0200R090 S2      
327GND              C650  -2          A01X+043544Y+073908X0180Y0200R090 S2      
327NNAME10833       R967  -1          A10X+044044Y+073908X0180Y0200R090 S1      
327NNAME10836       R964  -2          A10X+044094Y+073073X0180Y0200R090 S1      
327NNAME10837       R964  -1          A10X+044094Y+072758X0180Y0200R090 S1      
327NNAME10835       R997  -1          A01X+044844Y+073908X0180Y0200R270 S2      
327T6_NODE2_EN_R    R887  -2          A01X+043544Y+073073X0180Y0200R270 S2      
327T6_NODE2_EN      R887  -1          A01X+043544Y+072758X0180Y0200R270 S2      
327T6_NODE1_EN_R    R884  -2          A01X+043994Y+073073X0180Y0200R270 S2      
327T6_NODE1_EN      R884  -1          A01X+043994Y+072758X0180Y0200R270 S2      
317GND              VIA   -     D0100PA00X+044724Y+072478               S3      
317GND              VIA   -     D0100PA00X+043994Y+073551               S3      
317GND              VIA   -     D0100PA00X+044394Y+073568               S3      
317GND              VIA   -     D0100PA00X+043544Y+073593               S3      
317GND              VIA   -     D0100PA00X+043644Y+072471               S3      
317NNAME10837       VIA   -     D0100PA00X+044212Y+072478               S3      
317NNAME10834       VIA   -     D0100PA00X+044768Y+073356               S3      
327NNAME10823       C733  -1          A10X+043594Y+074223X0180Y0200R270 S1      
327NNAME10836       C727  -1          A10X+044494Y+074223X0180Y0200R270 S1      
327NNAME10832       C763  -1          A01X+044394Y+074223X0180Y0200R090 S2      
327T6_NODE1_EN_R    C647  -1          A01X+043994Y+074223X0180Y0200R090 S2      
327T6_NODE2_EN_R    C650  -1          A01X+043544Y+074223X0180Y0200R090 S2      
327NNAME10838       R967  -2          A10X+044044Y+074223X0180Y0200R090 S1      
327NNAME10839       R997  -2          A01X+044844Y+074223X0180Y0200R270 S2      
327NNAME10823       VIA   -           A10X+043656Y+077090X0260Y0260     S1      
317NNAME10839       VIA   -     D0100PA00X+044437Y+077015               S1      
317T6_NODE1_EN_R    VIA   -     D0100PA00X+043454Y+077850               S1      
327NNAME10838       VIA   -           A10X+044210Y+077762X0260Y0260     S1      
327NNAME10836       VIA   -           A10X+044651Y+078489X0260Y0260     S1      
317NNAME10832       VIA   -     D0100PA00X+044101Y+078530               S1      
327NNAME10838       J18   -A75        A10X+043707Y+080787X0300Y1660R180 S1      
327GND              J18   -A74        A10X+044101Y+080787X0300Y1660R180 S1      
327NNAME10836       J18   -A73        A10X+044494Y+080787X0300Y1660R180 S1      
327NNAME10840       J18   -A72        A10X+044888Y+080787X0300Y1660R180 S1      
327GND              J18   -B75        A01X+043707Y+080787X0300Y1660R180 S2      
327NNAME10832       J18   -B74        A01X+044101Y+080787X0300Y1660R180 S2      
327NNAME10839       J18   -B73        A01X+044494Y+080787X0300Y1660R180 S2      
327NNAME10841       J18   -B72        A01X+044888Y+080787X0300Y1660R180 S2      
317GND              VIA   -     D0100PA00X+044101Y+079148               S3      
317GND              VIA   -     D0100PA00X+043707Y+079148               S3      
317NNAME10503       VIA   -     D0100PA00X+045812Y+004472               S1      
317NNAME10051       VIA   -     D0100PA00X+046417Y+005644               S1      
327P3V3_STB_NODE1   C856  -1          A01X+046162Y+007500X0180Y0200R180 S2      
327GND              C198  -2          A01X+045068Y+007169X0180Y0200R090 S2      
327NNAME10842       C198  -1          A01X+045068Y+007484X0180Y0200R090 S2      
327NNAME10843       R1126 -2          A01X+045458Y+007477X0180Y0200     S2      
327P3V3_STB_NODE1   R1126 -1          A01X+045773Y+007477X0180Y0200     S2      
327NNAME10842       R1242 -2          A01X+045443Y+006919X0180Y0200     S2      
327GND              R1242 -1          A01X+045758Y+006919X0180Y0200     S2      
317GND              VIA   -     D0100PA00X+045062Y+006900               S3      
317GND              VIA   -     D0100PA00X+045758Y+006638               S3      
317GND              VIA   -     D0100PA00X+045426Y+007768               S3      
317P3V3_STB_NODE1   VIA   -     D0100PA00X+045860Y+007797               S3      
327P3V3_STB_NODE1   U123  -10         A01X+045820Y+008171X0110Y0360R180 S2      
327NNAME10824       U123  -6          A01X+045033Y+008171X0110Y0360     S2      
327NNAME10825       U123  -5          A01X+045033Y+009392X0110Y0360     S2      
327NNAME10844       U123  -1          A01X+045820Y+009392X0110Y0360R180 S2      
327NNAME10843       U123  -9          A01X+045623Y+008171X0110Y0360R180 S2      
327GND              U123  -8          A01X+045426Y+008171X0110Y0360R180 S2      
327NNAME10842       U123  -7          A01X+045229Y+008171X0110Y0360R180 S2      
327GND              U123  -4          A01X+045229Y+009392X0110Y0360R180 S2      
327NNAME10770       U123  -3          A01X+045426Y+009392X0110Y0360R180 S2      
327PV_VDDR_NODE1    U123  -2          A01X+045623Y+009392X0110Y0360R180 S2      
327GND              U123  -TH         A01X+045426Y+008782X0690Y1280R270 S2      
317GND              VIA   -     D0100PA00X+046229Y+008776               S3      
317GND              VIA   -     D0100PA00X+046229Y+008526               S3      
317GND              VIA   -     D0100PA00X+046229Y+009026               S3      
317P3V3_STB_NODE1   VIA   -     D0100PA00X+046152Y+007828               S3      
327PV_VDDR_NODE1    C854  -1          A01X+045917Y+011035X0440Y0540R270 S2      
327NNAME10770       C857  -1          A01X+045140Y+011043X0440Y0540R270 S2      
327NNAME10844       R1124 -2          A01X+046179Y+010274X0180Y0200R180 S2      
327PV_VDDR_NODE1    R1124 -1          A01X+045864Y+010274X0180Y0200R180 S2      
317GND              VIA   -     D0100PA00X+045092Y+009757               S3      
317NNAME10844       VIA   -     D0100PA00X+046159Y+009934               S1      
317NNAME10770       VIA   -     D0100PA00X+044954Y+010514               S1      
317NNAME10770       VIA   -     D0100PA00X+045317Y+010514               S3      
317NNAME10770       VIA   -     D0100PA00X+045394Y+009859               S1      
317PV_VDDR_NODE1    VIA   -     D0100PA00X+046041Y+010570               S3      
317PV_VDDR_NODE1    VIA   -     D0100PA00X+045791Y+010570               S3      
317PV_VDDR_NODE1    VIA   -     D0100PA00X+046291Y+010570               S3      
327GND              C854  -2          A01X+045917Y+011783X0440Y0540R270 S2      
327GND              C857  -2          A01X+045140Y+011791X0440Y0540R270 S2      
317GND              VIA   -     D0100PA00X+045330Y+012225               S3      
317GND              VIA   -     D0100PA00X+045080Y+012225               S3      
317GND              VIA   -     D0100PA00X+045216Y+012458               S3      
317GND              VIA   -     D0100PA00X+045882Y+012207               S3      
317GND              VIA   -     D0100PA00X+045882Y+012542               S3      
327OSC1_48MHZ       OSC4  -3          A01X+046192Y+015714X0440Y0560     S2      
317CLK_48M_SIO      VIA   -     D0100PA00X+046188Y+015060               S1      
317GND              VIA   -     D0100PA00X+045529Y+016280               S3      
317GND              VIA   -     D0100PA00X+045547Y+016696               S3      
317GND              VIA   -     D0100PA00X+045267Y+015714               S3      
327N46114787        OSC4  -4          A01X+046192Y+017714X0440Y0560     S2      
327P3V3_NODE1       L20   -1          A01X+045739Y+018721X0280Y0320R270 S2      
327N46114787        L20   -2          A01X+046319Y+018721X0280Y0320R270 S2      
327P3V3_NODE1       R619  -1          A01X+045018Y+018444X0180Y0200     S2      
317GND              VIA   -     D0100PA00X+045591Y+017870               S3      
317P3V3_NODE1       VIA   -     D0100PA00X+045476Y+018350               S3      
317P3V3_NODE1       VIA   -     D0100PA00X+045334Y+018567               S3      
317P3V3_NODE1       VIA   -     D0100PA00X+045748Y+018352               S3      
317N46114787        VIA   -     D0100PA00X+046279Y+018349               S1      
327GND              C484  -2          A01X+045212Y+019182X0180Y0200R270 S2      
327P3V3_NODE1       C484  -1          A01X+045212Y+018867X0180Y0200R270 S2      
327P3V3_NODE1       R1289 -2          A10X+045900Y+020293X0180Y0200R270 S1      
317GND              VIA   -     D0100PA00X+045212Y+019506               S3      
317P3V3_NODE1       VIA   -     D0100PA00X+045900Y+020050               S3      
317NNAME10561       VIA   -     D0100PA00X+045065Y+020379               S1      
327NNAME10845       R1289 -1          A10X+045900Y+020608X0180Y0200R270 S1      
317GND              VIA   -     D0100PA00X+045058Y+023443               S1      
327GND              C183  -2          A01X+045091Y+024940X0180Y0200R180 S2      
327P3V3_STB_NODE1   R223  -2          A01X+046035Y+024970X0180Y0200R180 S2      
327NNAME10800       R223  -1          A01X+045720Y+024970X0180Y0200R180 S2      
327P1V05_NODE1      R228  -2          A01X+045058Y+024516X0180Y0200R180 S2      
327GND              R229  -1          A01X+045058Y+024116X0180Y0200     S2      
327GND              R225  -2          A01X+045058Y+023716X0180Y0200R180 S2      
317GND              VIA   -     D0100PA00X+045415Y+024905               S3      
317P1V05_NODE1      VIA   -     D0100PA00X+045362Y+024516               S1      
317P3V3_STB_NODE1   VIA   -     D0100PA00X+045999Y+024593               S3      
327GND              C197  -1          A01X+045398Y+026229X0280Y0320R090 S2      
327NNAME10801       R221  -2          A01X+045018Y+025750X0180Y0200     S2      
327P1V05_NODE1      R221  -1          A01X+045333Y+025750X0180Y0200     S2      
317GND              VIA   -     D0100PA00X+045717Y+026237               S3      
317P1V05_NODE1      VIA   -     D0100PA00X+045680Y+025923               S3      
317NNAME10800       VIA   -     D0100PA00X+045911Y+025318               S3      
317NNAME10802       VIA   -     D0100PA00X+044986Y+026712               S3      
317NNAME10319       VIA   -     D0100PA00X+045653Y+025603               S3      
317GND              VIA   -     D0100PA00X+044929Y+027623               S3      
317NNAME10803       VIA   -     D0100PA00X+044986Y+027212               S3      
317P3V3_RTC_NODE1   VIA   -     D0100PA00X+045290Y+028165               S3      
317GND              VIA   -     D0100PA00X+045378Y+029241               S3      
317NNAME10772       VIA   -     D0100PA00X+045381Y+028933               S3      
317NNAME10775       VIA   -     D0100PA00X+045179Y+030013               S1      
317GND              VIA   -     D0100PA00X+046113Y+040832               S3      
317P1V8_NODE1       VIA   -     D0100PA00X+044897Y+040385               S3      
317P1V8_NODE1       VIA   -     D0100PA00X+045195Y+040243               S3      
327GND              PC118 -1          A10X+045532Y+042463X0440Y0540R180 S1      
327GND              PC100 -2          A01X+046476Y+041871X0950Y1110     S2      
317GND              VIA   -     D0100PA00X+046108Y+041145               S3      
327GND              PC121 -1          A10X+045532Y+043280X0440Y0540R180 S1      
327GND              PC99  -2          A01X+046476Y+043871X0950Y1110     S2      
317GND              VIA   -     D0100PA00X+046369Y+045181               S3      
317GND              VIA   -     D0100PA00X+046159Y+044670               S3      
317GND              VIA   -     D0100PA00X+046154Y+044983               S3      
327GND              PC90  -2          A10X+045096Y+048631X0180Y0200R270 S1      
327GND              PC89  -2          A01X+045094Y+048626X0180Y0200R090 S2      
327GND              PC92  -2          A10X+045696Y+047962X0460Y0620R270 S1      
327GND              PC93  -2          A10X+046529Y+047962X0460Y0620R270 S1      
327GND              PC94  -2          A01X+045699Y+047962X0460Y0620R090 S2      
327GND              PC91  -2          A01X+046526Y+047962X0460Y0620R090 S2      
317GND              VIA   -     D0100PA00X+045770Y+047548               S3      
317GND              VIA   -     D0100PA00X+046070Y+047548               S3      
317GND              VIA   -     D0100PA00X+045470Y+047548               S3      
317GND              VIA   -     D0100PA00X+046370Y+047548               S3      
317GND              VIA   -     D0100PA00X+045090Y+048345               S3      
327NNAME10826       PC90  -1          A10X+045096Y+048946X0180Y0200R270 S1      
327NNAME10826       PC89  -1          A01X+045094Y+048941X0180Y0200R090 S2      
327NNAME10826       PC92  -1          A10X+045696Y+049122X0460Y0620R270 S1      
327NNAME10826       PC93  -1          A10X+046529Y+049122X0460Y0620R270 S1      
327NNAME10826       PC94  -1          A01X+045699Y+049122X0460Y0620R090 S2      
327NNAME10826       PC91  -1          A01X+046526Y+049122X0460Y0620R090 S2      
327NNAME10826       PR49  -1          A01X+046234Y+049966X0460Y0620R270 S2      
317NNAME10826       VIA   -     D0100PA00X+046354Y+049572               S3      
317NNAME10826       VIA   -     D0100PA00X+045754Y+049555               S3      
317NNAME10826       VIA   -     D0100PA00X+045477Y+049559               S3      
317NNAME10826       VIA   -     D0100PA00X+045081Y+049299               S3      
327NNAME10811       PC98  -1          A01X+045464Y+051802X0280Y0320     S2      
327NNAME10777       PR59  -2          A01X+045605Y+051341X0180Y0200R180 S2      
327NNAME10778       PR59  -1          A01X+045290Y+051341X0180Y0200R180 S2      
327P12V_AUX         PR49  -2          A01X+046234Y+051126X0460Y0620R270 S2      
317P12V_AUX         VIA   -     D0100PA00X+046357Y+051572               S3      
317NNAME10778       VIA   -     D0100PA00X+045290Y+051006               S3      
317NNAME10804       VIA   -     D0100PA00X+044940Y+051551               S3      
327NNAME10846       PC102 -2          A01X+045284Y+053236X0180Y0200R180 S2      
327NNAME10810       PC102 -1          A01X+044969Y+053236X0180Y0200R180 S2      
327NNAME10777       PC98  -2          A01X+045464Y+052382X0280Y0320     S2      
327NNAME10847       PR69  -2          A01X+046072Y+053235X0180Y0200R090 S2      
327NNAME10846       PR66  -1          A01X+045672Y+053235X0180Y0200R270 S2      
317NNAME10810       VIA   -     D0100PA00X+045150Y+052973               S1      
317NNAME10811       VIA   -     D0100PA00X+045054Y+052133               S1      
317NNAME10847       VIA   -     D0100PA00X+046399Y+053150               S1      
317NNAME10777       VIA   -     D0100PA00X+045133Y+052598               S3      
317NNAME10846       VIA   -     D0100PA00X+045672Y+052954               S1      
327NNAME10848       PC109 -2          A01X+045037Y+054644X0180Y0200R270 S2      
327NNAME10808       PC109 -1          A01X+045037Y+054329X0180Y0200R270 S2      
327NNAME10809       PC110 -2          A01X+044969Y+053809X0180Y0200     S2      
327NNAME10785       PC110 -1          A01X+045284Y+053809X0180Y0200     S2      
327NNAME10848       PC103 -2          A01X+045669Y+054356X0180Y0200     S2      
327NNAME10849       PC103 -1          A01X+045984Y+054356X0180Y0200     S2      
327NNAME10809       PR69  -1          A01X+046072Y+053550X0180Y0200R090 S2      
327NNAME10809       PR66  -2          A01X+045672Y+053550X0180Y0200R270 S2      
327NNAME10849       PR67  -2          A01X+045979Y+053944X0180Y0200R180 S2      
327NNAME10809       PR67  -1          A01X+045664Y+053944X0180Y0200R180 S2      
327NNAME10848       PJ14  -1          A01X+045699Y+054773X0280Y0740R180 S2      
317NNAME10785       VIA   -     D0100PA00X+045402Y+054105               S3      
317NNAME10849       VIA   -     D0100PA00X+046303Y+054356               S1      
317NNAME10400       VIA   -     D0100PA00X+045392Y+055007               S1      
317NNAME10808       VIA   -     D0100PA00X+045037Y+054072               S1      
317NNAME10848       VIA   -     D0100PA00X+045370Y+054505               S1      
327NNAME10402       PC104 -2          A01X+045079Y+055352X0180Y0200R270 S2      
327NNAME10400       PC104 -1          A01X+045079Y+055037X0180Y0200R270 S2      
327PV_VCCP_NODE1    PR63  -2          A01X+046159Y+055046X0180Y0200R090 S2      
327NNAME10402       PR63  -1          A01X+046159Y+055361X0180Y0200R090 S2      
327NNAME10402       PJ14  -2          A01X+045699Y+055363X0280Y0320     S2      
317NNAME10402       VIA   -     D0100PA00X+045385Y+055507               S1      
327GND              R1038 -1          A01X+046335Y+058168X0180Y0200R180 S2      
317GND              VIA   -     D0100PA00X+046024Y+058168               S3      
327N52998325        R1249 -2          A01X+046387Y+058757X0440Y0540R180 S2      
327P12V_AUX         R1249 -1          A01X+045639Y+058757X0440Y0540R180 S2      
327N52998343        U111  -D          A01X+046517Y+059526X0400Y0500R180 S2      
317P12V_AUX         VIA   -     D0100PA00X+045589Y+059279               S3      
317NNAME10063       VIA   -     D0100PA00X+045078Y+058311               S3      
327GND              C887  -1          A01X+045378Y+060452X0280Y0320R090 S2      
327N52998261        U110  -D          A01X+045794Y+061107X0400Y0500R180 S2      
327GND              U111  -S          A01X+046117Y+060406X0400Y0500R180 S2      
317GND              VIA   -     D0100PA00X+045860Y+059920               S3      
317GND              VIA   -     D0100PA00X+045378Y+060061               S3      
317N52998261        VIA   -     D0100PA00X+046227Y+061291               S1      
327GND              U110  -S          A01X+045394Y+061987X0400Y0500R180 S2      
327NNAME10768       U110  -G          A01X+046194Y+061987X0400Y0500R180 S2      
317GND              VIA   -     D0100PA00X+045394Y+062474               S3      
317NNAME10768       VIA   -     D0100PA00X+045969Y+062642               S3      
327I2C_COM3_SCL     U61   -8          A01X+045184Y+063920X0140Y0590R270 S2      
327NNAME10850       U61   -7          A01X+045184Y+064176X0140Y0590R270 S2      
327PCA9535_INT_N    U61   -6          A01X+045184Y+064432X0140Y0590R270 S2      
327NNAME10850       C590  -2          A10X+045437Y+063879X0180Y0200     S1      
327GND              C590  -1          A10X+045122Y+063879X0180Y0200     S1      
327I2C_COM3_SDA     R795  -2          A10X+045123Y+064269X0180Y0200R180 S1      
327NNAME10850       R795  -1          A10X+045438Y+064269X0180Y0200R180 S1      
317I2C_PSU2_SDA     VIA   -     D0100PA00X+046405Y+063388               S1      
317NNAME10850       VIA   -     D0100PA00X+045890Y+064488               S1      
327PSU3_HUB_EN      U61   -5          A01X+045184Y+064688X0140Y0590R270 S2      
327GND              U61   -4          A01X+045184Y+064944X0140Y0590R270 S2      
327UART3_RESET_N    U61   -3          A01X+045184Y+065200X0140Y0590R270 S2      
327PSU2_HUB_EN      U61   -2          A01X+045184Y+065455X0140Y0590R270 S2      
327PSU1_HUB_EN      U61   -1          A01X+045184Y+065711X0140Y0590R270 S2      
327PSU3_HUB_EN      R1245 -2          A10X+045894Y+065520X0180Y0200R090 S1      
327GND              R1245 -1          A10X+045894Y+065205X0180Y0200R090 S1      
327PSU1_HUB_EN      R1243 -2          A10X+045323Y+065740X0180Y0200     S1      
327GND              R1243 -1          A10X+045008Y+065740X0180Y0200     S1      
327I2C_COM3_SCL     R773  -2          A10X+045324Y+064758X0180Y0200R270 S1      
327NNAME10755       R773  -1          A10X+045324Y+065073X0180Y0200R270 S1      
327I2C_COM3_SDA     R774  -2          A10X+044918Y+064760X0180Y0200R270 S1      
327NNAME10794       R774  -1          A10X+044918Y+065075X0180Y0200R270 S1      
317GND              VIA   -     D0100PA00X+045634Y+064944               S3      
317PSU3_HUB_EN      VIA   -     D0100PA00X+046200Y+065451               S3      
317I2C_COM3_SCL     VIA   -     D0100PA00X+046318Y+064748               S1      
327GND              U60   -8          A01X+045184Y+066170X0140Y0590R270 S2      
327NNAME10828       U60   -7          A01X+045184Y+066426X0140Y0590R270 S2      
327NNAME10819       U60   -6          A01X+045184Y+066682X0140Y0590R270 S2      
327PSU1_HUB_EN      U60   -5          A01X+045184Y+066938X0140Y0590R270 S2      
327NNAME10829       U60   -4          A01X+045184Y+067194X0140Y0590R270 S2      
327NNAME10830       U60   -3          A01X+045184Y+067450X0140Y0590R270 S2      
317GND              VIA   -     D0100PA00X+045865Y+066654               S3      
317PSU3_HUB_EN      VIA   -     D0100PA00X+046059Y+066942               S1      
317PSU1_HUB_EN      VIA   -     D0100PA00X+045714Y+066325               S1      
317I2C_PSU1_SCL     VIA   -     D0100PA00X+046302Y+066102               S3      
317I2C_PSU1_SDA     VIA   -     D0100PA00X+046433Y+066325               S3      
317NNAME10829       VIA   -     D0100PA00X+045882Y+067414               S3      
327I2C_COM3_SDA     U60   -2          A01X+045184Y+067705X0140Y0590R270 S2      
327I2C_COM3_SCL     U60   -1          A01X+045184Y+067961X0140Y0590R270 S2      
327GND              R1058 -2          A01X+045194Y+068908X0180Y0200R090 S2      
327GND              R805  -2          A01X+046144Y+068908X0180Y0200R090 S2      
327GND              R1048 -2          A01X+045644Y+068908X0180Y0200R090 S2      
317GND              VIA   -     D0100PA00X+046312Y+068199               S3      
317GND              VIA   -     D0100PA00X+046053Y+068187               S3      
317GND              VIA   -     D0100PA00X+045965Y+068599               S3      
317GND              VIA   -     D0100PA00X+045773Y+068201               S3      
317GND              VIA   -     D0100PA00X+045696Y+068558               S3      
317GND              VIA   -     D0100PA00X+046196Y+068439               S3      
327N31341801        D22   -C          A01X+045394Y+070320X0320Y0320R270 S2      
327N31341803        D23   -C          A01X+046094Y+070320X0320Y0320R270 S2      
327N31348569        R1058 -1          A01X+045194Y+069223X0180Y0200R090 S2      
327N31341803        R805  -1          A01X+046144Y+069223X0180Y0200R090 S2      
327N31341801        R1048 -1          A01X+045644Y+069223X0180Y0200R090 S2      
327N31341803        VIA   -           A01X+046124Y+069688X0300Y0300     S2      
327N31341801        VIA   -           A01X+045394Y+069745X0300Y0300     S2      
327UART_SW_S4_N     D22   -A          A01X+045394Y+070911X0320Y0320R270 S2      
327UART_SW_S3_N     D23   -A          A01X+046094Y+070911X0320Y0320R270 S2      
317NNAME10851       VIA   -     D0100PA00X+045995Y+072272               S3      
317NNAME10841       VIA   -     D0100PA00X+045396Y+072314               S3      
317NNAME10831       VIA   -     D0100PA00X+044906Y+072176               S1      
317NNAME10852       VIA   -     D0100PA00X+045706Y+072243               S3      
317UART_SW_S3_N     VIA   -     D0100PA00X+046082Y+071262               S3      
317UART_SW_S5_N     VIA   -     D0100PA00X+045182Y+071221               S3      
317UART_SW_S4_N     VIA   -     D0100PA00X+045407Y+071423               S3      
327GND              C644  -2          A10X+046244Y+073908X0180Y0200R270 S1      
327GND              C721  -2          A10X+045394Y+073908X0180Y0200R270 S1      
327GND              C718  -2          A10X+045444Y+072758X0180Y0200R270 S1      
327NNAME10853       C718  -1          A10X+045444Y+073073X0180Y0200R270 S1      
327GND              C757  -2          A01X+045294Y+073908X0180Y0200R090 S2      
327GND              C754  -2          A01X+045744Y+072758X0180Y0200R090 S2      
327NNAME10852       C754  -1          A01X+045744Y+073073X0180Y0200R090 S2      
327GND              C751  -2          A01X+046194Y+073908X0180Y0200R090 S2      
327T7_NODE4_EN_R    R881  -2          A10X+045844Y+073073X0180Y0200R090 S1      
327T7_NODE4_EN      R881  -1          A10X+045844Y+072758X0180Y0200R090 S1      
327T7_NODE3_EN_R    R878  -2          A10X+046244Y+073073X0180Y0200R090 S1      
327T7_NODE3_EN      R878  -1          A10X+046244Y+072758X0180Y0200R090 S1      
327NNAME10853       R955  -1          A10X+045844Y+073908X0180Y0200R090 S1      
327NNAME10854       R958  -2          A10X+044994Y+073073X0180Y0200R090 S1      
327NNAME10855       R958  -1          A10X+044994Y+072758X0180Y0200R090 S1      
327NNAME10834       R961  -1          A10X+044944Y+073908X0180Y0200R090 S1      
327NNAME10852       R991  -1          A01X+045744Y+073908X0180Y0200R270 S2      
317GND              VIA   -     D0100PA00X+045353Y+073621               S3      
317GND              VIA   -     D0100PA00X+045805Y+072505               S3      
317GND              VIA   -     D0100PA00X+046244Y+073569               S3      
317NNAME10853       VIA   -     D0100PA00X+045541Y+073411               S3      
317NNAME10835       VIA   -     D0100PA00X+045041Y+073368               S3      
317NNAME10855       VIA   -     D0100PA00X+045132Y+072504               S3      
327T7_NODE4_EN_R    C644  -1          A10X+046244Y+074223X0180Y0200R270 S1      
327NNAME10854       C721  -1          A10X+045394Y+074223X0180Y0200R270 S1      
327NNAME10841       C757  -1          A01X+045294Y+074223X0180Y0200R090 S2      
327NNAME10851       C751  -1          A01X+046194Y+074223X0180Y0200R090 S2      
327NNAME10856       R955  -2          A10X+045844Y+074223X0180Y0200R090 S1      
327NNAME10840       R961  -2          A10X+044944Y+074223X0180Y0200R090 S1      
327NNAME10857       R991  -2          A01X+045744Y+074223X0180Y0200R270 S2      
317NNAME10851       VIA   -     D0100PA00X+046157Y+078581               S1      
317NNAME10858       VIA   -     D0100PA00X+046375Y+078045               S1      
317NNAME10857       VIA   -     D0100PA00X+045412Y+078592               S1      
327NNAME10854       VIA   -           A10X+045440Y+077187X0260Y0260     S1      
327NNAME10856       VIA   -           A10X+045753Y+077902X0260Y0260     S1      
327NNAME10840       VIA   -           A10X+044961Y+077793X0260Y0260     S1      
327NNAME10854       J18   -A71        A10X+045282Y+080787X0300Y1660R180 S1      
327NNAME10856       J18   -A70        A10X+045675Y+080787X0300Y1660R180 S1      
327GND              J18   -A69        A10X+046069Y+080787X0300Y1660R180 S1      
327T7_NODE4_EN_R    J18   -A68        A10X+046463Y+080787X0300Y1660R180 S1      
327NNAME10857       J18   -B71        A01X+045282Y+080787X0300Y1660R180 S2      
327GND              J18   -B70        A01X+045675Y+080787X0300Y1660R180 S2      
327NNAME10851       J18   -B69        A01X+046069Y+080787X0300Y1660R180 S2      
327NNAME10858       J18   -B68        A01X+046463Y+080787X0300Y1660R180 S2      
317GND              VIA   -     D0100PA00X+046069Y+079148               S3      
317GND              VIA   -     D0100PA00X+045675Y+079148               S3      
317GND              H10   -1    D2130PA00X+048110Y+003453               S0      
317NNAME10074       VIA   -     D0100PA00X+047531Y+005975               S3      
327GND              C856  -2          A01X+046477Y+007500X0180Y0200R180 S2      
317GND              VIA   -     D0100PA00X+046477Y+007815               S3      
317UART_RX_P1_L     VIA   -     D0100PA00X+047503Y+006388               S1      
317NNAME10075       VIA   -     D0100PA00X+047945Y+006372               S3      
317GND              VIA   -     D0100PA00X+046665Y+009122               S3      
327GND              C855  -2          A01X+046763Y+009875X0180Y0200R180 S2      
327NNAME10844       C855  -1          A01X+046448Y+009875X0180Y0200R180 S2      
327SIO_VBAT         D6    -2          A01X+047837Y+010447X0320Y0340R270 S2      
327GND              R1125 -2          A01X+046763Y+009474X0180Y0200R180 S2      
327NNAME10844       R1125 -1          A01X+046448Y+009474X0180Y0200R180 S2      
317GND              VIA   -     D0100PA00X+046668Y+010241               S3      
327P3V3_RTC_NODE1   D6    -1          A01X+047837Y+011307X0320Y0340R090 S2      
317GND              VIA   -     D0100PA00X+047438Y+012531               S3      
317GND              VIA   -     D0100PA00X+047809Y+012522               S3      
327N/C              U43   -64         A01X+048209Y+012752X0110Y0710R270 S2      
327N/C              U43   -63         A01X+048209Y+012949X0110Y0710R270 S2      
327N/C              U43   -62         A01X+048209Y+013146X0110Y0710R270 S2      
327NNAME10859       U43   -61         A01X+048209Y+013342X0110Y0710R270 S2      
327N/C              U43   -60         A01X+048209Y+013539X0110Y0710R270 S2      
327NNAME10845       U43   -59         A01X+048209Y+013736X0110Y0710R270 S2      
327NNAME10860       U43   -58         A01X+048209Y+013933X0110Y0710R270 S2      
327GND              C488  -2          A10X+047896Y+013239X0440Y0540R180 S1      
327P3V3_NODE1       R1201 -2          A10X+047764Y+013936X0180Y0200R180 S1      
327P3V3_NODE1       R1291 -2          A10X+046900Y+013993X0180Y0200R270 S1      
317P3V3_NODE1       VIA   -     D0100PA00X+047150Y+013800               S3      
317NNAME10860       VIA   -     D0100PA00X+047320Y+014030               S3      
317NNAME10845       VIA   -     D0100PA00X+046840Y+013580               S3      
317NNAME10859       VIA   -     D0100PA00X+047032Y+013342               S1      
327NNAME10861       U43   -57         A01X+048209Y+014130X0110Y0710R270 S2      
327NNAME10862       U43   -56         A01X+048209Y+014327X0110Y0710R270 S2      
327N/C              U43   -55         A01X+048209Y+014524X0110Y0710R270 S2      
327NNAME10863       U43   -54         A01X+048209Y+014720X0110Y0710R270 S2      
327N/C              U43   -53         A01X+048209Y+014917X0110Y0710R270 S2      
327NNAME10864       U43   -52         A01X+048209Y+015114X0110Y0710R270 S2      
327SIO_PWROK2       U43   -51         A01X+048209Y+015311X0110Y0710R270 S2      
327GND              U43   -50         A01X+048209Y+015508X0110Y0710R270 S2      
327CLK_48M_SIO      R815  -1          A01X+047062Y+015409X0180Y0200R270 S2      
327P3V3_NODE1       R1202 -2          A10X+047764Y+014336X0180Y0200R180 S1      
327P3V3_NODE1       R1203 -2          A10X+047764Y+014736X0180Y0200R180 S1      
327P3V3_NODE1       R1204 -2          A10X+047764Y+015136X0180Y0200R180 S1      
327NNAME10860       R1291 -1          A10X+046900Y+014308X0180Y0200R270 S1      
327SIO_CLKIN        U43   -49         A01X+048209Y+015705X0110Y0710R270 S2      
327UART_RX_P5       U43   -48         A01X+048209Y+015902X0110Y0710R270 S2      
327SIO_PCICLK33     U43   -47         A01X+048209Y+016098X0110Y0710R270 S2      
327N/C              U43   -46         A01X+048209Y+016295X0110Y0710R270 S2      
327SIO_PIN45        U43   -45         A01X+048209Y+016492X0110Y0710R270 S2      
327NNAME10865       U43   -44         A01X+048209Y+016689X0110Y0710R270 S2      
327NNAME10866       U43   -43         A01X+048209Y+016886X0110Y0710R270 S2      
327NNAME10867       U43   -42         A01X+048209Y+017083X0110Y0710R270 S2      
327NNAME10421       R183  -1          A10X+047913Y+017211X0180Y0200     S1      
327NNAME10422       R185  -1          A10X+047913Y+016411X0180Y0200     S1      
327NNAME10419       R184  -1          A10X+047913Y+016811X0180Y0200     S1      
327SIO_PCICLK33     R625  -2          A01X+047057Y+016350X0180Y0200R180 S2      
327NNAME10561       R625  -1          A01X+046742Y+016350X0180Y0200R180 S2      
327SIO_CLKIN        R618  -2          A01X+047062Y+015724X0180Y0200R180 S2      
327OSC1_48MHZ       R618  -1          A01X+046747Y+015724X0180Y0200R180 S2      
327SIO_CLKIN        R815  -2          A01X+047062Y+015724X0180Y0200R270 S2      
317SIO_PCICLK33     VIA   -     D0100PA00X+047481Y+016222               S1      
317OSC1_48MHZ       VIA   -     D0100PA00X+046747Y+015977               S1      
317SIO_CLKIN        VIA   -     D0100PA00X+047395Y+015724               S1      
317NNAME10421       VIA   -     D0100PA00X+047395Y+017212               S1      
317NNAME10419       VIA   -     D0100PA00X+047576Y+016875               S3      
317NNAME10422       VIA   -     D0100PA00X+047267Y+016640               S3      
327NNAME10868       U43   -41         A01X+048209Y+017279X0110Y0710R270 S2      
327NNAME10869       U43   -40         A01X+048209Y+017476X0110Y0710R270 S2      
327NNAME10870       U43   -39         A01X+048209Y+017673X0110Y0710R270 S2      
327NNAME10870       R95   -2          A10X+047854Y+018038X0180Y0200     S1      
327NNAME10424       R95   -1          A10X+047539Y+018038X0180Y0200     S1      
327NNAME10423       R182  -1          A10X+047913Y+017611X0180Y0200     S1      
317NNAME10424       VIA   -     D0100PA00X+047358Y+017786               S3      
317NNAME10423       VIA   -     D0100PA00X+047463Y+017484               S3      
317CPLD123_RSV1     VIA   -     D0100PA00X+048022Y+018577               S3      
317NNAME10869       VIA   -     D0100PA00X+047577Y+018645               S1      
327NNAME10869       R181  -2          A01X+047122Y+019478X0180Y0200R090 S2      
327NNAME10559       R181  -1          A01X+047122Y+019793X0180Y0200R090 S2      
317NNAME10559       VIA   -     D0100PA00X+046845Y+019793               S3      
317NNAME10860       VIA   -     D0100PA00X+047130Y+020190               S1      
317NNAME10859       VIA   -     D0100PA00X+047640Y+020310               S3      
327P3V3_NODE1       R1288 -2          A10X+047800Y+021008X0180Y0200R090 S1      
327NNAME10859       R1288 -1          A10X+047800Y+020693X0180Y0200R090 S1      
317P3V3_NODE1       VIA   -     D0100PA00X+047800Y+021250               S3      
317NNAME10845       VIA   -     D0100PA00X+046620Y+020730               S1      
327P3V3_RTC_NODE1   U3    -3          A01X+047580Y+028167X0400Y0500     S2      
327NNAME10871       U3    -2          A01X+047980Y+027287X0400Y0500     S2      
327P3V3_STB_NODE1   U3    -1          A01X+047180Y+027287X0400Y0500     S2      
317P3V3_STB_NODE1   VIA   -     D0100PA00X+047180Y+026794               S3      
317NNAME10711       VIA   -     D0100PA00X+046481Y+031125               S1      
317NNAME10741       VIA   -     D0100PA00X+047009Y+033282               S3      
317NNAME10562       VIA   -     D0100PA00X+047519Y+033901               S3      
317GND              VIA   -     D0100PA00X+047414Y+040832               S3      
317GND              VIA   -     D0100PA00X+046959Y+040832               S3      
317GND              VIA   -     D0100PA00X+046533Y+040832               S3      
317GND              VIA   -     D0100PA00X+046821Y+040151               S3      
317NNAME10004       VIA   -     D0100PA00X+046591Y+040266               S3      
317NNAME10006       VIA   -     D0100PA00X+046588Y+039983               S3      
317GND              VIA   -     D0100PA00X+047408Y+041145               S3      
317GND              VIA   -     D0100PA00X+046953Y+041145               S3      
317GND              VIA   -     D0100PA00X+046527Y+041145               S3      
317GND              VIA   -     D0100PA00X+048005Y+041956               S3      
317GND              VIA   -     D0100PA00X+047154Y+043721               S3      
317GND              VIA   -     D0100PA00X+047314Y+043997               S3      
317GND              VIA   -     D0100PA00X+046950Y+044773               S3      
317GND              VIA   -     D0100PA00X+046792Y+045167               S3      
317GND              VIA   -     D0100PA00X+047221Y+045027               S3      
317GND              VIA   -     D0100PA00X+046573Y+044983               S3      
317GND              VIA   -     D0100PA00X+046579Y+044670               S3      
317GND              VIA   -     D0100PA00X+047958Y+046760               S3      
317GND              VIA   -     D0100PA00X+047975Y+046299               S3      
317GND              VIA   -     D0100PA00X+046670Y+047548               S3      
317NNAME10568       VIA   -     D0100PA00X+048012Y+047911               S1      
317NNAME10567       VIA   -     D0100PA00X+048012Y+047411               S1      
317NNAME10826       VIA   -     D0100PA00X+046631Y+049568               S3      
317P12V_AUX         VIA   -     D0100PA00X+046768Y+051006               S3      
317P12V_AUX         VIA   -     D0100PA00X+046750Y+051318               S3      
317P12V_AUX         VIA   -     D0100PA00X+046659Y+051576               S3      
317P12V_AUX         VIA   -     D0100PA00X+046759Y+050681               S3      
327NNAME10848       PR70  -2          A01X+046529Y+053799X0180Y0200R270 S2      
327NNAME10847       PR70  -1          A01X+046529Y+053484X0180Y0200R270 S2      
327NNAME10643       C187  -2          A10X+047639Y+055665X0180Y0200R180 S1      
327NNAME10872       C187  -1          A10X+047954Y+055665X0180Y0200R180 S1      
327NNAME10642       C188  -2          A10X+047639Y+056065X0180Y0200R180 S1      
327NNAME10873       C188  -1          A10X+047954Y+056065X0180Y0200R180 S1      
317GND              VIA   -     D0100PA00X+047413Y+055366               S3      
317GND              VIA   -     D0100PA00X+047429Y+056357               S3      
317NNAME10642       VIA   -     D0100PA00X+047180Y+056109               S1      
317NNAME10643       VIA   -     D0100PA00X+047180Y+055609               S1      
327NNAME10195       C186  -2          A10X+047639Y+056669X0180Y0200R180 S1      
327NNAME10874       C186  -1          A10X+047954Y+056669X0180Y0200R180 S1      
327NNAME10194       C185  -2          A10X+047639Y+057069X0180Y0200R180 S1      
327NNAME10875       C185  -1          A10X+047954Y+057069X0180Y0200R180 S1      
327NNAME10876       R1038 -2          A01X+046650Y+058168X0180Y0200R180 S2      
327NNAME10876       Q46   -3          A01X+047486Y+058140X0240Y0280R180 S2      
327NNAME10194       VIA   -           A10X+046788Y+056929X0160Y0050     S1      
327N52998343        R1250 -2          A01X+047841Y+059711X0180Y0200R270 S2      
327N52998345        R1250 -1          A01X+047841Y+059396X0180Y0200R270 S2      
327P12V_AUX         R1039 -2          A01X+047440Y+059396X0180Y0200R090 S2      
327N52998343        R1039 -1          A01X+047440Y+059711X0180Y0200R090 S2      
327N52998325        Q46   -2          A01X+047112Y+058927X0240Y0280R180 S2      
327N52998345        Q46   -1          A01X+047860Y+058927X0240Y0280R180 S2      
317P12V_AUX         VIA   -     D0100PA00X+047119Y+059396               S3      
317N52998325        VIA   -     D0100PA00X+046874Y+058590               S1      
317N52998343        VIA   -     D0100PA00X+046989Y+059658               S1      
327NNAME10829       R644  -2          A01X+047488Y+060748X0180Y0200R270 S2      
327I2C_PSU1_SDA     R644  -1          A01X+047488Y+060433X0180Y0200R270 S2      
327P3V3_STB_NODE1   R1059 -2          A01X+046999Y+061321X0180Y0200R180 S2      
327N52998261        R1059 -1          A01X+046684Y+061321X0180Y0200R180 S2      
327NNAME10829       U117  -S          A01X+047965Y+061283X0400Y0500R180 S2      
327N52998261        U111  -G          A01X+046917Y+060406X0400Y0500R180 S2      
317P3V3_STB_NODE1   VIA   -     D0100PA00X+047329Y+061321               S3      
327GND              C934  -1          A01X+047315Y+061788X0280Y0320R090 S2      
327N52998261        C934  -2          A01X+046735Y+061788X0280Y0320R090 S2      
327I2C_PSU2_SDA     R645  -1          A01X+047344Y+062638X0180Y0200R270 S2      
327NNAME10828       U118  -S          A01X+047983Y+062884X0400Y0500R180 S2      
317GND              VIA   -     D0100PA00X+047315Y+062245               S3      
317NNAME10828       VIA   -     D0100PA00X+047632Y+062928               S1      
327CMC_CPU_RST_N    U61   -11         A01X+047484Y+064432X0140Y0590R270 S2      
327UART_CMC_RX_P    U61   -10         A01X+047484Y+064176X0140Y0590R270 S2      
327UART_CMC_TX_P    U61   -9          A01X+047484Y+063920X0140Y0590R270 S2      
327NNAME10828       R645  -2          A01X+047344Y+062953X0180Y0200R270 S2      
327NNAME10828       R668  -2          A01X+046944Y+062994X0180Y0200R090 S2      
327P3V3_NODE1       R668  -1          A01X+046944Y+063309X0180Y0200R090 S2      
317P3V3_NODE1       VIA   -     D0100PA00X+046558Y+064142               S3      
317CMC_CPLD_RSV1    VIA   -     D0100PA00X+046923Y+063814               S1      
317NNAME10829       VIA   -     D0100PA00X+047582Y+063542               S1      
327CMC_CPLD_RSV1    U61   -16         A01X+047484Y+065711X0140Y0590R270 S2      
327FAN_MAX_CTRL     U61   -15         A01X+047484Y+065455X0140Y0590R270 S2      
327CPLD_WDT1_R      U61   -14         A01X+047484Y+065200X0140Y0590R270 S2      
327COM3_WAKEUP      U61   -13         A01X+047484Y+064944X0140Y0590R270 S2      
327P3V3_NODE1       U61   -12         A01X+047484Y+064688X0140Y0590R270 S2      
327GND              R1225 -2          A10X+047390Y+064965X0180Y0200R270 S1      
327FAN_MAX_CTRL     R1225 -1          A10X+047390Y+065280X0180Y0200R270 S1      
327P3V3_NODE1       R1211 -2          A10X+047637Y+065671X0180Y0200     S1      
327FAN_MAX_CTRL     R1211 -1          A10X+047322Y+065671X0180Y0200     S1      
317GND              VIA   -     D0100PA00X+047891Y+065943               S3      
317GND              VIA   -     D0100PA00X+047019Y+064869               S3      
317P3V3_NODE1       VIA   -     D0100PA00X+047495Y+065938               S3      
317FAN_MAX_CTRL     VIA   -     D0100PA00X+046881Y+065218               S1      
317COM3_WAKEUP      VIA   -     D0100PA00X+047951Y+064944               S1      
317CMC_CPU_RST_N    VIA   -     D0100PA00X+046854Y+065580               S3      
327PU_I2C_SDA4      U60   -14         A01X+047484Y+067450X0140Y0590R270 S2      
327PU_I2C_SCL4      U60   -13         A01X+047484Y+067194X0140Y0590R270 S2      
327PSU3_HUB_EN      U60   -12         A01X+047484Y+066938X0140Y0590R270 S2      
327NNAME10877       U60   -11         A01X+047484Y+066682X0140Y0590R270 S2      
327NNAME10878       U60   -10         A01X+047484Y+066426X0140Y0590R270 S2      
327PSU2_HUB_EN      U60   -9          A01X+047484Y+066170X0140Y0590R270 S2      
327PSU2_HUB_EN      R1244 -2          A10X+047336Y+066362X0180Y0200R180 S1      
327GND              R1244 -1          A10X+047651Y+066362X0180Y0200R180 S1      
317GND              VIA   -     D0100PA00X+047935Y+066867               S3      
317GND              VIA   -     D0100PA00X+046605Y+067533               S3      
317PSU2_HUB_EN      VIA   -     D0100PA00X+046698Y+066706               S1      
317I2C_COM3_SDA     VIA   -     D0100PA00X+046998Y+067650               S3      
317UART3_RESET_N    VIA   -     D0100PA00X+046826Y+066437               S3      
327P3V3_NODE1       U60   -16         A01X+047484Y+067961X0140Y0590R270 S2      
327N21699069        U60   -15         A01X+047484Y+067705X0140Y0590R270 S2      
327P3V3_NODE1       U64   -24         A10X+046994Y+068358X0140Y0590R270 S1      
327I2C_COM3_SDA     U64   -23         A10X+046994Y+068614X0140Y0590R270 S1      
327I2C_COM3_SCL     U64   -22         A10X+046994Y+068870X0140Y0590R270 S1      
327N21699372        U64   -21         A10X+046994Y+069126X0140Y0590R270 S1      
327GND              R798  -2          A01X+046594Y+068908X0180Y0200R090 S2      
327GND              R797  -2          A01X+047044Y+068908X0180Y0200R090 S2      
327GND              R796  -2          A01X+047494Y+068908X0180Y0200R090 S2      
317I2C_COM3_SCL     VIA   -     D0100PA00X+046947Y+067992               S3      
317P3V3_NODE1       VIA   -     D0100PA00X+047941Y+068231               S3      
317N21699069        VIA   -     D0100PA00X+047935Y+067705               S1      
327T8_NODE4_EN      U64   -20         A10X+046994Y+069382X0140Y0590R270 S1      
327T8_NODE3_EN      U64   -19         A10X+046994Y+069638X0140Y0590R270 S1      
327T8_NODE2_EN      U64   -18         A10X+046994Y+069894X0140Y0590R270 S1      
327T8_NODE1_EN      U64   -17         A10X+046994Y+070150X0140Y0590R270 S1      
327T7_NODE4_EN      U64   -16         A10X+046994Y+070405X0140Y0590R270 S1      
327T7_NODE3_EN      U64   -15         A10X+046994Y+070661X0140Y0590R270 S1      
327N31328107        D17   -C          A01X+046744Y+070320X0320Y0320R270 S2      
327N31328108        D16   -C          A01X+047394Y+070320X0320Y0320R270 S2      
327N31328106        D15   -C          A01X+048044Y+070320X0320Y0320R270 S2      
327N31328107        R798  -1          A01X+046594Y+069223X0180Y0200R090 S2      
327N31328108        R797  -1          A01X+047044Y+069223X0180Y0200R090 S2      
327N31328106        R796  -1          A01X+047494Y+069223X0180Y0200R090 S2      
327N31328106        VIA   -           A01X+047721Y+069692X0300Y0300     S2      
327N31328107        VIA   -           A01X+046668Y+069705X0300Y0300     S2      
327N31328108        VIA   -           A01X+047177Y+069689X0300Y0300     S2      
327T7_NODE2_EN      U64   -14         A10X+046994Y+070917X0140Y0590R270 S1      
327T7_NODE1_EN      U64   -13         A10X+046994Y+071173X0140Y0590R270 S1      
327UART_SW_S2_N     D17   -A          A01X+046744Y+070911X0320Y0320R270 S2      
327UART_SW_S1_N     D16   -A          A01X+047394Y+070911X0320Y0320R270 S2      
327UART_SW_S0_N     D15   -A          A01X+048044Y+070911X0320Y0320R270 S2      
317UART_SW_S0_N     VIA   -     D0100PA00X+047771Y+072230               S3      
317UART_SW_S2_N     VIA   -     D0100PA00X+046662Y+071414               S3      
317UART_SW_S1_N     VIA   -     D0100PA00X+047394Y+071418               S3      
327GND              C641  -2          A10X+046644Y+073908X0180Y0200R270 S1      
327GND              C638  -2          A10X+047044Y+073908X0180Y0200R270 S1      
327GND              C745  -2          A01X+047094Y+073908X0180Y0200R090 S2      
327NNAME10879       C742  -1          A01X+047494Y+073908X0180Y0200R270 S2      
327GND              C748  -2          A01X+046644Y+072758X0180Y0200R090 S2      
327NNAME10880       C748  -1          A01X+046644Y+073073X0180Y0200R090 S2      
327GND              C635  -2          A01X+047043Y+073075X0180Y0200R270 S2      
327T7_NODE1_EN_R    C635  -1          A01X+047043Y+072760X0180Y0200R270 S2      
327T7_NODE1_EN_R    R872  -2          A10X+047044Y+073073X0180Y0200R090 S1      
327T7_NODE1_EN      R872  -1          A10X+047044Y+072758X0180Y0200R090 S1      
327T8_NODE4_EN_R    R869  -2          A01X+047493Y+073075X0180Y0200R270 S2      
327T8_NODE4_EN      R869  -1          A01X+047493Y+072760X0180Y0200R270 S2      
327T7_NODE2_EN_R    R875  -2          A10X+046644Y+073073X0180Y0200R090 S1      
327T7_NODE2_EN      R875  -1          A10X+046644Y+072758X0180Y0200R090 S1      
327T8_NODE3_EN_R    R866  -2          A01X+047943Y+073075X0180Y0200R270 S2      
327T8_NODE3_EN      R866  -1          A01X+047943Y+072760X0180Y0200R270 S2      
327NNAME10880       R985  -1          A01X+046644Y+073908X0180Y0200R270 S2      
327NNAME10879       R979  -1          A01X+047894Y+073908X0180Y0200R270 S2      
317GND              VIA   -     D0100PA00X+047145Y+073637               S3      
317GND              VIA   -     D0100PA00X+046644Y+073599               S3      
317GND              VIA   -     D0100PA00X+047131Y+073381               S3      
317GND              VIA   -     D0100PA00X+046644Y+072447               S3      
317NNAME10881       VIA   -     D0100PA00X+047055Y+072403               S3      
317T7_NODE1_EN_R    VIA   -     D0100PA00X+047356Y+072495               S3      
317NNAME10880       VIA   -     D0100PA00X+046585Y+073343               S3      
317NNAME10879       VIA   -     D0100PA00X+047698Y+073659               S3      
317NNAME10853       VIA   -     D0100PA00X+047616Y+073421               S3      
327T7_NODE3_EN_R    C641  -1          A10X+046644Y+074223X0180Y0200R270 S1      
327T7_NODE2_EN_R    C638  -1          A10X+047044Y+074223X0180Y0200R270 S1      
327NNAME10881       C745  -1          A01X+047094Y+074223X0180Y0200R090 S2      
327GND              C742  -2          A01X+047494Y+074223X0180Y0200R270 S2      
327NNAME10858       R985  -2          A01X+046644Y+074223X0180Y0200R270 S2      
327NNAME10882       R979  -2          A01X+047894Y+074223X0180Y0200R270 S2      
317GND              VIA   -     D0100PA00X+047494Y+074719               S3      
327T7_NODE4_EN_R    VIA   -           A10X+046607Y+077500X0260Y0260     S1      
327T7_NODE3_EN_R    VIA   -           A10X+046936Y+078041X0260Y0260     S1      
327T7_NODE2_EN_R    VIA   -           A10X+047562Y+077910X0260Y0260     S1      
327T7_NODE1_EN_R    VIA   -           A10X+047829Y+078639X0260Y0260     S1      
317NNAME10882       VIA   -     D0100PA00X+047178Y+078630               S1      
327T7_NODE3_EN_R    J18   -A67        A10X+046857Y+080787X0300Y1660R180 S1      
327T7_NODE2_EN_R    J18   -A66        A10X+047250Y+080787X0300Y1660R180 S1      
327T7_NODE1_EN_R    J18   -A65        A10X+047644Y+080787X0300Y1660R180 S1      
327GND              J18   -A64        A10X+048038Y+080787X0300Y1660R180 S1      
327NNAME10881       J18   -B67        A01X+046857Y+080787X0300Y1660R180 S2      
327NNAME10882       J18   -B66        A01X+047250Y+080787X0300Y1660R180 S2      
327GND              J18   -B65        A01X+047644Y+080787X0300Y1660R180 S2      
327T8_NODE4_EN_R    J18   -B64        A01X+048038Y+080787X0300Y1660R180 S2      
317GND              VIA   -     D0100PA00X+047644Y+079148               S3      
317NNAME10113       VIA   -     D0100PA00X+048681Y+006079               S1      
317UART_TX_P1_L     VIA   -     D0100PA00X+048324Y+006055               S3      
317NNAME10842       VIA   -     D0100PA00X+048703Y+006808               S3      
327GND              C486  -2          A01X+048844Y+010305X0180Y0200R090 S2      
327SIO_VBAT         C486  -1          A01X+048844Y+010620X0180Y0200R090 S2      
327GND              R624  -2          A01X+048354Y+010305X0180Y0200R090 S2      
327SIO_COPEN_N      R624  -1          A01X+048354Y+010620X0180Y0200R090 S2      
327SIO_GPIO47       R1150 -2          A01X+049296Y+010618X0180Y0200R270 S2      
327P3V3_NODE1       R1150 -1          A01X+049296Y+010303X0180Y0200R270 S2      
317SIO_VBAT         VIA   -     D0100PA00X+048844Y+010962               S1      
317GND              VIA   -     D0100PA00X+048844Y+010012               S3      
317GND              VIA   -     D0100PA00X+048407Y+009998               S3      
317P3V3_NODE1       VIA   -     D0100PA00X+049296Y+009944               S3      
317SIO_GPIO47       VIA   -     D0100PA00X+049436Y+010867               S1      
327SIO_VCCH         U43   -67         A01X+049513Y+011842X0110Y0710R180 S2      
327UART_TX_P5       U43   -66         A01X+049316Y+011842X0110Y0710R180 S2      
327N/C              U43   -65         A01X+049119Y+011842X0110Y0710R180 S2      
327SIO_VCCH         VIA   -           A10X+049018Y+012235X0260Y0260     S1      
317SIO_VCCH         VIA   -     D0100PA00X+049188Y+012522               S3      
317SIO_VCCH         VIA   -     D0100PA00X+048714Y+012340               S3      
317SIO_COPEN_N      VIA   -     D0100PA00X+048435Y+011281               S1      
317UART_TX_P5       VIA   -     D0100PA00X+048702Y+011975               S3      
327GND              C487  -2          A10X+048213Y+012640X0180Y0200R180 S1      
327SIO_VCCH         C487  -1          A10X+048528Y+012640X0180Y0200R180 S1      
327SIO_VCCH         C488  -1          A10X+048644Y+013239X0440Y0540R180 S1      
327NNAME10862       R1201 -1          A10X+048079Y+013936X0180Y0200R180 S1      
327SIO_VCCH         R628  -2          A10X+049270Y+012867X0180Y0200R180 S1      
317SIO_VCCH         VIA   -     D0100PA00X+049491Y+013332               S3      
327NNAME10861       R1202 -1          A10X+048079Y+014336X0180Y0200R180 S1      
327NNAME10863       R1203 -1          A10X+048079Y+014736X0180Y0200R180 S1      
327NNAME10864       R1204 -1          A10X+048079Y+015136X0180Y0200R180 S1      
317SIO_PWROK2       VIA   -     D0100PA00X+048786Y+015215               S1      
317GND              VIA   -     D0100PA00X+049076Y+015477               S3      
317NNAME10863       VIA   -     D0100PA00X+048857Y+014749               S3      
317NNAME10861       VIA   -     D0100PA00X+049242Y+014223               S1      
317NNAME10864       VIA   -     D0100PA00X+049447Y+014887               S1      
327NNAME10867       R183  -2          A10X+048228Y+017211X0180Y0200     S1      
327NNAME10865       R185  -2          A10X+048228Y+016411X0180Y0200     S1      
327NNAME10866       R184  -2          A10X+048228Y+016811X0180Y0200     S1      
327SIO_PWROK2       R620  -2          A10X+049464Y+015776X0180Y0200R180 S1      
327SIO_PIN45        R1138 -2          A10X+049464Y+016226X0180Y0200R180 S1      
317P3V3_NODE1       VIA   -     D0100PA00X+048774Y+016124               S3      
317UART_RX_P5       VIA   -     D0100PA00X+048822Y+015752               S3      
317SIO_PIN45        VIA   -     D0100PA00X+049013Y+016309               S1      
317NNAME10867       VIA   -     D0100PA00X+049367Y+017187               S1      
317NNAME10866       VIA   -     D0100PA00X+048904Y+016948               S1      
327SIO_PIN38        U43   -38         A01X+049119Y+018583X0110Y0710R180 S2      
327SIO_LRESET_N     U43   -37         A01X+049316Y+018583X0110Y0710R180 S2      
327UART_DSR_P5_N    U43   -36         A01X+049513Y+018583X0110Y0710R180 S2      
327NNAME10868       R182  -2          A10X+048228Y+017611X0180Y0200     S1      
317CPLD123_RSV2     VIA   -     D0100PA00X+048250Y+018417               S3      
317CPLD123_RSV3     VIA   -     D0100PA00X+048708Y+018092               S3      
317NNAME10870       VIA   -     D0100PA00X+048298Y+018107               S1      
317NNAME10868       VIA   -     D0100PA00X+048885Y+017542               S1      
317UART_DSR_P5_N    VIA   -     D0100PA00X+049421Y+017504               S3      
327GND              C536  -2          A01X+049528Y+019870X0180Y0200R270 S2      
327P5V_NODE1        C536  -1          A01X+049528Y+019555X0180Y0200R270 S2      
327SIO_LRESET_N     R621  -2          A01X+049117Y+019557X0180Y0200R090 S2      
327NNAME10319       R621  -1          A01X+049117Y+019872X0180Y0200R090 S2      
327SIO_PIN38        R617  -2          A01X+048428Y+019542X0180Y0200R090 S2      
327P3V3_NODE1       R617  -1          A01X+048428Y+019857X0180Y0200R090 S2      
317GND              VIA   -     D0100PA00X+049530Y+020160               S3      
317SIO_LRESET_N     VIA   -     D0100PA00X+048784Y+019414               S1      
317P3V3_NODE1       VIA   -     D0100PA00X+048746Y+019857               S3      
317NNAME10319       VIA   -     D0100PA00X+048802Y+020372               S1      
317SIO_PIN38        VIA   -     D0100PA00X+048637Y+018928               S1      
327COM4_EN_N        U103  -D          A01X+049141Y+021443X0400Y0500R270 S2      
327GND              U103  -S          A01X+048261Y+021043X0400Y0500R270 S2      
327NNAME10883       U103  -G          A01X+048261Y+021843X0400Y0500R270 S2      
317GND              VIA   -     D0100PA00X+049105Y+020751               S3      
317GND              VIA   -     D0100PA00X+048674Y+021043               S3      
317NNAME10883       VIA   -     D0100PA00X+048717Y+021457               S3      
327P3V3_NODE1       R1217 -2          A01X+049130Y+022795X0180Y0200R180 S2      
327COM4_EN_N        R1217 -1          A01X+048815Y+022795X0180Y0200R180 S2      
327NNAME10883       R521  -2          A01X+048499Y+022375X0180Y0200     S2      
327COM4_EN_N        R521  -1          A01X+048814Y+022375X0180Y0200     S2      
317P3V3_NODE1       VIA   -     D0100PA00X+049132Y+023181               S3      
317COM4_EN_N        VIA   -     D0100PA00X+049270Y+022380               S1      
327P3V3_NODE1       U31   -8          A01X+049395Y+025058X0220Y0680R090 S2      
327GND              C335  -2          A01X+049216Y+024288X0180Y0200     S2      
327P3V3_NODE1       C335  -1          A01X+049531Y+024288X0180Y0200     S2      
317GND              VIA   -     D0100PA00X+048882Y+024288               S3      
327N21116716        U31   -7          A01X+049395Y+025558X0220Y0680R090 S2      
327NNAME10884       U31   -6          A01X+049395Y+026058X0220Y0680R090 S2      
327NNAME10885       U31   -5          A01X+049395Y+026558X0220Y0680R090 S2      
327NNAME10871       R147  -2          A01X+048572Y+027627X0180Y0200R090 S2      
327P3V_COIN_CELL    R147  -1          A01X+048572Y+027942X0180Y0200R090 S2      
317NNAME10871       VIA   -     D0100PA00X+048417Y+027287               S1      
317P1V05_NODE1      VIA   -     D0100PA00X+048478Y+031409               S3      
317P1V05_NODE1      VIA   -     D0100PA00X+049485Y+031573               S3      
317PCIE_SW_P0_ERR   VIA   -     D0100PA00X+048083Y+033392               S3      
317GND              VIA   -     D0100PA00X+049514Y+038576               S3      
317NNAME10302       VIA   -     D0100PA00X+048630Y+042215               S1      
317NNAME10303       VIA   -     D0100PA00X+048130Y+042215               S1      
317GND              VIA   -     D0100PA00X+048667Y+042620               S3      
317P3V3_CLK_NODE1   VIA   -     D0100PA00X+049550Y+044747               S3      
317NNAME10802       VIA   -     D0100PA00X+048288Y+046794               S1      
317NNAME10803       VIA   -     D0100PA00X+048288Y+046294               S1      
327P1V05_NODE1      R3    -1          A10X+049407Y+048633X0280Y0320     S1      
317GND              VIA   -     D0100PA00X+048369Y+047352               S3      
317GND              VIA   -     D0100PA00X+048364Y+047963               S3      
317P1V05_NODE1      VIA   -     D0100PA00X+049226Y+048283               S3      
317P1V05_NODE1      VIA   -     D0100PA00X+049498Y+048298               S3      
327NNAME10886       R3    -2          A10X+049407Y+049213X0280Y0320     S1      
317NNAME10886       VIA   -     D0100PA00X+049033Y+049734               S1      
327N/C                    -1          A01X+048777Y+051367X0390Y0390R270 S2      
327N/C                    -1          A10X+048777Y+051367X0390Y0390R270 S1      
327NNAME10641       U125  -96         A01X+049523Y+054085X0070Y0600R090 S2      
327GND              U125  -95         A01X+049523Y+054242X0070Y0600R090 S2      
327GND              U125  -94         A01X+049523Y+054400X0070Y0600R090 S2      
327NNAME10887       U125  -93         A01X+049523Y+054557X0070Y0600R090 S2      
327P1V0_PCI_SW_A    U125  -92         A01X+049523Y+054715X0070Y0600R090 S2      
327NNAME10888       U125  -91         A01X+049523Y+054872X0070Y0600R090 S2      
327GND              C897  -2          A10X+049574Y+054385X0180Y0200R270 S1      
327P1V0_PCI_SW_A    C897  -1          A10X+049574Y+054700X0180Y0200R270 S1      
327NNAME10641       R281  -2          A01X+048701Y+053953X0180Y0200R180 S2      
327P3V3_NODE1       R281  -1          A01X+048386Y+053953X0180Y0200R180 S2      
317GND              VIA   -     D0100PA00X+048664Y+054369               S3      
317P3V3_NODE1       VIA   -     D0100PA00X+048551Y+053667               S3      
317NNAME10674       VIA   -     D0100PA00X+048321Y+054525               S1      
317NNAME10673       VIA   -     D0100PA00X+048321Y+055025               S1      
317P1V0_PCI_SW_A    VIA   -     D0100PA00X+049066Y+054715               S1      
317NNAME10641       VIA   -     D0100PA00X+048996Y+054085               S1      
327GND              U125  -90         A01X+049523Y+055030X0070Y0600R090 S2      
327GND              U125  -89         A01X+049523Y+055187X0070Y0600R090 S2      
327NNAME10674       U125  -88         A01X+049523Y+055345X0070Y0600R090 S2      
327NNAME10673       U125  -87         A01X+049523Y+055502X0070Y0600R090 S2      
327GND              U125  -86         A01X+049523Y+055660X0070Y0600R090 S2      
327P1V0_NODE1       U125  -85         A01X+049523Y+055817X0070Y0600R090 S2      
327NNAME10872       U125  -84         A01X+049523Y+055975X0070Y0600R090 S2      
327NNAME10873       U125  -83         A01X+049523Y+056132X0070Y0600R090 S2      
327NNAME10063       U125  -82         A01X+049523Y+056290X0070Y0600R090 S2      
327GND              U125  -81         A01X+049523Y+056447X0070Y0600R090 S2      
327GND              C894  -2          A10X+049396Y+056303X0180Y0200R180 S1      
317GND              VIA   -     D0100PA00X+048994Y+056343               S3      
317GND              VIA   -     D0100PA00X+048672Y+056373               S3      
317GND              VIA   -     D0100PA00X+048138Y+055321               S3      
317NNAME10874       VIA   -     D0100PA00X+048384Y+056619               S1      
317NNAME10872       VIA   -     D0100PA00X+048384Y+055615               S1      
317NNAME10873       VIA   -     D0100PA00X+048384Y+056115               S1      
327P1V0_PCI_SW_A    U125  -80         A01X+049523Y+056605X0070Y0600R090 S2      
327P1V0_PCI_SW_A    U125  -79         A01X+049523Y+056762X0070Y0600R090 S2      
327P1V0_PCI_SW_A    U125  -78         A01X+049523Y+056920X0070Y0600R090 S2      
327GND              U125  -77         A01X+049523Y+057077X0070Y0600R090 S2      
327P1V0_NODE1       U125  -76         A01X+049523Y+057235X0070Y0600R090 S2      
327NNAME10063       U125  -75         A01X+049523Y+057392X0070Y0600R090 S2      
327NNAME10874       U125  -74         A01X+049523Y+057549X0070Y0600R090 S2      
327NNAME10875       U125  -73         A01X+049523Y+057707X0070Y0600R090 S2      
327P1V0_NODE1       U125  -72         A01X+049523Y+057864X0070Y0600R090 S2      
327GND              U125  -71         A01X+049523Y+058022X0070Y0600R090 S2      
327GND              C896  -2          A10X+049406Y+056783X0180Y0200R180 S1      
327GND              C880  -2          A10X+049406Y+057173X0180Y0200R180 S1      
327GND              C862  -2          A10X+049406Y+057953X0180Y0200R180 S1      
327GND              C882  -2          A10X+049406Y+057563X0180Y0200R180 S1      
317GND              VIA   -     D0100PA00X+049066Y+057903               S3      
317GND              VIA   -     D0100PA00X+048740Y+057667               S3      
317GND              VIA   -     D0100PA00X+049069Y+057077               S3      
317GND              VIA   -     D0100PA00X+049054Y+056783               S3      
317GND              VIA   -     D0100PA00X+048141Y+057356               S3      
317NNAME10875       VIA   -     D0100PA00X+048384Y+057119               S1      
327NNAME10131       U125  -70         A01X+049523Y+058179X0070Y0600R090 S2      
327NNAME10129       U125  -69         A01X+049523Y+058337X0070Y0600R090 S2      
327GND              U125  -68         A01X+049523Y+058494X0070Y0600R090 S2      
327GND              U125  -67         A01X+049523Y+058652X0070Y0600R090 S2      
327PCIE_SW_TEST2    U125  -66         A01X+049523Y+058809X0070Y0600R090 S2      
327PCIE_SW_TRST     U125  -65         A01X+049523Y+058967X0070Y0600R090 S2      
327GND              C200  -2          A10X+049238Y+059424X0280Y0320R090 S1      
317GND              VIA   -     D0100PA00X+048589Y+059056               S3      
317GND              VIA   -     D0100PA00X+048938Y+059084               S3      
317GND              VIA   -     D0100PA00X+048538Y+059651               S3      
317NNAME10131       VIA   -     D0100PA00X+048574Y+058713               S1      
317NNAME10129       VIA   -     D0100PA00X+049074Y+058713               S1      
317N52998345        VIA   -     D0100PA00X+048134Y+059330               S1      
327PCIE_SW_TRST     R295  -2          A01X+049424Y+060345X0180Y0200R090 S2      
327GND              R295  -1          A01X+049424Y+060660X0180Y0200R090 S2      
327I2C_PSU1_SDA     U117  -D          A01X+048365Y+060403X0400Y0500R180 S2      
327PMBUS1_EN        U117  -G          A01X+048765Y+061283X0400Y0500R180 S2      
317PCIE_SW_TRST     VIA   -     D0100PA00X+049424Y+060044               S1      
317NNAME10818       VIA   -     D0100PA00X+049060Y+060814               S1      
317NNAME10876       VIA   -     D0100PA00X+048980Y+060020               S1      
327NNAME10830       U116  -S          A01X+049428Y+062884X0400Y0500R180 S2      
327I2C_PSU2_SDA     U118  -D          A01X+048383Y+062004X0400Y0500R180 S2      
327PMBUS2_EN        U118  -G          A01X+048783Y+062884X0400Y0500R180 S2      
317PMBUS2_EN        VIA   -     D0100PA00X+048783Y+062443               S1      
317NNAME10000       VIA   -     D0100PA00X+049004Y+062214               S3      
327P3V3_NODE1       C567  -2          A01X+048547Y+064360X0180Y0200     S2      
327GND              C567  -1          A01X+048862Y+064360X0180Y0200     S2      
327NNAME10830       R643  -2          A01X+048681Y+063480X0180Y0200R180 S2      
327I2C_PSU1_SCL     R643  -1          A01X+048366Y+063480X0180Y0200R180 S2      
327UART_CMC_RX_P    R1248 -2          A01X+048536Y+063962X0180Y0200     S2      
327P3V3_NODE1       R1248 -1          A01X+048851Y+063962X0180Y0200     S2      
327NNAME10830       R665  -2          A01X+049062Y+063460X0180Y0200     S2      
327P3V3_NODE1       R665  -1          A01X+049377Y+063460X0180Y0200     S2      
317GND              VIA   -     D0100PA00X+049110Y+064435               S3      
317P3V3_NODE1       VIA   -     D0100PA00X+049138Y+063928               S3      
317P3V3_NODE1       VIA   -     D0100PA00X+049590Y+064180               S3      
317UART_CMC_RX_P    VIA   -     D0100PA00X+048031Y+064222               S1      
327GND              C908  -2          A01X+049589Y+065541X0280Y0320R090 S2      
327CPLD_WDT1_R      R623  -2          A01X+048547Y+065560X0180Y0200     S2      
327CPLD_WDT1        R623  -1          A01X+048862Y+065560X0180Y0200     S2      
327COM3_WAKEUP      R792  -2          A01X+048547Y+065160X0180Y0200     S2      
327GND              R792  -1          A01X+048862Y+065160X0180Y0200     S2      
327P3V3_NODE1       R680  -2          A01X+048862Y+064760X0180Y0200R180 S2      
327COM3_WAKEUP      R680  -1          A01X+048547Y+064760X0180Y0200R180 S2      
317GND              VIA   -     D0100PA00X+049193Y+065420               S3      
317GND              VIA   -     D0100PA00X+049562Y+066018               S3      
317P3V3_NODE1       VIA   -     D0100PA00X+049231Y+065052               S3      
317P3V3_NODE1       VIA   -     D0100PA00X+048218Y+064628               S3      
317CPLD_WDT1_R      VIA   -     D0100PA00X+048125Y+065484               S1      
317UART_CMC_TX_P    VIA   -     D0100PA00X+049302Y+064670               S3      
317NNAME10878       VIA   -     D0100PA00X+048470Y+066036               S1      
327N21699069        R682  -2          A01X+048547Y+067560X0180Y0200     S2      
327GND              R682  -1          A01X+048862Y+067560X0180Y0200     S2      
327PU_I2C_SDA4      R674  -2          A01X+048547Y+067160X0180Y0200     S2      
327P3V3_NODE1       R674  -1          A01X+048862Y+067160X0180Y0200     S2      
327PU_I2C_SCL4      R672  -2          A01X+048547Y+066760X0180Y0200     S2      
327P3V3_NODE1       R672  -1          A01X+048862Y+066760X0180Y0200     S2      
317GND              VIA   -     D0100PA00X+049116Y+067560               S3      
317PU_I2C_SDA4      VIA   -     D0100PA00X+048240Y+067309               S1      
317PU_I2C_SCL4      VIA   -     D0100PA00X+048254Y+066804               S1      
317P3V3_NODE1       VIA   -     D0100PA00X+049104Y+066760               S3      
317P3V3_NODE1       VIA   -     D0100PA00X+049106Y+067160               S3      
317CPLD_WDT1        VIA   -     D0100PA00X+049012Y+066270               S1      
317NNAME10877       VIA   -     D0100PA00X+049277Y+066509               S3      
327P3V3_NODE1       C570  -2          A10X+048547Y+067866X0180Y0200R180 S1      
327GND              C570  -1          A10X+048862Y+067866X0180Y0200R180 S1      
327P3V3_NODE1       C566  -2          A01X+048547Y+067963X0180Y0200     S2      
327GND              C566  -1          A01X+048862Y+067963X0180Y0200     S2      
327N21699372        R706  -2          A10X+048547Y+068266X0180Y0200R180 S1      
327P3V3_NODE1       R706  -1          A10X+048862Y+068266X0180Y0200R180 S1      
327P5V_NODE1        R727  -2          A10X+048862Y+068666X0180Y0200     S1      
327T8_NODE4_EN      R727  -1          A10X+048547Y+068666X0180Y0200     S1      
327P5V_NODE1        R726  -2          A10X+048862Y+069066X0180Y0200     S1      
327T8_NODE3_EN      R726  -1          A10X+048547Y+069066X0180Y0200     S1      
317GND              VIA   -     D0100PA00X+049119Y+067966               S3      
317GND              VIA   -     D0100PA00X+049432Y+068767               S3      
317P3V3_NODE1       VIA   -     D0100PA00X+049229Y+068235               S3      
317P3V3_NODE1       VIA   -     D0100PA00X+048306Y+067963               S3      
317N21699372        VIA   -     D0100PA00X+048123Y+068537               S1      
317P5V_NODE1        VIA   -     D0100PA00X+049117Y+068751               S3      
317T8_NODE4_EN      VIA   -     D0100PA00X+048123Y+069137               S1      
317P3V3_STB_NODE1   VIA   -     D0100PA00X+049434Y+069162               S3      
327P5V_NODE1        R725  -2          A10X+048862Y+069466X0180Y0200     S1      
327T8_NODE2_EN      R725  -1          A10X+048547Y+069466X0180Y0200     S1      
327P5V_NODE1        R724  -2          A10X+048862Y+069866X0180Y0200     S1      
327T8_NODE1_EN      R724  -1          A10X+048547Y+069866X0180Y0200     S1      
327T7_NODE4_EN      R723  -1          A01X+049345Y+070658X0180Y0200R180 S2      
317P5V_NODE1        VIA   -     D0100PA00X+049107Y+069966               S3      
317P5V_NODE1        VIA   -     D0100PA00X+049138Y+069466               S3      
317T7_NODE4_EN      VIA   -     D0100PA00X+049090Y+070615               S1      
317T8_NODE3_EN      VIA   -     D0100PA00X+048123Y+069637               S1      
317T8_NODE2_EN      VIA   -     D0100PA00X+049556Y+069478               S1      
327T7_NODE2_EN      R721  -1          A01X+049345Y+071458X0180Y0200R180 S2      
327T7_NODE1_EN      R720  -1          A01X+049345Y+071858X0180Y0200R180 S2      
327T7_NODE3_EN      R722  -1          A01X+049345Y+071058X0180Y0200R180 S2      
317T7_NODE1_EN      VIA   -     D0100PA00X+048818Y+071924               S1      
317T7_NODE2_EN      VIA   -     D0100PA00X+049089Y+071490               S1      
317T7_NODE3_EN      VIA   -     D0100PA00X+048809Y+071055               S1      
327GND              C629  -2          A01X+048724Y+073908X0180Y0200R090 S2      
327GND              C626  -2          A01X+049154Y+073908X0180Y0200R090 S2      
327GND              C632  -2          A01X+048294Y+073908X0180Y0200R090 S2      
327GND              C737  -2          A01X+049244Y+073073X0180Y0200R270 S2      
327NNAME10889       C737  -1          A01X+049244Y+072758X0180Y0200R270 S2      
327T8_NODE1_EN_R    R860  -2          A01X+048794Y+073073X0180Y0200R270 S2      
327T8_NODE1_EN      R860  -1          A01X+048794Y+072758X0180Y0200R270 S2      
327T8_NODE2_EN_R    R863  -2          A01X+048344Y+073073X0180Y0200R270 S2      
327T8_NODE2_EN      R863  -1          A01X+048344Y+072758X0180Y0200R270 S2      
317GND              VIA   -     D0100PA00X+049600Y+073615               S3      
317GND              VIA   -     D0100PA00X+048318Y+073651               S3      
317GND              VIA   -     D0100PA00X+048794Y+073568               S3      
317GND              VIA   -     D0100PA00X+049189Y+073574               S3      
317GND              VIA   -     D0100PA00X+049485Y+073325               S3      
317NNAME10834       VIA   -     D0100PA00X+048062Y+073424               S3      
327T8_NODE3_EN_R    C629  -1          A01X+048724Y+074223X0180Y0200R090 S2      
327T8_NODE2_EN_R    C626  -1          A01X+049154Y+074223X0180Y0200R090 S2      
327T8_NODE4_EN_R    C632  -1          A01X+048294Y+074223X0180Y0200R090 S2      
327NNAME10890       VIA   -           A10X+048825Y+078666X0260Y0260     S1      
317T8_NODE4_EN_R    VIA   -     D0100PA00X+048077Y+077813               S1      
317T8_NODE3_EN_R    VIA   -     D0100PA00X+048587Y+077609               S1      
317T8_NODE2_EN_R    VIA   -     D0100PA00X+049172Y+077671               S1      
317T8_NODE1_EN_R    VIA   -     D0100PA00X+049511Y+077173               S1      
327NNAME10891       J18   -A63        A10X+048431Y+080787X0300Y1660R180 S1      
327NNAME10890       J18   -A62        A10X+048825Y+080787X0300Y1660R180 S1      
327NNAME10892       J18   -A61        A10X+049219Y+080787X0300Y1660R180 S1      
327NNAME10893       J18   -A60        A10X+049612Y+080787X0300Y1660R180 S1      
327T8_NODE3_EN_R    J18   -B63        A01X+048431Y+080787X0300Y1660R180 S2      
327T8_NODE2_EN_R    J18   -B62        A01X+048825Y+080787X0300Y1660R180 S2      
327T8_NODE1_EN_R    J18   -B61        A01X+049219Y+080787X0300Y1660R180 S2      
327GND              J18   -B60        A01X+049612Y+080787X0300Y1660R180 S2      
317GND              VIA   -     D0100PA00X+048038Y+079148               S3      
317NNAME10843       VIA   -     D0100PA00X+050290Y+005767               S1      
327SIO_PIN76        R1141 -2          A01X+050896Y+010618X0180Y0200R270 S2      
327P3V3_STB_NODE1   R1141 -1          A01X+050896Y+010303X0180Y0200R270 S2      
327SIO_PIN72        R1143 -2          A01X+049696Y+010618X0180Y0200R270 S2      
327P3V3_STB_NODE1   R1143 -1          A01X+049696Y+010303X0180Y0200R270 S2      
327SIO_PIN75        R1142 -2          A01X+050496Y+010618X0180Y0200R270 S2      
327P3V3_STB_NODE1   R1142 -1          A01X+050496Y+010303X0180Y0200R270 S2      
327SIO_PIN73        R1140 -2          A01X+050096Y+010618X0180Y0200R270 S2      
327P3V3_STB_NODE1   R1140 -1          A01X+050096Y+010303X0180Y0200R270 S2      
317P3V3_STB_NODE1   VIA   -     D0100PA00X+049696Y+009996               S3      
317P3V3_STB_NODE1   VIA   -     D0100PA00X+050896Y+009998               S3      
317P3V3_STB_NODE1   VIA   -     D0100PA00X+050096Y+010014               S3      
317P3V3_STB_NODE1   VIA   -     D0100PA00X+050496Y+009983               S3      
317SIO_PIN72        VIA   -     D0100PA00X+050031Y+010921               S1      
327SIO_PIN75        U43   -75         A01X+051087Y+011842X0110Y0710R180 S2      
327GND              U43   -74         A01X+050890Y+011842X0110Y0710R180 S2      
327SIO_PIN73        U43   -73         A01X+050694Y+011842X0110Y0710R180 S2      
327SIO_PIN72        U43   -72         A01X+050497Y+011842X0110Y0710R180 S2      
327SIO_GPIO47       U43   -71         A01X+050300Y+011842X0110Y0710R180 S2      
327UART_RI_P5_N     U43   -70         A01X+050103Y+011842X0110Y0710R180 S2      
327SIO_VBAT         U43   -69         A01X+049906Y+011842X0110Y0710R180 S2      
327SIO_COPEN_N      U43   -68         A01X+049709Y+011842X0110Y0710R180 S2      
317GND              VIA   -     D0100PA00X+050890Y+012406               S3      
317UART_RI_P5_N     VIA   -     D0100PA00X+049743Y+012402               S1      
317SIO_PIN73        VIA   -     D0100PA00X+050475Y+011175               S1      
317SIO_PIN75        VIA   -     D0100PA00X+050969Y+011294               S1      
327NNAME10894       R1208 -2          A10X+050827Y+013769X0180Y0200     S1      
327NNAME10862       R1208 -1          A10X+050512Y+013769X0180Y0200     S1      
327P5V_STB_NODE1    R628  -1          A10X+049585Y+012867X0180Y0200R180 S1      
317P5V_STB_NODE1    VIA   -     D0100PA00X+049946Y+012867               S3      
317UART_RI_P6_N     VIA   -     D0100PA00X+050971Y+012727               S1      
317NNAME10862       VIA   -     D0100PA00X+050022Y+013645               S1      
327NNAME10895       R1207 -2          A10X+050827Y+015069X0180Y0200     S1      
327NNAME10864       R1207 -1          A10X+050512Y+015069X0180Y0200     S1      
327GND              R1210 -2          A10X+050512Y+014669X0180Y0200R180 S1      
327NNAME10895       R1210 -1          A10X+050827Y+014669X0180Y0200R180 S1      
327NNAME10896       R1205 -2          A10X+050827Y+014219X0180Y0200     S1      
327NNAME10861       R1205 -1          A10X+050512Y+014219X0180Y0200     S1      
317GND              VIA   -     D0100PA00X+050213Y+014669               S3      
317P3V3_NODE1       VIA   -     D0100PA00X+050218Y+015671               S1      
327P3V3_NODE1       R620  -1          A10X+049779Y+015776X0180Y0200R180 S1      
327P3V3_NODE1       R1138 -1          A10X+049779Y+016226X0180Y0200R180 S1      
317P3V3_NODE1       VIA   -     D0100PA00X+050096Y+016226               S3      
317NNAME10865       VIA   -     D0100PA00X+049636Y+016722               S1      
327P5V_NODE1        U43   -35         A01X+049709Y+018583X0110Y0710R180 S2      
327UART_RTS_P5_N    U43   -34         A01X+049906Y+018583X0110Y0710R180 S2      
327UART_DTR_P5_N    U43   -33         A01X+050103Y+018583X0110Y0710R180 S2      
327UART_CTS_P5_N    U43   -32         A01X+050300Y+018583X0110Y0710R180 S2      
327UART_RX_P4_BUF   U43   -31         A01X+050497Y+018583X0110Y0710R180 S2      
327N/C              U43   -30         A01X+050694Y+018583X0110Y0710R180 S2      
327UART_DTR_P6_N    U43   -29         A01X+050890Y+018583X0110Y0710R180 S2      
327UART_TX_P4_R     U43   -28         A01X+051087Y+018583X0110Y0710R180 S2      
317UART_DTR_P5_N    VIA   -     D0100PA00X+050104Y+017730               S3      
317UART_RTS_P5_N    VIA   -     D0100PA00X+049894Y+017974               S1      
317UART_DTR_P6_N    VIA   -     D0100PA00X+051000Y+017350               S1      
317UART_CTS_P5_N    VIA   -     D0100PA00X+050300Y+018054               S3      
327UART_TX_P4_BUF   R1161 -2          A01X+050830Y+020188X0180Y0200R270 S2      
327UART_TX_P4_R     R1161 -1          A01X+050830Y+019873X0180Y0200R270 S2      
327UART_CTS_P5_N    R616  -2          A01X+050405Y+020215X0180Y0200R090 S2      
327UART_RI_P3_N     R1263 -2          A10X+050455Y+020180X0180Y0200R180 S1      
327P5V_NODE1        R1263 -1          A10X+050770Y+020180X0180Y0200R180 S1      
317P5V_NODE1        VIA   -     D0100PA00X+049915Y+019420               S3      
317UART_TX_P4_R     VIA   -     D0100PA00X+050910Y+019190               S1      
317UART_RX_P4_BUF   VIA   -     D0100PA00X+050558Y+019256               S3      
327UART_RX_P4_BUF   U136  -4          A01X+050628Y+020976X0130Y0460R270 S2      
327P3V3_NODE1       U136  -5          A01X+050628Y+021488X0130Y0460R270 S2      
327GND              U136  -3          A01X+049870Y+020976X0130Y0460R270 S2      
327UART_RX_P4       U136  -2          A01X+049870Y+021232X0130Y0460R270 S2      
327COM4_EN_N        U136  -1          A01X+049870Y+021488X0130Y0460R270 S2      
327GND              U146  -3          A10X+050494Y+021371X0130Y0460     S1      
327NNAME10897       U146  -2          A10X+050750Y+021371X0130Y0460     S1      
327N/C              U146  -1          A10X+051006Y+021371X0130Y0460     S1      
327P3V3_NODE1       R616  -1          A01X+050405Y+020530X0180Y0200R090 S2      
317GND              VIA   -     D0100PA00X+049888Y+021717               S3      
317P3V3_NODE1       VIA   -     D0100PA00X+049923Y+020530               S1      
317UART_RX_P4       VIA   -     D0100PA00X+050623Y+020737               S1      
327UART_TX_P4       U135  -4          A01X+050636Y+021956X0130Y0460R270 S2      
327P3V3_NODE1       U135  -5          A01X+050636Y+022468X0130Y0460R270 S2      
327GND              U135  -3          A01X+049878Y+021956X0130Y0460R270 S2      
327UART_TX_P4_BUF   U135  -2          A01X+049878Y+022212X0130Y0460R270 S2      
327COM4_EN_N        U135  -1          A01X+049878Y+022468X0130Y0460R270 S2      
327UART_RI_P3_N     U146  -4          A10X+050494Y+022129X0130Y0460     S1      
327P3V3_NODE1       U146  -5          A10X+051006Y+022129X0130Y0460     S1      
327GND              R1162 -2          A01X+049612Y+023082X0180Y0200     S2      
327UART_TX_P4_BUF   R1162 -1          A01X+049927Y+023082X0180Y0200     S2      
327UART_RI_P3_N     R1328 -1          A10X+050200Y+023243X0180Y0200R090 S1      
327UART_RI_P3_N     R1327 -2          A10X+050600Y+023243X0180Y0200R270 S1      
327NNAME10897       R1330 -1          A10X+051000Y+023243X0180Y0200R090 S1      
317GND              VIA   -     D0100PA00X+049908Y+023558               S3      
317GND              VIA   -     D0100PA00X+049612Y+023350               S3      
317UART_RI_P3_N     VIA   -     D0100PA00X+050494Y+022786               S3      
317UART_TX_P4_BUF   VIA   -     D0100PA00X+049887Y+022777               S1      
327GND              R1328 -2          A10X+050200Y+023558X0180Y0200R090 S1      
327NNAME10897       R1327 -1          A10X+050600Y+023558X0180Y0200R270 S1      
327P3V3_NODE1       R1330 -2          A10X+051000Y+023558X0180Y0200R090 S1      
317P3V3_NODE1       VIA   -     D0100PA00X+049941Y+024288               S3      
317P3V3_NODE1       VIA   -     D0100PA00X+050700Y+023900               S3      
317N21116716        VIA   -     D0100PA00X+050416Y+025558               S1      
317P3V_COIN_CELL    BT1   -1    D0440PA00X+050749Y+028154               S0      
317P1V8_NODE1       VIA   -     D0100PA00X+051107Y+031072               S3      
317P1V0_NODE1       VIA   -     D0100PA00X+050914Y+033801               S3      
317GND              BT1   -2    D0400PA00X+050749Y+036028               S0      
317GND              VIA   -     D0100PA00X+050490Y+039048               S3      
317NNAME10460       VIA   -     D0100PA00X+049711Y+038857               S1      
317NNAME10459       VIA   -     D0100PA00X+050211Y+038857               S1      
327GND              Y1    -4          A01X+051317Y+042294X0480Y0560R270 S2      
327NNAME10898       Y1    -3          A01X+050451Y+042294X0480Y0560R270 S2      
317GND              VIA   -     D0100PA00X+050582Y+041747               S1      
317GND              VIA   -     D0100PA00X+051058Y+041774               S3      
317GND              VIA   -     D0100PA00X+049824Y+041783               S1      
317GND              VIA   -     D0100PA00X+050269Y+041745               S3      
327GND              C13   -2          A01X+050543Y+043673X0180Y0200     S2      
327NNAME10898       C13   -1          A01X+050858Y+043673X0180Y0200     S2      
327GND              Y1    -2          A01X+050451Y+042964X0480Y0560R270 S2      
327NNAME10899       Y1    -1          A01X+051317Y+042964X0480Y0560R270 S2      
317GND              VIA   -     D0100PA00X+049955Y+042964               S1      
317GND              VIA   -     D0100PA00X+050249Y+043673               S1      
317NNAME10898       VIA   -     D0100PA00X+050949Y+043383               S1      
317NNAME10900       VIA   -     D0100PA00X+049782Y+044027               S3      
327GND              U1    -56         A01X+050946Y+045242X0070Y0350R090 S2      
327NNAME10901       U1    -55         A01X+050946Y+045400X0070Y0350R090 S2      
327P3V3_CLK_NODE1   C1    -1          A10X+050790Y+045599X0280Y0320R270 S1      
327P3V3_CLK_NODE1   R8    -2          A01X+049775Y+044976X0180Y0200     S2      
327NNAME10901       R8    -1          A01X+050090Y+044976X0180Y0200     S2      
327NNAME10900       R7    -2          A01X+049782Y+044529X0180Y0200     S2      
327NNAME10901       R7    -1          A01X+050097Y+044529X0180Y0200     S2      
327NNAME10898       R4    -2          A01X+050923Y+044113X0180Y0200     S2      
317GND              VIA   -     D0100PA00X+050946Y+045027               S3      
317NNAME10901       VIA   -     D0100PA00X+050646Y+044693               S1      
327NNAME10459       U1    -54         A01X+050946Y+045557X0070Y0350R090 S2      
327NNAME10460       U1    -53         A01X+050946Y+045714X0070Y0350R090 S2      
327GND              U1    -52         A01X+050946Y+045872X0070Y0350R090 S2      
327NNAME10302       U1    -51         A01X+050946Y+046029X0070Y0350R090 S2      
327NNAME10303       U1    -50         A01X+050946Y+046187X0070Y0350R090 S2      
327NNAME10902       U1    -49         A01X+050946Y+046344X0070Y0350R090 S2      
327P1V5_CLK_NODE1   U1    -48         A01X+050946Y+046502X0070Y0350R090 S2      
327NNAME10803       U1    -47         A01X+050946Y+046659X0070Y0350R090 S2      
327NNAME10802       U1    -46         A01X+050946Y+046817X0070Y0350R090 S2      
327CPU_STP_NODE1    U1    -45         A01X+050946Y+046974X0070Y0350R090 S2      
327NNAME10902       C10   -1          A10X+050866Y+046322X0180Y0200     S1      
327P1V5_CLK_NODE1   C7    -1          A10X+050866Y+046872X0180Y0200     S1      
327CPU_STP_NODE1    R6    -2          A10X+049856Y+046052X0180Y0200R090 S1      
327P3V3_CLK_NODE1   R6    -1          A10X+049856Y+045737X0180Y0200R090 S1      
317GND              VIA   -     D0100PA00X+050544Y+045872               S3      
317NNAME10902       VIA   -     D0100PA00X+050294Y+046382               S1      
317P1V5_CLK_NODE1   VIA   -     D0100PA00X+050584Y+046502               S3      
317CPU_STP_NODE1    VIA   -     D0100PA00X+049812Y+047001               S1      
327NNAME10902       L3    -2          A10X+050164Y+048533X0440Y0540R270 S1      
327NNAME10567       U1    -44         A01X+050946Y+047132X0070Y0350R090 S2      
327NNAME10568       U1    -43         A01X+050946Y+047289X0070Y0350R090 S2      
327NNAME10902       C9    -1          A10X+050844Y+048430X0280Y0320     S1      
327NNAME10886       L3    -1          A10X+050164Y+049281X0440Y0540R270 S1      
327GND              C9    -2          A10X+050844Y+049010X0280Y0320     S1      
317GND              VIA   -     D0100PA00X+051107Y+049338               S3      
317GND              VIA   -     D0100PA00X+051152Y+049626               S3      
317GND              VIA   -     D0100PA00X+050574Y+049588               S3      
317NNAME10191       VIA   -     D0100PA00X+051123Y+049906               S1      
317NNAME10192       VIA   -     D0100PA00X+050623Y+049906               S1      
317GND              VIA   -     D0100PA00X+051156Y+051379               S3      
327NNAME10903       U125  -103        A01X+051078Y+053475X0070Y0600R180 S2      
327GND              U125  -102        A01X+050921Y+053475X0070Y0600R180 S2      
327P1V0_NODE1       U125  -101        A01X+050763Y+053475X0070Y0600R180 S2      
327GND              U125  -100        A01X+050606Y+053475X0070Y0600R180 S2      
327P3V3_NODE1       U125  -99         A01X+050448Y+053475X0070Y0600R180 S2      
327N/C              U125  -98         A01X+050291Y+053475X0070Y0600R180 S2      
327NNAME10904       U125  -97         A01X+050133Y+053475X0070Y0600R180 S2      
327P3V3_NODE1       C865  -1          A10X+050194Y+053403X0180Y0200R090 S1      
327GND              C877  -2          A01X+050764Y+052205X0180Y0200R090 S2      
327P1V0_NODE1       C877  -1          A01X+050764Y+052520X0180Y0200R090 S2      
327NNAME10904       R280  -2          A01X+050204Y+052590X0180Y0200R270 S2      
327P3V3_NODE1       R280  -1          A01X+050204Y+052275X0180Y0200R270 S2      
317GND              VIA   -     D0100PA00X+050461Y+052205               S3      
317P3V3_NODE1       VIA   -     D0100PA00X+049892Y+052380               S3      
317P3V3_NODE1       VIA   -     D0100PA00X+050396Y+052941               S3      
317P1V0_NODE1       VIA   -     D0100PA00X+050461Y+052520               S1      
317NNAME10904       VIA   -     D0100PA00X+050133Y+052893               S3      
327NNAME10887       C193  -2          A10X+050694Y+053994X0180Y0200R090 S1      
327NNAME10905       C193  -1          A10X+050694Y+053679X0180Y0200R090 S1      
327NNAME10888       C192  -2          A10X+051094Y+053994X0180Y0200R090 S1      
327NNAME10906       C192  -1          A10X+051094Y+053679X0180Y0200R090 S1      
327GND              C865  -2          A10X+050194Y+053718X0180Y0200R090 S1      
317GND              VIA   -     D0100PA00X+050014Y+054323               S3      
317GND              VIA   -     D0100PA00X+050345Y+054024               S3      
317GND              VIA   -     D0100PA00X+050572Y+054287               S3      
317NNAME10888       VIA   -     D0100PA00X+050334Y+054983               S1      
317NNAME10887       VIA   -     D0100PA00X+050334Y+054483               S1      
327NNAME10063       C894  -1          A10X+049711Y+056303X0180Y0200R180 S1      
327GND              C878  -2          A10X+049634Y+055575X0180Y0200R270 S1      
327P1V0_NODE1       C878  -1          A10X+049634Y+055890X0180Y0200R270 S1      
327P1V0_NODE1       C199  -1          A10X+050454Y+055693X0280Y0320R270 S1      
327GND              C199  -2          A10X+051034Y+055693X0280Y0320R270 S1      
327P1V0_NODE1       L53   -1          A10X+051034Y+056243X0280Y0320R090 S1      
327P1V0_PCI_SW_A    L53   -2          A10X+050454Y+056243X0280Y0320R090 S1      
317GND              VIA   -     D0100PA00X+050004Y+055593               S3      
317GND              VIA   -     D0100PA00X+050004Y+055073               S3      
317NNAME10063       VIA   -     D0100PA00X+050014Y+056303               S3      
317P1V0_NODE1       VIA   -     D0100PA00X+050014Y+055863               S3      
317P1V0_PCI_SW_A    VIA   -     D0100PA00X+050034Y+056643               S3      
327GND              C932  -2          A10X+050363Y+057179X0180Y0200R090 S1      
327P1V0_PCI_SW_A    C932  -1          A10X+050363Y+056864X0180Y0200R090 S1      
327GND              C931  -2          A10X+050753Y+057179X0180Y0200R090 S1      
327P1V0_PCI_SW_A    C931  -1          A10X+050753Y+056864X0180Y0200R090 S1      
327P1V0_PCI_SW_A    C896  -1          A10X+049721Y+056783X0180Y0200R180 S1      
327P1V0_NODE1       C880  -1          A10X+049721Y+057173X0180Y0200R180 S1      
327P1V0_NODE1       C862  -1          A10X+049721Y+057953X0180Y0200R180 S1      
327NNAME10063       C882  -1          A10X+049721Y+057563X0180Y0200R180 S1      
317GND              VIA   -     D0100PA00X+051034Y+057133               S3      
317NNAME10063       VIA   -     D0100PA00X+050044Y+057493               S3      
317P1V0_NODE1       VIA   -     D0100PA00X+050042Y+057864               S3      
317P1V0_NODE1       VIA   -     D0100PA00X+050054Y+057203               S3      
317P1V0_PCI_SW_A    VIA   -     D0100PA00X+050034Y+056943               S3      
327N/C              U125  -64         A01X+050133Y+059577X0070Y0600R180 S2      
327PCIE_SW_TMS      U125  -63         A01X+050291Y+059577X0070Y0600R180 S2      
327GND              U125  -62         A01X+050448Y+059577X0070Y0600R180 S2      
327P1V0_NODE1       U125  -61         A01X+050606Y+059577X0070Y0600R180 S2      
327GND              U125  -60         A01X+050763Y+059577X0070Y0600R180 S2      
327N/C              U125  -59         A01X+050921Y+059577X0070Y0600R180 S2      
327N/C              U125  -58         A01X+051078Y+059577X0070Y0600R180 S2      
327GND              C872  -2          A10X+050514Y+059730X0180Y0200R090 S1      
327P1V0_NODE1       C872  -1          A10X+050514Y+059415X0180Y0200R090 S1      
327P1V0_NODE1       C200  -1          A10X+049818Y+059424X0280Y0320R090 S1      
317GND              VIA   -     D0100PA00X+049987Y+058573               S3      
317PCIE_SW_TEST2    VIA   -     D0100PA00X+050054Y+058853               S1      
317P1V0_NODE1       VIA   -     D0100PA00X+050574Y+059053               S3      
327PCIE_SW_TMS      R296  -2          A01X+050224Y+060345X0180Y0200R090 S2      
327GND              R296  -1          A01X+050224Y+060660X0180Y0200R090 S2      
327PCIE_SW_TEST2    R283  -2          A01X+049824Y+060345X0180Y0200R090 S2      
327P3V3_NODE1       R283  -1          A01X+049824Y+060660X0180Y0200R090 S2      
317GND              VIA   -     D0100PA00X+050574Y+060043               S3      
317GND              VIA   -     D0100PA00X+049614Y+060888               S3      
317GND              VIA   -     D0100PA00X+050427Y+060863               S3      
317P3V3_NODE1       VIA   -     D0100PA00X+050010Y+060889               S3      
317P3V3_NODE1       VIA   -     D0100PA00X+050924Y+060852               S3      
317P5V_NODE1        VIA   -     D0100PA00X+050802Y+061360               S3      
317PCIE_SW_TMS      VIA   -     D0100PA00X+050054Y+060093               S1      
327PMBUS1_EN        R1282 -2          A01X+050076Y+061360X0180Y0200     S2      
327P5V_NODE1        R1282 -1          A01X+050391Y+061360X0180Y0200     S2      
327UART_RI_P6_N     U143  -D          A10X+050239Y+062883X0400Y0500R180 S1      
327I2C_PSU1_SCL     U116  -D          A01X+049828Y+062004X0400Y0500R180 S2      
327PMBUS1_EN        U116  -G          A01X+050228Y+062884X0400Y0500R180 S2      
327I2C_PSU3_SCL     U139  -D          A01X+051224Y+062017X0400Y0500R180 S2      
327NNAME10878       U139  -S          A01X+050824Y+062897X0400Y0500R180 S2      
317NNAME10207       VIA   -     D0100PA00X+050498Y+061643               S3      
317NNAME10428       VIA   -     D0100PA00X+050840Y+061780               S1      
317PMBUS1_EN        VIA   -     D0100PA00X+050208Y+062300               S1      
317NNAME10830       VIA   -     D0100PA00X+049835Y+062758               S3      
327NNAME10878       R648  -2          A01X+050755Y+063482X0180Y0200R180 S2      
327I2C_PSU3_SCL     R648  -1          A01X+050440Y+063482X0180Y0200R180 S2      
327NNAME10878       R669  -2          A01X+050440Y+063878X0180Y0200     S2      
327P3V3_NODE1       R669  -1          A01X+050755Y+063878X0180Y0200     S2      
327NNAME10000       U143  -S          A10X+050639Y+063763X0400Y0500R180 S1      
327TACKOVER_EN      U143  -G          A10X+049839Y+063763X0400Y0500R180 S1      
317I2C_PSU3_SCL     VIA   -     D0100PA00X+050578Y+064254               S3      
317CPLD123_RSV2     VIA   -     D0100PA00X+050112Y+063325               S3      
317CPLD123_RSV3     VIA   -     D0100PA00X+051070Y+063430               S3      
317CPLD123_RSV1     VIA   -     D0100PA00X+049669Y+063359               S3      
317NNAME10878       VIA   -     D0100PA00X+050194Y+064407               S3      
327CPLD3_RSV2       U129  -50         A01X+051093Y+065003X0110Y0590R270 S2      
327CPLD3_RSV1       U129  -49         A01X+051093Y+065200X0110Y0590R270 S2      
327NNAME10835       U129  -48         A01X+051093Y+065397X0110Y0590R270 S2      
327NNAME10907       U129  -47         A01X+051093Y+065594X0110Y0590R270 S2      
327GND              U129  -46         A01X+051093Y+065791X0110Y0590R270 S2      
327P3V3_NODE1       U129  -45         A01X+051093Y+065988X0110Y0590R270 S2      
327GND              C902  -2          A01X+049806Y+066018X0180Y0200     S2      
327P3V3_NODE1       C902  -1          A01X+050121Y+066018X0180Y0200     S2      
327P3V3_NODE1       C908  -1          A01X+050169Y+065541X0280Y0320R090 S2      
327CPLD3_RSV1       R679  -2          A01X+050019Y+065063X0180Y0200R180 S2      
327CPLD123_RSV1     R679  -1          A01X+049704Y+065063X0180Y0200R180 S2      
327CPLD3_RSV2       R684  -2          A01X+050017Y+064657X0180Y0200R180 S2      
327CPLD123_RSV2     R684  -1          A01X+049702Y+064657X0180Y0200R180 S2      
327NNAME10907       R1000 -1          A10X+050992Y+065501X0180Y0200     S1      
317GND              VIA   -     D0100PA00X+049867Y+065301               S3      
317P3V3_NODE1       VIA   -     D0100PA00X+050484Y+065710               S3      
317P3V3_NODE1       VIA   -     D0100PA00X+050368Y+065967               S3      
317NNAME10835       VIA   -     D0100PA00X+050569Y+065442               S1      
317CPLD3_RSV2       VIA   -     D0100PA00X+050806Y+064538               S1      
317CPLD3_RSV1       VIA   -     D0100PA00X+050430Y+064961               S1      
327CPLD_WDT2        U129  -44         A01X+051093Y+066185X0110Y0590R270 S2      
327CPLD_WDT1        U129  -43         A01X+051093Y+066381X0110Y0590R270 S2      
327NNAME10852       U129  -42         A01X+051093Y+066578X0110Y0590R270 S2      
327NNAME10908       U129  -41         A01X+051093Y+066775X0110Y0590R270 S2      
327NNAME10880       U129  -40         A01X+051093Y+066972X0110Y0590R270 S2      
327NNAME10909       U129  -39         A01X+051093Y+067169X0110Y0590R270 S2      
327NNAME10879       U129  -38         A01X+051093Y+067366X0110Y0590R270 S2      
327NNAME10910       U129  -37         A01X+051093Y+067562X0110Y0590R270 S2      
327NNAME10908       R994  -1          A10X+050858Y+066640X0180Y0200     S1      
327NNAME10909       R988  -1          A10X+050988Y+067049X0180Y0200     S1      
327NNAME10881       R982  -2          A10X+051129Y+067466X0180Y0200     S1      
327NNAME10910       R982  -1          A10X+050814Y+067466X0180Y0200     S1      
317P3V3_NODE1       VIA   -     D0100PA00X+049804Y+067531               S3      
317P3V3_NODE1       VIA   -     D0100PA00X+049887Y+066832               S3      
317NNAME10909       VIA   -     D0100PA00X+050411Y+067083               S1      
317NNAME10880       VIA   -     D0100PA00X+049645Y+067088               S1      
317NNAME10910       VIA   -     D0100PA00X+050191Y+067562               S1      
317NNAME10908       VIA   -     D0100PA00X+050424Y+066581               S1      
317NNAME10852       VIA   -     D0100PA00X+049732Y+066522               S1      
327NNAME10820       U129  -36         A01X+051093Y+067759X0110Y0590R270 S2      
327NNAME10911       U129  -35         A01X+051093Y+067956X0110Y0590R270 S2      
327NNAME10833       U129  -34         A01X+051093Y+068153X0110Y0590R270 S2      
327NNAME10831       U129  -33         A01X+051093Y+068350X0110Y0590R270 S2      
327GND              U129  -32         A01X+051093Y+068547X0110Y0590R270 S2      
327P3V3_NODE1       U129  -31         A01X+051093Y+068744X0110Y0590R270 S2      
327CPLD_EXT_RST_N   U129  -30         A01X+051093Y+068940X0110Y0590R270 S2      
327NNAME10834       U129  -29         A01X+051093Y+069137X0110Y0590R270 S2      
327GND              C900  -2          A01X+049686Y+068767X0180Y0200     S2      
327P3V3_NODE1       C900  -1          A01X+050001Y+068767X0180Y0200     S2      
327NNAME10911       R976  -1          A10X+050982Y+067900X0180Y0200     S1      
317P3V3_NODE1       VIA   -     D0100PA00X+050638Y+068744               S3      
317NNAME10831       VIA   -     D0100PA00X+050647Y+068351               S3      
317NNAME10879       VIA   -     D0100PA00X+049658Y+068455               S1      
317NNAME10911       VIA   -     D0100PA00X+050558Y+067911               S1      
317NNAME10820       VIA   -     D0100PA00X+049628Y+067819               S1      
317NNAME10833       VIA   -     D0100PA00X+050154Y+068197               S1      
317NNAME10834       VIA   -     D0100PA00X+050641Y+069137               S1      
327NNAME10837       U129  -28         A01X+051093Y+069334X0110Y0590R270 S2      
327NNAME10853       U129  -27         A01X+051093Y+069531X0110Y0590R270 S2      
327NNAME10855       U129  -26         A01X+051093Y+069728X0110Y0590R270 S2      
327P5V_NODE1        R723  -2          A01X+049660Y+070658X0180Y0200R180 S2      
317P5V_NODE1        VIA   -     D0100PA00X+050071Y+070658               S3      
317T8_NODE1_EN      VIA   -     D0100PA00X+049735Y+069977               S1      
317NNAME10853       VIA   -     D0100PA00X+050609Y+069758               S1      
327P5V_NODE1        R721  -2          A01X+049660Y+071458X0180Y0200R180 S2      
327P5V_NODE1        R720  -2          A01X+049660Y+071858X0180Y0200R180 S2      
327P5V_NODE1        R722  -2          A01X+049660Y+071058X0180Y0200R180 S2      
317NNAME10912       VIA   -     D0100PA00X+051061Y+071745               S3      
317P5V_NODE1        VIA   -     D0100PA00X+049984Y+071058               S3      
317P5V_NODE1        VIA   -     D0100PA00X+049945Y+071458               S3      
327GND              C764  -2          A01X+050014Y+073908X0180Y0200R090 S2      
327GND              C740  -2          A01X+050414Y+073908X0180Y0200R090 S2      
327GND              C623  -2          A01X+049584Y+073908X0180Y0200R090 S2      
327GND              C761  -2          A01X+050494Y+072758X0180Y0200R090 S2      
327NNAME10913       C761  -1          A01X+050494Y+073073X0180Y0200R090 S2      
327NNAME10892       R971  -2          A01X+050967Y+073063X0180Y0200R270 S2      
327NNAME10914       R971  -1          A01X+050967Y+072748X0180Y0200R270 S2      
327NNAME10913       R998  -1          A01X+050814Y+073908X0180Y0200R270 S2      
327NNAME10890       R974  -2          A01X+049694Y+073073X0180Y0200R270 S2      
327NNAME10889       R974  -1          A01X+049694Y+072758X0180Y0200R270 S2      
317GND              VIA   -     D0100PA00X+050289Y+073635               S3      
317GND              VIA   -     D0100PA00X+050611Y+072413               S3      
317NNAME10890       VIA   -     D0100PA00X+049808Y+073325               S3      
317NNAME10914       VIA   -     D0100PA00X+050986Y+072411               S3      
317NNAME10889       VIA   -     D0100PA00X+050026Y+072909               S3      
317NNAME10913       VIA   -     D0100PA00X+050160Y+073300               S1      
327NNAME10915       C764  -1          A01X+050014Y+074223X0180Y0200R090 S2      
327NNAME10891       C740  -1          A01X+050414Y+074223X0180Y0200R090 S2      
327T8_NODE1_EN_R    C623  -1          A01X+049584Y+074223X0180Y0200R090 S2      
327NNAME10916       R998  -2          A01X+050814Y+074223X0180Y0200R270 S2      
317NNAME10891       VIA   -     D0100PA00X+050189Y+074666               S1      
327NNAME10893       VIA   -           A10X+049788Y+078589X0260Y0260     S1      
327NNAME10917       VIA   -           A10X+050900Y+077542X0260Y0260     S1      
327NNAME10918       VIA   -           A10X+050248Y+078238X0260Y0260     S1      
317NNAME10919       VIA   -     D0100PA00X+050794Y+078570               S1      
317NNAME10920       VIA   -     D0100PA00X+051177Y+077994               S1      
317NNAME10915       VIA   -     D0100PA00X+049927Y+077643               S1      
317NNAME10916       VIA   -     D0100PA00X+050444Y+077255               S1      
327GND              J18   -A59        A10X+050006Y+080787X0300Y1660R180 S1      
327NNAME10918       J18   -A58        A10X+050400Y+080787X0300Y1660R180 S1      
327NNAME10917       J18   -A57        A10X+050794Y+080787X0300Y1660R180 S1      
327NNAME10921       J18   -A56        A10X+051187Y+080787X0300Y1660R180 S1      
327NNAME10915       J18   -B59        A01X+050006Y+080787X0300Y1660R180 S2      
327NNAME10916       J18   -B58        A01X+050400Y+080787X0300Y1660R180 S2      
327NNAME10919       J18   -B57        A01X+050794Y+080787X0300Y1660R180 S2      
327NNAME10920       J18   -B56        A01X+051187Y+080787X0300Y1660R180 S2      
317GND              VIA   -     D0100PA00X+050006Y+079148               S3      
317GND              VIA   -     D0100PA00X+049612Y+079148               S3      
317GND              J20   -10   D0460PA00X+051478Y+002880               S0      
317N/C              J20   -8    D0460PA00X+052478Y+002880               S0      
317JTAG_CPLD1_TDI   J20   -9    D0460PA00X+051478Y+003880               S0      
317N/C              J20   -7    D0460PA00X+052478Y+003880               S0      
317NNAME10503       VIA   -     D0100PA00X+051312Y+007207               S1      
327SIO_PIN81        R1146 -2          A01X+052096Y+010618X0180Y0200R270 S2      
327P3V3_STB_NODE1   R1146 -1          A01X+052096Y+010303X0180Y0200R270 S2      
327SIO_PIN80        R1145 -2          A01X+051696Y+010618X0180Y0200R270 S2      
327P3V3_STB_NODE1   R1145 -1          A01X+051696Y+010303X0180Y0200R270 S2      
327SIO_PIN78        R1144 -2          A01X+051296Y+010618X0180Y0200R270 S2      
327P3V3_STB_NODE1   R1144 -1          A01X+051296Y+010303X0180Y0200R270 S2      
327SIO_PIN82        R1147 -2          A01X+052496Y+010618X0180Y0200R270 S2      
327P3V3_STB_NODE1   R1147 -1          A01X+052496Y+010303X0180Y0200R270 S2      
317P3V3_STB_NODE1   VIA   -     D0100PA00X+051296Y+010043               S3      
317P3V3_STB_NODE1   VIA   -     D0100PA00X+052496Y+009936               S3      
317P3V3_STB_NODE1   VIA   -     D0100PA00X+051696Y+010033               S3      
317P3V3_STB_NODE1   VIA   -     D0100PA00X+052096Y+010044               S3      
317SIO_PIN76        VIA   -     D0100PA00X+051288Y+010864               S1      
317SIO_PIN80        VIA   -     D0100PA00X+051963Y+010854               S1      
317SIO_PIN82        VIA   -     D0100PA00X+052684Y+010831               S1      
327SIO_PIN83        U43   -83         A01X+052662Y+011842X0110Y0710R180 S2      
327SIO_PIN82        U43   -82         A01X+052465Y+011842X0110Y0710R180 S2      
327SIO_PIN81        U43   -81         A01X+052268Y+011842X0110Y0710R180 S2      
327SIO_PIN80        U43   -80         A01X+052072Y+011842X0110Y0710R180 S2      
327N/C              U43   -79         A01X+051875Y+011842X0110Y0710R180 S2      
327SIO_PIN78        U43   -78         A01X+051678Y+011842X0110Y0710R180 S2      
327UART_TX_P6       U43   -77         A01X+051481Y+011842X0110Y0710R180 S2      
327SIO_PIN76        U43   -76         A01X+051284Y+011842X0110Y0710R180 S2      
327UART_RI_P6_N     R776  -2          A10X+051247Y+012051X0180Y0200R180 S1      
327P3V3_NODE1       R776  -1          A10X+051562Y+012051X0180Y0200R180 S1      
317P3V3_NODE1       VIA   -     D0100PA00X+052557Y+012462               S3      
317SIO_PIN78        VIA   -     D0100PA00X+051615Y+011312               S1      
317SIO_PIN81        VIA   -     D0100PA00X+052211Y+011331               S1      
327GND              R1209 -2          A10X+051544Y+013769X0180Y0200     S1      
327NNAME10894       R1209 -1          A10X+051229Y+013769X0180Y0200     S1      
317GND              VIA   -     D0100PA00X+051825Y+013769               S3      
317UART_TX_P6       VIA   -     D0100PA00X+051864Y+012554               S1      
327NNAME10894       VIA   -           A10X+051451Y+013309X0260Y0260     S1      
327NNAME10896       VIA   -           A10X+052245Y+013767X0260Y0260     S1      
327JTAG_CPLD2_TDI   R1081 -2          A10X+051540Y+015380X0180Y0200R180 S1      
327NNAME10922       R1081 -1          A10X+051855Y+015380X0180Y0200R180 S1      
327GND              R1206 -2          A10X+051546Y+014219X0180Y0200     S1      
327NNAME10896       R1206 -1          A10X+051231Y+014219X0180Y0200     S1      
317GND              VIA   -     D0100PA00X+051848Y+014140               S3      
317GND              VIA   -     D0100PA00X+052735Y+015225               S3      
327NNAME10922       VIA   -           A10X+052310Y+015310X0260Y0260     S1      
327NNAME10895       VIA   -           A10X+051260Y+014750X0260Y0260     S1      
327JTAG_CPLD2_TMS   R1079 -2          A10X+051538Y+015994X0180Y0200R180 S1      
327NNAME10923       R1079 -1          A10X+051853Y+015994X0180Y0200R180 S1      
327P3V3_NODE1       R1329 -2          A10X+052132Y+017053X0180Y0200R270 S1      
317GND              VIA   -     D0100PA00X+052688Y+016184               S3      
317P3V3_NODE1       VIA   -     D0100PA00X+051873Y+017053               S3      
327NNAME10923       VIA   -           A10X+052310Y+015940X0260Y0260     S1      
327UART_DSR_P4_N    U43   -27         A01X+051284Y+018583X0110Y0710R180 S2      
327NNAME10924       U43   -26         A01X+051481Y+018583X0110Y0710R180 S2      
327N/C              U43   -25         A01X+051678Y+018583X0110Y0710R180 S2      
327N/C              U43   -24         A01X+051875Y+018583X0110Y0710R180 S2      
327NNAME10925       U43   -23         A01X+052072Y+018583X0110Y0710R180 S2      
327UART_CTS_P4_N    U43   -22         A01X+052268Y+018583X0110Y0710R180 S2      
327UART_RI_P4_R_N   U43   -21         A01X+052465Y+018583X0110Y0710R180 S2      
327UART_DCD_P4_N    U43   -20         A01X+052662Y+018583X0110Y0710R180 S2      
327UART_DCD_P4_N    R1322 -2          A10X+052540Y+018648X0180Y0200R090 S1      
327P5V_NODE1        R1322 -1          A10X+052540Y+018333X0180Y0200R090 S1      
327UART_CTS_P4_N    R1325 -2          A10X+051688Y+018260X0180Y0200     S1      
327P5V_NODE1        R1325 -1          A10X+051373Y+018260X0180Y0200     S1      
327UART_RI_P4_R_N   R1324 -2          A10X+052140Y+018648X0180Y0200R090 S1      
327UART_RI_P4_N     R1324 -1          A10X+052140Y+018333X0180Y0200R090 S1      
327UART_RI_P4_N     R1329 -1          A10X+052132Y+017368X0180Y0200R270 S1      
317P5V_NODE1        VIA   -     D0100PA00X+051260Y+017890               S3      
317UART_RI_P3_N     VIA   -     D0100PA00X+051560Y+017280               S1      
317UART_RI_P4_N     VIA   -     D0100PA00X+052132Y+017818               S1      
317UART_CTS_P4_N    VIA   -     D0100PA00X+051610Y+017810               S1      
317UART_DCD_P4_N    VIA   -     D0100PA00X+052662Y+017708               S1      
327NNAME10924       R1164 -1          A01X+051666Y+020099X0180Y0200R270 S2      
327NNAME10925       R1163 -1          A01X+052050Y+020093X0180Y0200R270 S2      
327UART_RI_P4_R_N   R615  -2          A01X+052450Y+020093X0180Y0200R090 S2      
327UART_DSR_P4_N    R1323 -2          A01X+051220Y+019863X0180Y0200R090 S2      
327P5V_NODE1        R1323 -1          A01X+051220Y+020178X0180Y0200R090 S2      
317P5V_NODE1        VIA   -     D0100PA00X+051220Y+020420               S3      
317UART_TX_P3       VIA   -     D0100PA00X+052644Y+019412               S3      
317UART_TX_P4       VIA   -     D0100PA00X+051450Y+019430               S3      
317UART_RX_P3       VIA   -     D0100PA00X+052529Y+019171               S3      
317NNAME10924       VIA   -     D0100PA00X+051523Y+019133               S1      
317NNAME10925       VIA   -     D0100PA00X+052002Y+019458               S1      
317UART_RI_P4_R_N   VIA   -     D0100PA00X+052359Y+019817               S1      
317UART_DSR_P4_N    VIA   -     D0100PA00X+051220Y+019600               S1      
327UART_RI_P4_N     U145  -2          A10X+052361Y+021890X0130Y0460R270 S1      
327N/C              U145  -1          A10X+052361Y+021634X0130Y0460R270 S1      
327GND              C538  -2          A01X+051216Y+021145X0180Y0200R090 S2      
327P3V3_NODE1       C538  -1          A01X+051216Y+021460X0180Y0200R090 S2      
327UART_RTS_P4_N    R1164 -2          A01X+051666Y+020414X0180Y0200R270 S2      
327UART_DTR_P4_N    R1163 -2          A01X+052050Y+020408X0180Y0200R270 S2      
327P5V_NODE1        R615  -1          A01X+052450Y+020408X0180Y0200R090 S2      
327GND              R1326 -2          A01X+052180Y+021468X0180Y0200R270 S2      
327UART_RI_P4_R_N   R1326 -1          A01X+052180Y+021153X0180Y0200R270 S2      
317GND              VIA   -     D0100PA00X+051200Y+020773               S3      
317UART_DTR_P4_N    VIA   -     D0100PA00X+052007Y+020714               S1      
317UART_RTS_P4_N    VIA   -     D0100PA00X+051655Y+021499               S1      
317P3V3_NODE1       VIA   -     D0100PA00X+051216Y+021707               S3      
317P5V_NODE1        VIA   -     D0100PA00X+052666Y+020736               S3      
317UART_TX_P3       VIA   -     D0100PA00X+052441Y+021253               S3      
317UART_TX_P4       VIA   -     D0100PA00X+051477Y+020822               S3      
327GND              U145  -3          A10X+052361Y+022146X0130Y0460R270 S1      
327GND              C539  -2          A01X+051350Y+022147X0180Y0200R090 S2      
327P3V3_NODE1       C539  -1          A01X+051350Y+022462X0180Y0200R090 S2      
327GND              C599  -2          A10X+051406Y+023008X0180Y0200R090 S1      
327P3V3_NODE1       C599  -1          A10X+051406Y+022693X0180Y0200R090 S1      
317GND              VIA   -     D0100PA00X+051918Y+022417               S3      
317GND              VIA   -     D0100PA00X+051930Y+022050               S3      
317GND              VIA   -     D0100PA00X+051663Y+023008               S3      
317P3V3_NODE1       VIA   -     D0100PA00X+051568Y+023456               S3      
317P3V3_NODE1       VIA   -     D0100PA00X+052468Y+023477               S3      
317P3V3_NODE1       VIA   -     D0100PA00X+051719Y+022623               S3      
327NNAME10926       U31   -1          A01X+052259Y+025058X0220Y0680R090 S2      
327NNAME10927       R519  -2          A01X+051968Y+023831X0180Y0200R090 S2      
327NNAME10928       R519  -1          A01X+051968Y+024146X0180Y0200R090 S2      
327P3V3_NODE1       R516  -2          A01X+051568Y+023831X0180Y0200R090 S2      
327NNAME10928       R516  -1          A01X+051568Y+024146X0180Y0200R090 S2      
327N21116716        R653  -2          A01X+052468Y+024146X0180Y0200R270 S2      
327P3V3_NODE1       R653  -1          A01X+052468Y+023831X0180Y0200R270 S2      
317NNAME10926       VIA   -     D0100PA00X+051767Y+024753               S1      
327GND              U31   -4          A01X+052259Y+026558X0220Y0680R090 S2      
327N21116716        U31   -3          A01X+052259Y+026058X0220Y0680R090 S2      
327NNAME10928       U31   -2          A01X+052259Y+025558X0220Y0680R090 S2      
317NNAME10928       VIA   -     D0100PA00X+051568Y+025410               S1      
317NNAME10884       VIA   -     D0100PA00X+052548Y+026896               S1      
317P1V8_NODE1       VIA   -     D0100PA00X+051859Y+031013               S3      
317P1V8_NODE1       VIA   -     D0100PA00X+052625Y+031094               S3      
317P1V8_NODE1       VIA   -     D0100PA00X+051965Y+032038               S3      
317P1V8_NODE1       VIA   -     D0100PA00X+052242Y+031548               S3      
317P1V8_NODE1       VIA   -     D0100PA00X+051726Y+031598               S3      
317P1V8_NODE1       VIA   -     D0100PA00X+052393Y+032164               S3      
317P1V0_NODE1       VIA   -     D0100PA00X+051440Y+034083               S3      
317P1V0_NODE1       VIA   -     D0100PA00X+052051Y+033730               S3      
317P1V0_NODE1       VIA   -     D0100PA00X+052744Y+034035               S1      
317GND              VIA   -     D0100PA00X+051762Y+042294               S1      
317GND              VIA   -     D0100PA00X+051482Y+041762               S1      
317P3V3_CLK_NODE1   VIA   -     D0100PA00X+052644Y+042243               S1      
317P3V3_CLK_NODE1   VIA   -     D0100PA00X+052730Y+041737               S1      
327GND              C12   -2          A01X+051578Y+043673X0180Y0200R180 S2      
327NNAME10899       C12   -1          A01X+051263Y+043673X0180Y0200R180 S2      
327P3V3_CLK_NODE1   R11   -2          A01X+052644Y+042508X0180Y0200R090 S2      
327NNAME10929       R11   -1          A01X+052644Y+042823X0180Y0200R090 S2      
327NNAME10930       R9    -2          A01X+051984Y+043098X0180Y0200R090 S2      
327NNAME10931       R9    -1          A01X+051984Y+043413X0180Y0200R090 S2      
327NNAME10929       R17   -2          A01X+052644Y+043773X0180Y0200R270 S2      
327GND              R17   -1          A01X+052644Y+043458X0180Y0200R270 S2      
317GND              VIA   -     D0100PA00X+052644Y+043208               S3      
317GND              VIA   -     D0100PA00X+051578Y+043404               S3      
317NNAME10931       VIA   -     D0100PA00X+051793Y+043968               S1      
317NNAME10004       VIA   -     D0100PA00X+052367Y+043845               S3      
317NNAME10006       VIA   -     D0100PA00X+052238Y+043197               S3      
327CLK_FSLB_NODE1   U1    -9          A01X+052580Y+044868X0070Y0350     S2      
327NNAME10929       U1    -8          A01X+052423Y+044868X0070Y0350     S2      
327P3V3_CLK_NODE1   U1    -7          A01X+052265Y+044868X0070Y0350     S2      
327NNAME10004       U1    -6          A01X+052108Y+044868X0070Y0350     S2      
327NNAME10006       U1    -5          A01X+051950Y+044868X0070Y0350     S2      
327NNAME10931       U1    -4          A01X+051793Y+044868X0070Y0350     S2      
327P3V3_CLK_NODE1   U1    -3          A01X+051635Y+044868X0070Y0350     S2      
327NNAME10899       U1    -2          A01X+051478Y+044868X0070Y0350     S2      
327NNAME10898       U1    -1          A01X+051320Y+044868X0070Y0350     S2      
327GND              U1    -TH         A01X+052344Y+046266X2280Y2280R090 S2      
327GND              C2    -2          A10X+051758Y+045005X0180Y0200R090 S1      
327P3V3_CLK_NODE1   C2    -1          A10X+051758Y+044690X0180Y0200R090 S1      
327GND              C4    -2          A10X+052264Y+045030X0180Y0200R090 S1      
327P3V3_CLK_NODE1   C4    -1          A10X+052264Y+044715X0180Y0200R090 S1      
327GND              C1    -2          A10X+051370Y+045599X0280Y0320R270 S1      
327NNAME10899       R4    -1          A01X+051238Y+044113X0180Y0200     S2      
317GND              VIA   -     D0100PA00X+051314Y+045262               S3      
317GND              VIA   -     D0100PA00X+051944Y+045232               S3      
317GND              VIA   -     D0100PA00X+052634Y+045232               S3      
317NNAME10899       VIA   -     D0100PA00X+051287Y+044368               S1      
317P3V3_CLK_NODE1   VIA   -     D0100PA00X+051635Y+044352               S3      
317P3V3_CLK_NODE1   VIA   -     D0100PA00X+052384Y+044272               S3      
327GND              C10   -2          A10X+051181Y+046322X0180Y0200     S1      
327GND              C7    -2          A10X+051181Y+046872X0180Y0200     S1      
317GND              VIA   -     D0100PA00X+051314Y+045972               S3      
317GND              VIA   -     D0100PA00X+051314Y+046602               S3      
327NNAME10192       U1    -42         A01X+051320Y+047663X0070Y0350     S2      
327NNAME10191       U1    -41         A01X+051478Y+047663X0070Y0350     S2      
327GND              U1    -40         A01X+051635Y+047663X0070Y0350     S2      
327NNAME10932       U1    -39         A01X+051793Y+047663X0070Y0350     S2      
327NNAME10933       U1    -38         A01X+051950Y+047663X0070Y0350     S2      
327NNAME10272       U1    -37         A01X+052108Y+047663X0070Y0350     S2      
327NNAME10273       U1    -36         A01X+052265Y+047663X0070Y0350     S2      
327PCI_STP_NODE1    U1    -35         A01X+052423Y+047663X0070Y0350     S2      
327NNAME10902       U1    -34         A01X+052580Y+047663X0070Y0350     S2      
317GND              VIA   -     D0100PA00X+052564Y+047302               S3      
317GND              VIA   -     D0100PA00X+051964Y+047302               S3      
317GND              VIA   -     D0100PA00X+051314Y+047302               S3      
317GND              VIA   -     D0100PA00X+051635Y+048071               S3      
317NNAME10902       VIA   -     D0100PA00X+052560Y+048019               S3      
317PCI_STP_NODE1    VIA   -     D0100PA00X+052564Y+048402               S1      
317GND              VIA   -     D0100PA00X+051949Y+049665               S3      
317GND              VIA   -     D0100PA00X+052570Y+049672               S3      
317NNAME10272       VIA   -     D0100PA00X+051994Y+049313               S3      
317NNAME10273       VIA   -     D0100PA00X+052494Y+049313               S3      
327NNAME10934       C189  -2          A01X+052547Y+051215X0180Y0200R090 S2      
327NNAME10935       C189  -1          A01X+052547Y+051530X0180Y0200R090 S2      
317GND              VIA   -     D0100PA00X+052225Y+051369               S3      
317NNAME10903       VIA   -     D0100PA00X+051443Y+051180               S3      
317NNAME10936       VIA   -     D0100PA00X+051943Y+051180               S3      
327P1V0_PCI_SW_A    U125  -113        A01X+052653Y+053475X0070Y0600R180 S2      
327P1V0_PCI_SW_A    U125  -112        A01X+052495Y+053475X0070Y0600R180 S2      
327GND              U125  -111        A01X+052338Y+053475X0070Y0600R180 S2      
327P1V0_NODE1       U125  -110        A01X+052180Y+053475X0070Y0600R180 S2      
327NNAME10063       U125  -109        A01X+052023Y+053475X0070Y0600R180 S2      
327NNAME10937       U125  -108        A01X+051865Y+053475X0070Y0600R180 S2      
327NNAME10935       U125  -107        A01X+051708Y+053475X0070Y0600R180 S2      
327P1V0_NODE1       U125  -106        A01X+051550Y+053475X0070Y0600R180 S2      
327GND              U125  -105        A01X+051393Y+053475X0070Y0600R180 S2      
327NNAME10936       U125  -104        A01X+051235Y+053475X0070Y0600R180 S2      
327GND              C930  -2          A10X+052664Y+053335X0180Y0200R270 S1      
327GND              C893  -2          A10X+051884Y+053335X0180Y0200R270 S1      
327GND              C876  -2          A10X+051494Y+053335X0180Y0200R270 S1      
327GND              C873  -2          A10X+052274Y+053335X0180Y0200R270 S1      
317GND              VIA   -     D0100PA00X+052714Y+052953               S3      
317GND              VIA   -     D0100PA00X+052394Y+052873               S3      
317GND              VIA   -     D0100PA00X+051511Y+052879               S3      
327NNAME10937       VIA   -           A01X+051999Y+052664X0160Y0050R315 S2      
327NNAME10935       VIA   -           A01X+052509Y+052218X0160Y0050R315 S2      
327P1V0_PCI_SW_A    C930  -1          A10X+052664Y+053650X0180Y0200R270 S1      
327GND              C895  -2          A10X+052196Y+054303X0180Y0200R180 S1      
327P1V0_PCI_SW_A    C895  -1          A10X+052511Y+054303X0180Y0200R180 S1      
327NNAME10063       C893  -1          A10X+051884Y+053650X0180Y0200R270 S1      
327P1V0_NODE1       C876  -1          A10X+051494Y+053650X0180Y0200R270 S1      
327P1V0_NODE1       C873  -1          A10X+052274Y+053650X0180Y0200R270 S1      
317GND              VIA   -     D0100PA00X+051944Y+054303               S3      
317GND              VIA   -     D0100PA00X+051348Y+054150               S3      
317NNAME10063       VIA   -     D0100PA00X+051894Y+054043               S3      
317P1V0_NODE1       VIA   -     D0100PA00X+052194Y+054033               S3      
317P1V0_NODE1       VIA   -     D0100PA00X+051638Y+054036               S3      
317P1V0_PCI_SW_A    VIA   -     D0100PA00X+052534Y+054013               S3      
327P1V0_PCI_SW_A    VIA   -           A10X+052485Y+054876X0260Y0260     S1      
317GND              VIA   -     D0100PA00X+051384Y+055693               S3      
317P1V0_NODE1       VIA   -     D0100PA00X+051674Y+056243               S3      
317P1V0_NODE1       VIA   -     D0100PA00X+051374Y+056243               S3      
327P1V0_PCI_SW_A    VIA   -           A10X+051400Y+056868X0260Y0260     S1      
327GND              U125  -57         A01X+051235Y+059577X0070Y0600R180 S2      
327NNAME10938       U125  -56         A01X+051393Y+059577X0070Y0600R180 S2      
327P3V3_NODE1       U125  -55         A01X+051550Y+059577X0070Y0600R180 S2      
327N/C              U125  -54         A01X+051708Y+059577X0070Y0600R180 S2      
327GND              U125  -53         A01X+051865Y+059577X0070Y0600R180 S2      
327P1V0_NODE1       U125  -52         A01X+052023Y+059577X0070Y0600R180 S2      
327N/C              U125  -51         A01X+052180Y+059577X0070Y0600R180 S2      
327GND              U125  -50         A01X+052338Y+059577X0070Y0600R180 S2      
327P1V0_NODE1       U125  -49         A01X+052495Y+059577X0070Y0600R180 S2      
327P3V3_NODE1       U125  -48         A01X+052653Y+059577X0070Y0600R180 S2      
327GND              C875  -2          A10X+051964Y+059720X0180Y0200R090 S1      
327P1V0_NODE1       C875  -1          A10X+051964Y+059405X0180Y0200R090 S1      
327GND              C871  -2          A10X+051226Y+059463X0180Y0200R180 S1      
327P3V3_NODE1       C871  -1          A10X+051541Y+059463X0180Y0200R180 S1      
327GND              C331  -2          A10X+052354Y+059730X0180Y0200R090 S1      
327P1V0_NODE1       C331  -1          A10X+052354Y+059415X0180Y0200R090 S1      
317GND              VIA   -     D0100PA00X+051235Y+059083               S3      
317P3V3_NODE1       VIA   -     D0100PA00X+051541Y+059095               S3      
327P1V0_NODE1       VIA   -           A10X+052581Y+058267X0260Y0260     S1      
317P1V0_NODE1       VIA   -     D0100PA00X+052464Y+059023               S3      
317P1V0_NODE1       VIA   -     D0100PA00X+052023Y+059034               S3      
327PCIE_SW_P0_ERR   R299  -2          A01X+052664Y+061120X0180Y0200R270 S2      
327P3V3_NODE1       R299  -1          A01X+052664Y+060805X0180Y0200R270 S2      
327NNAME10938       R297  -2          A01X+051528Y+060904X0180Y0200R180 S2      
327P3V3_NODE1       R297  -1          A01X+051213Y+060904X0180Y0200R180 S2      
317GND              VIA   -     D0100PA00X+051964Y+060043               S3      
317GND              VIA   -     D0100PA00X+052354Y+060033               S3      
317GND              VIA   -     D0100PA00X+052744Y+060033               S3      
317P3V3_NODE1       VIA   -     D0100PA00X+052557Y+060247               S3      
317NNAME10938       VIA   -     D0100PA00X+051406Y+060506               S1      
317PCIE_SW_P0_ERR   VIA   -     D0100PA00X+052380Y+061115               S3      
327PMBUS3_EN        R1284 -2          A01X+052161Y+061539X0180Y0200     S2      
327P5V_NODE1        R1284 -1          A01X+052476Y+061539X0180Y0200     S2      
327UART_RI_P6_N     R1069 -2          A10X+051253Y+062679X0180Y0200R270 S1      
327GND              U140  -S          A10X+052078Y+062960X0400Y0500     S1      
327I2C_PSU3_SDA     U127  -D          A01X+052628Y+062960X0400Y0500     S2      
327PMBUS3_EN        U127  -G          A01X+052228Y+062080X0400Y0500     S2      
327PMBUS3_EN        U139  -G          A01X+051624Y+062897X0400Y0500R180 S2      
317UART_RI_P6_N     VIA   -     D0100PA00X+052037Y+062516               S3      
317NNAME10877       VIA   -     D0100PA00X+052630Y+062362               S1      
317PMBUS3_EN        VIA   -     D0100PA00X+051892Y+061539               S1      
327NNAME10939       U129  -55         A01X+052569Y+064314X0110Y0590     S2      
327NNAME10940       U129  -54         A01X+052372Y+064314X0110Y0590     S2      
327NNAME10941       U129  -53         A01X+052176Y+064314X0110Y0590     S2      
327NNAME10942       U129  -52         A01X+051979Y+064314X0110Y0590     S2      
327CPLD3_RSV3       U129  -51         A01X+051782Y+064314X0110Y0590     S2      
327NNAME10000       R1069 -1          A10X+051253Y+062994X0180Y0200R270 S1      
327CPLD3_RSV3       R775  -2          A01X+051694Y+063445X0180Y0200R180 S2      
327CPLD123_RSV3     R775  -1          A01X+051379Y+063445X0180Y0200R180 S2      
327TACKOVER_EN      U140  -D          A10X+052478Y+063840X0400Y0500     S1      
317GND              VIA   -     D0100PA00X+051983Y+063466               S3      
317P3V3_NODE1       VIA   -     D0100PA00X+051191Y+063872               S3      
317CPLD3_RSV3       VIA   -     D0100PA00X+051432Y+064109               S1      
327TACKOVER_EN      R1309 -2          A10X+052440Y+064521X0180Y0200R180 S1      
327NNAME10832       R1000 -2          A10X+051307Y+065501X0180Y0200     S1      
317GND              VIA   -     D0100PA00X+051537Y+065888               S3      
317NNAME10832       VIA   -     D0100PA00X+051544Y+065000               S3      
317NNAME10939       VIA   -     D0100PA00X+052569Y+065486               S1      
317NNAME10907       VIA   -     D0100PA00X+051733Y+065553               S1      
317NNAME10941       VIA   -     D0100PA00X+052152Y+065058               S1      
327NNAME10841       R994  -2          A10X+051173Y+066640X0180Y0200     S1      
327NNAME10851       R988  -2          A10X+051303Y+067049X0180Y0200     S1      
317NNAME10851       VIA   -     D0100PA00X+051781Y+067010               S3      
317NNAME10881       VIA   -     D0100PA00X+051722Y+067392               S1      
317NNAME10841       VIA   -     D0100PA00X+051880Y+066578               S1      
317P3V3_NODE1       VIA   -     D0100PA00X+052661Y+067229               S3      
317CPLD_WDT2        VIA   -     D0100PA00X+051554Y+066185               S1      
317NNAME10940       VIA   -     D0100PA00X+052643Y+066473               S1      
327NNAME10821       R976  -2          A10X+051297Y+067900X0180Y0200     S1      
317GND              VIA   -     D0100PA00X+051543Y+068578               S3      
317NNAME10821       VIA   -     D0100PA00X+051838Y+067825               S3      
317NNAME10837       VIA   -     D0100PA00X+051543Y+069228               S1      
317NNAME10942       VIA   -     D0100PA00X+052660Y+067912               S1      
317CPLD_EXT_RST_N   VIA   -     D0100PA00X+051789Y+068790               S1      
317UART_CMC_RX_P    VIA   -     D0100PA00X+051895Y+068512               S3      
317UART_CMC_TX_P    VIA   -     D0100PA00X+052711Y+068605               S1      
327JTAG_CPLD3_TDO   U129  -25         A01X+051782Y+070417X0110Y0590     S2      
327JTAG_CPLD3_TCK   U129  -24         A01X+051979Y+070417X0110Y0590     S2      
327JTAG_CPLD3_TDI   U129  -23         A01X+052176Y+070417X0110Y0590     S2      
327JTAG_CPLD3_TMS   U129  -22         A01X+052372Y+070417X0110Y0590     S2      
327UART_CMC_RX_P    U129  -21         A01X+052569Y+070417X0110Y0590     S2      
317NNAME10855       VIA   -     D0100PA00X+051543Y+069728               S1      
317GND              VIA   -     D0100PA00X+051850Y+072307               S3      
317NNAME10919       VIA   -     D0100PA00X+051255Y+072209               S1      
317NNAME10915       VIA   -     D0100PA00X+051462Y+071319               S3      
317JTAG_CPLD3_TDO   VIA   -     D0100PA00X+051744Y+071701               S3      
317JTAG_CPLD3_TCK   VIA   -     D0100PA00X+051778Y+071120               S3      
317JTAG_CPLD3_TMS   VIA   -     D0100PA00X+052287Y+071118               S3      
317JTAG_CPLD3_TDI   VIA   -     D0100PA00X+051450Y+071647               S3      
327GND              C755  -2          A01X+051894Y+072698X0180Y0200R090 S2      
327NNAME10943       C755  -1          A01X+051894Y+073013X0180Y0200R090 S2      
327GND              C731  -2          A10X+051494Y+072658X0180Y0200R270 S1      
327NNAME10944       C731  -1          A10X+051494Y+072973X0180Y0200R270 S1      
327GND              C752  -2          A01X+052094Y+073908X0180Y0200R090 S2      
327GND              C728  -2          A10X+051944Y+073808X0180Y0200R270 S1      
327GND              C749  -2          A01X+052394Y+072758X0180Y0200R090 S2      
327NNAME10945       C749  -1          A01X+052394Y+073073X0180Y0200R090 S2      
327GND              C725  -2          A10X+052394Y+072658X0180Y0200R270 S1      
327NNAME10939       C725  -1          A10X+052394Y+072973X0180Y0200R270 S1      
327GND              C758  -2          A01X+051214Y+073908X0180Y0200R090 S2      
327GND              C734  -2          A01X+051494Y+072758X0180Y0200R090 S2      
327NNAME10892       C734  -1          A01X+051494Y+073073X0180Y0200R090 S2      
327NNAME10918       R965  -2          A10X+051944Y+072973X0180Y0200R090 S1      
327NNAME10940       R965  -1          A10X+051944Y+072658X0180Y0200R090 S1      
327NNAME10943       R992  -1          A01X+051694Y+073908X0180Y0200R270 S2      
327NNAME10944       R968  -1          A10X+051494Y+073808X0180Y0200R090 S1      
327NNAME10945       R986  -1          A01X+052544Y+073908X0180Y0200R270 S2      
327NNAME10939       R962  -1          A10X+052394Y+073808X0180Y0200R090 S1      
317GND              VIA   -     D0100PA00X+051944Y+073568               S3      
317GND              VIA   -     D0100PA00X+051214Y+073655               S3      
317GND              VIA   -     D0100PA00X+051490Y+072412               S3      
317GND              VIA   -     D0100PA00X+052337Y+072413               S3      
317NNAME10943       VIA   -     D0100PA00X+051694Y+073568               S3      
317NNAME10939       VIA   -     D0100PA00X+052180Y+073267               S3      
317NNAME10944       VIA   -     D0100PA00X+051442Y+073313               S3      
317NNAME10945       VIA   -     D0100PA00X+052458Y+073323               S3      
327NNAME10912       C752  -1          A01X+052094Y+074223X0180Y0200R090 S2      
327NNAME10918       C728  -1          A10X+051944Y+074123X0180Y0200R270 S1      
327NNAME10919       C758  -1          A01X+051214Y+074223X0180Y0200R090 S2      
327NNAME10920       R992  -2          A01X+051694Y+074223X0180Y0200R270 S2      
327NNAME10893       R968  -2          A10X+051494Y+074123X0180Y0200R090 S1      
327NNAME10946       R986  -2          A01X+052544Y+074223X0180Y0200R270 S2      
327NNAME10917       R962  -2          A10X+052394Y+074123X0180Y0200R090 S1      
317NNAME10892       VIA   -     D0100PA00X+051261Y+074712               S1      
327NNAME10947       VIA   -           A10X+051956Y+077969X0260Y0260     S1      
327NNAME10921       VIA   -           A10X+051443Y+078572X0260Y0260     S1      
317NNAME10946       VIA   -     D0100PA00X+052511Y+077440               S1      
317NNAME10912       VIA   -     D0100PA00X+051944Y+077286               S1      
327T9_NODE4_EN_R    VIA   -           A10X+052368Y+078611X0260Y0260     S1      
327NNAME10947       J18   -A55        A10X+051581Y+080787X0300Y1660R180 S1      
327GND              J18   -A54        A10X+051975Y+080787X0300Y1660R180 S1      
327T9_NODE4_EN_R    J18   -A53        A10X+052368Y+080787X0300Y1660R180 S1      
327T9_NODE3_EN_R    J18   -A52        A10X+052762Y+080787X0300Y1660R180 S1      
327GND              J18   -B55        A01X+051581Y+080787X0300Y1660R180 S2      
327NNAME10912       J18   -B54        A01X+051975Y+080787X0300Y1660R180 S2      
327NNAME10946       J18   -B53        A01X+052368Y+080787X0300Y1660R180 S2      
327NNAME10948       J18   -B52        A01X+052762Y+080787X0300Y1660R180 S2      
317GND              VIA   -     D0100PA00X+051975Y+079148               S3      
317GND              VIA   -     D0100PA00X+051581Y+079148               S3      
317N/C              J20   -6    D0460PA00X+053478Y+002880               S0      
317P3V3_STB_NODE1   J20   -4    D0460PA00X+054478Y+002880               S0      
317JTAG_CPLD1_TMS   J20   -5    D0460PA00X+053478Y+003880               S0      
317JTAG_CPLD1_TDO   J20   -3    D0460PA00X+054478Y+003880               S0      
317P5V_NODE1        VIA   -     D0100PA00X+054218Y+009353               S3      
327GNDA             C485  -2          A01X+053696Y+010303X0180Y0200R090 S2      
327SIO_VREF         C485  -1          A01X+053696Y+010618X0180Y0200R090 S2      
327P5V_NODE1        C491  -1          A01X+054225Y+009719X0280Y0320     S2      
327GND              C491  -2          A01X+054225Y+010299X0280Y0320     S2      
327UART_RTS_P6_N    R1149 -2          A01X+053296Y+010618X0180Y0200R270 S2      
327P3V3_STB_NODE1   R1149 -1          A01X+053296Y+010303X0180Y0200R270 S2      
327SIO_PIN83        R1148 -2          A01X+052896Y+010618X0180Y0200R270 S2      
327P3V3_STB_NODE1   R1148 -1          A01X+052896Y+010303X0180Y0200R270 S2      
317SIO_VREF         VIA   -     D0100PA00X+053951Y+010874               S1      
317GND              VIA   -     D0100PA00X+054225Y+010633               S3      
317GNDA             VIA   -     D0100PA00X+053696Y+010026               S1      
317UART_RTS_P6_N    VIA   -     D0100PA00X+053296Y+010867               S3      
317P3V3_STB_NODE1   VIA   -     D0100PA00X+052896Y+009978               S3      
317P3V3_STB_NODE1   VIA   -     D0100PA00X+053296Y+010060               S3      
327NNAME10949       U43   -91         A01X+054237Y+011842X0110Y0710R180 S2      
327SIO_VREF         U43   -90         A01X+054040Y+011842X0110Y0710R180 S2      
327N/C              U43   -89         A01X+053843Y+011842X0110Y0710R180 S2      
327N/C              U43   -88         A01X+053646Y+011842X0110Y0710R180 S2      
327UART_RI_P6_N     U43   -87         A01X+053450Y+011842X0110Y0710R180 S2      
327GNDA             U43   -86         A01X+053253Y+011842X0110Y0710R180 S2      
327UART_RTS_P6_N    U43   -85         A01X+053056Y+011842X0110Y0710R180 S2      
327N/C              U43   -84         A01X+052859Y+011842X0110Y0710R180 S2      
317GNDA             VIA   -     D0100PA00X+053596Y+011285               S1      
317SIO_PIN83        VIA   -     D0100PA00X+052761Y+011337               S1      
317UART_CTS_P6_N    VIA   -     D0100PA00X+054270Y+011288               S3      
327NNAME10950       R1185 -2          A10X+053385Y+013515X0180Y0200     S1      
327CPLD123_RSV3     R1185 -1          A10X+053070Y+013515X0180Y0200     S1      
327NNAME10950       R1186 -1          A10X+054161Y+013542X0180Y0200     S1      
327NNAME10951       R1184 -1          A10X+054161Y+013942X0180Y0200     S1      
327NNAME10951       R1183 -2          A10X+053385Y+013915X0180Y0200     S1      
327CPLD123_RSV2     R1183 -1          A10X+053070Y+013915X0180Y0200     S1      
327CPLD_WDT3        R1179 -2          A10X+054161Y+015142X0180Y0200R180 S1      
327GND              R1180 -2          A10X+053070Y+015115X0180Y0200R180 S1      
327CPLD_WDT3        R1180 -1          A10X+053385Y+015115X0180Y0200R180 S1      
327NNAME10923       R1190 -2          A10X+054161Y+015542X0180Y0200R180 S1      
327GND              R1191 -2          A10X+053070Y+015515X0180Y0200R180 S1      
327NNAME10923       R1191 -1          A10X+053385Y+015515X0180Y0200R180 S1      
327NNAME10922       R1187 -2          A10X+054161Y+014742X0180Y0200R180 S1      
327NNAME10952       R1181 -2          A10X+053385Y+014315X0180Y0200     S1      
327CPLD123_RSV1     R1181 -1          A10X+053070Y+014315X0180Y0200     S1      
327GND              R1188 -2          A10X+053070Y+014715X0180Y0200R180 S1      
327NNAME10922       R1188 -1          A10X+053385Y+014715X0180Y0200R180 S1      
327NNAME10952       R1182 -1          A10X+054161Y+014342X0180Y0200     S1      
317GND              VIA   -     D0100PA00X+052790Y+014715               S3      
317CPLD_WDT3        VIA   -     D0100PA00X+053866Y+015142               S3      
327JTAG_CPLD2_TCK   R1119 -2          A10X+053056Y+016733X0180Y0200R180 S1      
327NNAME10953       R1119 -1          A10X+053371Y+016733X0180Y0200R180 S1      
327JTAG_CPLD2_TDO   R1080 -2          A10X+054161Y+016342X0180Y0200R180 S1      
327GND              R1192 -2          A10X+053070Y+016315X0180Y0200R180 S1      
327NNAME10953       R1192 -1          A10X+053385Y+016315X0180Y0200R180 S1      
327P3V3_NODE1       R1065 -2          A10X+054161Y+015942X0180Y0200R180 S1      
317P3V3_NODE1       VIA   -     D0100PA00X+053829Y+015942               S3      
327NNAME10953       VIA   -           A10X+053897Y+016884X0260Y0260     S1      
327UART_RX_P3       U43   -19         A01X+052859Y+018583X0110Y0710R180 S2      
327UART_TX_P3_R     U43   -18         A01X+053056Y+018583X0110Y0710R180 S2      
327UART_DSR_P3_N    U43   -17         A01X+053253Y+018583X0110Y0710R180 S2      
327NNAME10954       U43   -16         A01X+053450Y+018583X0110Y0710R180 S2      
327GND              U43   -15         A01X+053646Y+018583X0110Y0710R180 S2      
327NNAME10955       U43   -14         A01X+053843Y+018583X0110Y0710R180 S2      
327UART_CTS_P3_N    U43   -13         A01X+054040Y+018583X0110Y0710R180 S2      
327UART_RI_P3_N     U43   -12         A01X+054237Y+018583X0110Y0710R180 S2      
327NNAME10954       R1137 -2          A10X+053377Y+018642X0180Y0200R090 S1      
327GND              R1137 -1          A10X+053377Y+018327X0180Y0200R090 S1      
327NNAME10955       R1133 -2          A10X+053793Y+018643X0180Y0200R090 S1      
327GND              R1133 -1          A10X+053793Y+018328X0180Y0200R090 S1      
327NNAME10954       R1136 -2          A10X+052927Y+018646X0180Y0200R090 S1      
327P5V_NODE1        R1136 -1          A10X+052927Y+018331X0180Y0200R090 S1      
327NNAME10955       R1132 -2          A10X+054200Y+018643X0180Y0200R090 S1      
327P5V_NODE1        R1132 -1          A10X+054200Y+018328X0180Y0200R090 S1      
317GND              VIA   -     D0100PA00X+053348Y+017745               S3      
317GND              VIA   -     D0100PA00X+053380Y+018076               S3      
317P5V_NODE1        VIA   -     D0100PA00X+052927Y+017831               S3      
317P5V_NODE1        VIA   -     D0100PA00X+054200Y+018010               S3      
327UART_DSR_P3_N    R614  -2          A01X+053250Y+020093X0180Y0200R090 S2      
327NNAME10955       R1155 -1          A01X+054050Y+020093X0180Y0200R270 S2      
327UART_TX_P3_R     R1159 -1          A01X+052850Y+020093X0180Y0200R270 S2      
327NNAME10954       R1157 -1          A01X+053666Y+020099X0180Y0200R270 S2      
317NNAME10955       VIA   -     D0100PA00X+053950Y+019650               S1      
317NNAME10954       VIA   -     D0100PA00X+053623Y+019209               S1      
317UART_TX_P3_R     VIA   -     D0100PA00X+052959Y+019300               S1      
317UART_DSR_P3_N    VIA   -     D0100PA00X+053347Y+019650               S1      
327P3V3_NODE1       U145  -5          A10X+053119Y+021634X0130Y0460R270 S1      
327GND              C598  -2          A10X+054168Y+021610X0180Y0200     S1      
327P3V3_NODE1       C598  -1          A10X+053853Y+021610X0180Y0200     S1      
327P5V_NODE1        R614  -1          A01X+053250Y+020408X0180Y0200R090 S2      
327UART_TX_P3_R     R1134 -2          A01X+053193Y+021624X0180Y0200R090 S2      
327P5V_NODE1        R1134 -1          A01X+053193Y+021939X0180Y0200R090 S2      
327UART_DTR_P3_N    R1156 -1          A01X+054166Y+021163X0180Y0200R180 S2      
327UART_TX_P3_R     R1135 -2          A01X+053593Y+021624X0180Y0200R090 S2      
327GND              R1135 -1          A01X+053593Y+021939X0180Y0200R090 S2      
327UART_DTR_P3_N    R1155 -2          A01X+054050Y+020408X0180Y0200R270 S2      
327UART_TX_P3       R1159 -2          A01X+052850Y+020408X0180Y0200R270 S2      
327UART_RTS_P3_N    R1157 -2          A01X+053666Y+020414X0180Y0200R270 S2      
317UART_DTR_P3_N    VIA   -     D0100PA00X+054166Y+020765               S1      
317UART_RTS_P3_N    VIA   -     D0100PA00X+053232Y+020947               S1      
317P3V3_NODE1       VIA   -     D0100PA00X+053853Y+021343               S3      
317P5V_NODE1        VIA   -     D0100PA00X+053250Y+020650               S3      
327UART_RI_P4_R_N   U145  -4          A10X+053119Y+022146X0130Y0460R270 S1      
327GND              R512  -1          A01X+054013Y+023499X0180Y0200R180 S2      
317GND              VIA   -     D0100PA00X+053668Y+023499               S3      
317NNAME10927       VIA   -     D0100PA00X+053421Y+022783               S1      
317NNAME10897       VIA   -     D0100PA00X+052811Y+023059               S1      
327P3V3_NODE1       R511  -1          A01X+054013Y+023899X0180Y0200R180 S2      
327GND              R510  -1          A01X+054013Y+024699X0180Y0200R180 S2      
327P3V3_NODE1       R509  -1          A01X+054013Y+024299X0180Y0200R180 S2      
317GND              VIA   -     D0100PA00X+053658Y+024699               S3      
317GND              VIA   -     D0100PA00X+053944Y+025032               S3      
317P3V3_NODE1       VIA   -     D0100PA00X+053697Y+024299               S3      
317P3V3_NODE1       VIA   -     D0100PA00X+053648Y+023899               S3      
317P1V8_NODE1       VIA   -     D0100PA00X+053577Y+025008               S1      
327P1V8_NODE1       C329  -1          A01X+053577Y+025386X0280Y0320R270 S2      
327GND              C329  -2          A01X+054157Y+025386X0280Y0320R270 S2      
327P1V8_NODE1       Q12   -2          A01X+053574Y+025962X0240Y0280R270 S2      
327NNAME10956       Q12   -1          A01X+053574Y+026710X0240Y0280R270 S2      
317GND              VIA   -     D0100PA00X+052953Y+026558               S3      
317NNAME10956       VIA   -     D0100PA00X+053927Y+026710               S1      
317NNAME10926       VIA   -     D0100PA00X+053279Y+028207               S3      
317NNAME10885       VIA   -     D0100PA00X+053012Y+028010               S1      
317P1V8_NODE1       VIA   -     D0100PA00X+052868Y+031735               S3      
317P1V0_NODE1       VIA   -     D0100PA00X+054138Y+034036               S3      
317P1V0_NODE1       VIA   -     D0100PA00X+054311Y+033385               S3      
317P1V0_NODE1       VIA   -     D0100PA00X+053618Y+034143               S3      
317P1V0_NODE1       VIA   -     D0100PA00X+053617Y+033660               S3      
317P1V0_NODE1       VIA   -     D0100PA00X+053180Y+034041               S3      
317P1V0_NODE1       VIA   -     D0100PA00X+053143Y+033707               S3      
317P1V0_NODE1       VIA   -     D0100PA00X+052760Y+033721               S3      
327NNAME10957       VIA   -           A10X+053391Y+040215X0260Y0260     S1      
327P3V3_CLK_NODE1   L2    -2          A10X+053481Y+041786X0440Y0540R090 S1      
327NNAME10957       L2    -1          A10X+053481Y+041038X0440Y0540R090 S1      
327NNAME10957       R1    -2          A10X+054288Y+041162X0280Y0320R090 S1      
317GND              VIA   -     D0100PA00X+052991Y+041948               S3      
317P3V3_CLK_NODE1   VIA   -     D0100PA00X+054070Y+041885               S3      
317P3V3_CLK_NODE1   VIA   -     D0100PA00X+054165Y+042228               S1      
317P3V3_CLK_NODE1   VIA   -     D0100PA00X+053644Y+042197               S3      
317CLK_33M_PORT80   VIA   -     D0100PA00X+053094Y+042221               S3      
327CLK_33M_PORT80   R188  -2          A01X+053094Y+042508X0180Y0200R090 S2      
327NNAME10929       R188  -1          A01X+053094Y+042823X0180Y0200R090 S2      
327P3V3_CLK_NODE1   R19   -2          A01X+054094Y+042508X0180Y0200R090 S2      
327NNAME10958       R19   -1          A01X+054094Y+042823X0180Y0200R090 S2      
327P3V3_CLK_NODE1   R14   -2          A01X+053594Y+042508X0180Y0200R090 S2      
327CLK_FSLB_NODE1   R14   -1          A01X+053594Y+042823X0180Y0200R090 S2      
327NNAME10959       R26   -2          A01X+054144Y+043773X0180Y0200R270 S2      
327GND              R26   -1          A01X+054144Y+043458X0180Y0200R270 S2      
327NNAME10958       R23   -2          A01X+053644Y+043773X0180Y0200R270 S2      
327GND              R23   -1          A01X+053644Y+043458X0180Y0200R270 S2      
327CLK_FSLB_NODE1   R16   -2          A01X+053144Y+043773X0180Y0200R270 S2      
327GND              R16   -1          A01X+053144Y+043458X0180Y0200R270 S2      
317GND              VIA   -     D0100PA00X+054144Y+043179               S3      
317GND              VIA   -     D0100PA00X+053644Y+043192               S3      
317GND              VIA   -     D0100PA00X+053144Y+043218               S3      
317CLK_FSLB_NODE1   VIA   -     D0100PA00X+052997Y+044022               S1      
317NNAME10929       VIA   -     D0100PA00X+052903Y+043047               S1      
317NNAME10958       VIA   -     D0100PA00X+053535Y+044041               S1      
327SEL_DOT_SRC5     U1    -16         A01X+053742Y+045400X0070Y0350R090 S2      
327P3V3_CLK_NODE1   U1    -15         A01X+053742Y+045242X0070Y0350R090 S2      
327P3V3_CLK_NODE1   U1    -14         A01X+053368Y+044868X0070Y0350     S2      
327NNAME10959       U1    -13         A01X+053210Y+044868X0070Y0350     S2      
327GND              U1    -12         A01X+053053Y+044868X0070Y0350     S2      
327GND              U1    -11         A01X+052895Y+044868X0070Y0350     S2      
327NNAME10958       U1    -10         A01X+052738Y+044868X0070Y0350     S2      
327GND              C196  -2          A10X+053124Y+045030X0180Y0200R090 S1      
327P3V3_CLK_NODE1   C196  -1          A10X+053124Y+044715X0180Y0200R090 S1      
327GND              C5    -2          A10X+053576Y+045242X0180Y0200R180 S1      
327P3V3_CLK_NODE1   C5    -1          A10X+053891Y+045242X0180Y0200R180 S1      
317GND              VIA   -     D0100PA00X+054274Y+045582               S3      
317GND              VIA   -     D0100PA00X+053004Y+044432               S3      
317GND              VIA   -     D0100PA00X+053304Y+045322               S3      
317NNAME10959       VIA   -     D0100PA00X+054014Y+044299               S1      
317P3V3_CLK_NODE1   VIA   -     D0100PA00X+053474Y+044552               S3      
317P3V3_CLK_NODE1   VIA   -     D0100PA00X+054184Y+045072               S3      
327N/C              U1    -26         A01X+053742Y+046974X0070Y0350R090 S2      
327P1V5_CLK_NODE1   U1    -25         A01X+053742Y+046817X0070Y0350R090 S2      
327NNAME10905       U1    -24         A01X+053742Y+046659X0070Y0350R090 S2      
327NNAME10906       U1    -23         A01X+053742Y+046502X0070Y0350R090 S2      
327GND              U1    -22         A01X+053742Y+046344X0070Y0350R090 S2      
327SEL_PCI_27M      U1    -21         A01X+053742Y+046187X0070Y0350R090 S2      
327P3V3_CLK_NODE1   U1    -20         A01X+053742Y+046029X0070Y0350R090 S2      
327NNAME10960       U1    -19         A01X+053742Y+045872X0070Y0350R090 S2      
327GND              U1    -18         A01X+053742Y+045714X0070Y0350R090 S2      
327NNAME10961       U1    -17         A01X+053742Y+045557X0070Y0350R090 S2      
327GND              C8    -2          A10X+053536Y+047042X0180Y0200R180 S1      
327P1V5_CLK_NODE1   C8    -1          A10X+053851Y+047042X0180Y0200R180 S1      
327GND              C3    -2          A10X+053576Y+046012X0180Y0200R180 S1      
327P3V3_CLK_NODE1   C3    -1          A10X+053891Y+046012X0180Y0200R180 S1      
317GND              VIA   -     D0100PA00X+053374Y+045802               S3      
317GND              VIA   -     D0100PA00X+053374Y+046502               S3      
317GND              VIA   -     D0100PA00X+054274Y+046312               S3      
327GND              U1    -28         A01X+053742Y+047289X0070Y0350R090 S2      
327N/C              U1    -27         A01X+053742Y+047132X0070Y0350R090 S2      
327NNAME10962       U1    -33         A01X+052738Y+047663X0070Y0350     S2      
327NNAME10963       U1    -32         A01X+052895Y+047663X0070Y0350     S2      
327NNAME10964       U1    -31         A01X+053053Y+047663X0070Y0350     S2      
327NNAME10965       U1    -30         A01X+053210Y+047663X0070Y0350     S2      
327GND              U1    -29         A01X+053368Y+047663X0070Y0350     S2      
327GND              C11   -2          A10X+052834Y+047435X0180Y0200R270 S1      
327NNAME10902       C11   -1          A10X+052834Y+047750X0180Y0200R270 S1      
327PCI_STP_NODE1    R5    -2          A10X+053153Y+048363X0180Y0200R180 S1      
327P3V3_CLK_NODE1   R5    -1          A10X+053468Y+048363X0180Y0200R180 S1      
317GND              VIA   -     D0100PA00X+053374Y+047302               S3      
317GND              VIA   -     D0100PA00X+054094Y+047362               S3      
317GND              VIA   -     D0100PA00X+053573Y+047663               S3      
317GND              VIA   -     D0100PA00X+053942Y+049111               S3      
317GND              VIA   -     D0100PA00X+053293Y+049138               S3      
317NNAME10965       VIA   -     D0100PA00X+053804Y+048832               S3      
317NNAME10964       VIA   -     D0100PA00X+053304Y+048832               S3      
317NNAME10701       VIA   -     D0100PA00X+054328Y+049104               S3      
327NNAME10966       C190  -2          A01X+052947Y+051215X0180Y0200R090 S2      
327NNAME10937       C190  -1          A01X+052947Y+051530X0180Y0200R090 S2      
327P1V0_NODE1       U125  -123        A01X+054228Y+053475X0070Y0600R180 S2      
327GND              U125  -122        A01X+054070Y+053475X0070Y0600R180 S2      
327N/C              U125  -121        A01X+053913Y+053475X0070Y0600R180 S2      
327N/C              U125  -120        A01X+053755Y+053475X0070Y0600R180 S2      
327GND              U125  -119        A01X+053598Y+053475X0070Y0600R180 S2      
327P1V0_NODE1       U125  -118        A01X+053440Y+053475X0070Y0600R180 S2      
327N/C              U125  -117        A01X+053283Y+053475X0070Y0600R180 S2      
327N/C              U125  -116        A01X+053125Y+053475X0070Y0600R180 S2      
327NNAME10063       U125  -115        A01X+052968Y+053475X0070Y0600R180 S2      
327GND              U125  -114        A01X+052810Y+053475X0070Y0600R180 S2      
327NNAME10063       C892  -1          A10X+053054Y+053335X0180Y0200R090 S1      
327P1V0_NODE1       C879  -1          A10X+054154Y+053325X0180Y0200R090 S1      
327P1V0_NODE1       C861  -1          A10X+053444Y+053335X0180Y0200R090 S1      
317NNAME10063       VIA   -     D0100PA00X+053044Y+052953               S3      
317P1V0_NODE1       VIA   -     D0100PA00X+054154Y+052963               S3      
317P1V0_NODE1       VIA   -     D0100PA00X+053440Y+052956               S3      
327GND              C892  -2          A10X+053054Y+053650X0180Y0200R090 S1      
327GND              C879  -2          A10X+054154Y+053640X0180Y0200R090 S1      
327GND              C861  -2          A10X+053444Y+053650X0180Y0200R090 S1      
317GND              VIA   -     D0100PA00X+053064Y+053953               S3      
317GND              VIA   -     D0100PA00X+053464Y+053983               S3      
317GND              VIA   -     D0100PA00X+054124Y+053963               S3      
317P1V0_PCI_SW_A    VIA   -     D0100PA00X+052814Y+053993               S3      
327P1V0_NODE1       VIA   -           A10X+053738Y+056488X0260Y0260     S1      
327N/C              U125  -47         A01X+052810Y+059577X0070Y0600R180 S2      
327P1V0_NODE1       U125  -46         A01X+052968Y+059577X0070Y0600R180 S2      
327NNAME10967       U125  -45         A01X+053125Y+059577X0070Y0600R180 S2      
327GND              U125  -44         A01X+053283Y+059577X0070Y0600R180 S2      
327PCIE_SW_RST_N    U125  -43         A01X+053440Y+059577X0070Y0600R180 S2      
327P1V0_NODE1       U125  -42         A01X+053598Y+059577X0070Y0600R180 S2      
327NNAME10968       U125  -41         A01X+053755Y+059577X0070Y0600R180 S2      
327NNAME10969       U125  -40         A01X+053913Y+059577X0070Y0600R180 S2      
327P3V3_NODE1       U125  -39         A01X+054070Y+059577X0070Y0600R180 S2      
327PCIE_SW_TEST7    U125  -38         A01X+054228Y+059577X0070Y0600R180 S2      
327GND              C891  -2          A10X+053644Y+059720X0180Y0200R090 S1      
327P1V0_NODE1       C891  -1          A10X+053644Y+059405X0180Y0200R090 S1      
327GND              C864  -2          A10X+053144Y+059730X0180Y0200R090 S1      
327P1V0_NODE1       C864  -1          A10X+053144Y+059415X0180Y0200R090 S1      
327GND              C869  -2          A10X+052744Y+059730X0180Y0200R090 S1      
327P3V3_NODE1       C869  -1          A10X+052744Y+059415X0180Y0200R090 S1      
327GND              C881  -2          A10X+054034Y+059720X0180Y0200R090 S1      
327P3V3_NODE1       C881  -1          A10X+054034Y+059405X0180Y0200R090 S1      
317GND              VIA   -     D0100PA00X+053304Y+059033               S3      
317P3V3_NODE1       VIA   -     D0100PA00X+054070Y+059016               S3      
317P3V3_NODE1       VIA   -     D0100PA00X+052764Y+059033               S3      
317P1V0_NODE1       VIA   -     D0100PA00X+053578Y+059049               S3      
317P1V0_NODE1       VIA   -     D0100PA00X+053034Y+059033               S3      
327PCIE_SW_TEST7    R287  -2          A01X+054244Y+060785X0180Y0200R090 S2      
327GND              R287  -1          A01X+054244Y+061100X0180Y0200R090 S2      
327PCIE_SW_RST_N    R231  -2          A01X+053464Y+060795X0180Y0200R090 S2      
327NNAME10970       R231  -1          A01X+053464Y+061110X0180Y0200R090 S2      
327PCIE_SW_P0_ERR   R234  -2          A01X+053074Y+061110X0180Y0200R270 S2      
327NNAME10967       R234  -1          A01X+053074Y+060795X0180Y0200R270 S2      
317GND              VIA   -     D0100PA00X+053644Y+060043               S3      
317GND              VIA   -     D0100PA00X+054244Y+061372               S3      
317NNAME10967       VIA   -     D0100PA00X+052941Y+060349               S1      
317NNAME10969       VIA   -     D0100PA00X+054054Y+060101               S3      
317NNAME10968       VIA   -     D0100PA00X+053883Y+060295               S3      
317PCIE_SW_TEST7    VIA   -     D0100PA00X+054285Y+060298               S1      
317PCIE_SW_RST_N    VIA   -     D0100PA00X+053505Y+060289               S1      
327NNAME10877       R647  -2          A01X+053563Y+062423X0180Y0200     S2      
327I2C_PSU3_SDA     R647  -1          A01X+053878Y+062423X0180Y0200     S2      
327NNAME10877       R671  -2          A01X+053563Y+062023X0180Y0200     S2      
327P3V3_NODE1       R671  -1          A01X+053878Y+062023X0180Y0200     S2      
327TACKOVER_EN_N    U140  -G          A10X+052878Y+062960X0400Y0500     S1      
327NNAME10877       U127  -S          A01X+053028Y+062080X0400Y0500     S2      
317GND              VIA   -     D0100PA00X+053840Y+061380               S3      
317P3V3_NODE1       VIA   -     D0100PA00X+054198Y+062023               S3      
317P5V_NODE1        VIA   -     D0100PA00X+052783Y+061539               S3      
317NNAME10970       VIA   -     D0100PA00X+053242Y+061548               S1      
327P3V3_NODE1       U129  -63         A01X+054144Y+064314X0110Y0590     S2      
327NNAME10897       U129  -62         A01X+053947Y+064314X0110Y0590     S2      
327CMC_CPU_RST_N    U129  -61         A01X+053750Y+064314X0110Y0590     S2      
327GND              U129  -60         A01X+053553Y+064314X0110Y0590     S2      
327P3V3_NODE1       U129  -59         A01X+053357Y+064314X0110Y0590     S2      
327TACKOVER_EN_N    U129  -58         A01X+053160Y+064314X0110Y0590     S2      
327NNAME10944       U129  -57         A01X+052963Y+064314X0110Y0590     S2      
327NNAME10914       U129  -56         A01X+052766Y+064314X0110Y0590     S2      
327GND              C906  -2          A01X+053607Y+062933X0180Y0200R090 S2      
327P3V3_NODE1       C906  -1          A01X+053607Y+063248X0180Y0200R090 S2      
317GND              VIA   -     D0100PA00X+054005Y+062964               S3      
317P3V3_NODE1       VIA   -     D0100PA00X+053947Y+063248               S3      
317TACKOVER_EN_N    VIA   -     D0100PA00X+053078Y+063735               S3      
317TACKOVER_EN      VIA   -     D0100PA00X+053248Y+063359               S3      
327P3V3_NODE1       C905  -1          A10X+054162Y+064493X0180Y0200     S1      
327P3V3_NODE1       R1309 -1          A10X+052755Y+064521X0180Y0200R180 S1      
327NNAME10891       R977  -2          A10X+054188Y+065028X0180Y0200R180 S1      
317GND              VIA   -     D0100PA00X+053523Y+064871               S3      
317P3V3_NODE1       VIA   -     D0100PA00X+054144Y+064759               S3      
317P3V3_NODE1       VIA   -     D0100PA00X+053197Y+065049               S3      
317NNAME10971       VIA   -     D0100PA00X+054242Y+065482               S1      
317CMC_CPU_RST_N    VIA   -     D0100PA00X+053656Y+065550               S1      
317P3V3_NODE1       VIA   -     D0100PA00X+053912Y+067013               S3      
317NNAME10914       VIA   -     D0100PA00X+052953Y+066935               S1      
317NNAME10944       VIA   -     D0100PA00X+052990Y+066102               S1      
317NNAME10945       VIA   -     D0100PA00X+053973Y+067502               S1      
317NNAME10897       VIA   -     D0100PA00X+053983Y+066733               S3      
317UART_RX_P4       VIA   -     D0100PA00X+053160Y+068984               S3      
317UART_RX_P3       VIA   -     D0100PA00X+053327Y+067935               S3      
327UART_CMC_TX_P    U129  -20         A01X+052766Y+070417X0110Y0590     S2      
327UART_RX_P3       U129  -19         A01X+052963Y+070417X0110Y0590     S2      
327UART_TX_P3       U129  -18         A01X+053160Y+070417X0110Y0590     S2      
327UART_DTR_P3_N    U129  -17         A01X+053357Y+070417X0110Y0590     S2      
327UART_RX_P4       U129  -16         A01X+053553Y+070417X0110Y0590     S2      
327UART_TX_P4       U129  -15         A01X+053750Y+070417X0110Y0590     S2      
327CPU_RSV_1        U129  -14         A01X+053947Y+070417X0110Y0590     S2      
327P3V3_NODE1       U129  -13         A01X+054144Y+070417X0110Y0590     S2      
317UART_TX_P3       VIA   -     D0100PA00X+053160Y+069751               S3      
327GND              C903  -2          A01X+054144Y+071617X0180Y0200R270 S2      
327P3V3_NODE1       C903  -1          A01X+054144Y+071302X0180Y0200R270 S2      
327GND              R1160 -2          A01X+053157Y+071635X0180Y0200R270 S2      
327UART_TX_P3       R1160 -1          A01X+053157Y+071320X0180Y0200R270 S2      
317GND              VIA   -     D0100PA00X+053549Y+071518               S3      
317UART_DTR_P3_N    VIA   -     D0100PA00X+053527Y+071122               S3      
317UART_DTR_P4_N    VIA   -     D0100PA00X+053506Y+070868               S3      
317UART_RTS_P4_N    VIA   -     D0100PA00X+053001Y+070862               S3      
317P3V3_NODE1       VIA   -     D0100PA00X+054319Y+071079               S3      
317T9_NODE4_EN      VIA   -     D0100PA00X+053958Y+072189               S1      
317UART_TX_P4       VIA   -     D0100PA00X+053750Y+071009               S3      
317NNAME10972       VIA   -     D0100PA00X+052839Y+072290               S3      
317CPU_RSV_1        VIA   -     D0100PA00X+054006Y+070878               S1      
327GND              C645  -2          A01X+054194Y+073908X0180Y0200R090 S2      
327GND              C633  -2          A10X+053744Y+073808X0180Y0200R270 S1      
327GND              C630  -2          A10X+054194Y+073808X0180Y0200R270 S1      
327GND              C743  -2          A01X+053294Y+072758X0180Y0200R090 S2      
327NNAME10973       C743  -1          A01X+053294Y+073073X0180Y0200R090 S2      
327GND              C719  -2          A10X+053294Y+072658X0180Y0200R270 S1      
327NNAME10941       C719  -1          A10X+053294Y+072973X0180Y0200R270 S1      
327GND              C746  -2          A01X+052994Y+073908X0180Y0200R090 S2      
327GND              C722  -2          A10X+052844Y+073808X0180Y0200R270 S1      
327T9_NODE3_EN_R    R867  -2          A10X+054194Y+072973X0180Y0200R090 S1      
327T9_NODE3_EN      R867  -1          A10X+054194Y+072658X0180Y0200R090 S1      
327NNAME10973       R980  -1          A01X+053444Y+073908X0180Y0200R270 S2      
327NNAME10941       R956  -1          A10X+053294Y+073808X0180Y0200R090 S1      
327T10_NODE4_EN_R   R882  -2          A01X+054194Y+073073X0180Y0200R270 S2      
327T10_NODE4_EN     R882  -1          A01X+054194Y+072758X0180Y0200R270 S2      
327T9_NODE4_EN_R    R870  -2          A10X+053744Y+072973X0180Y0200R090 S1      
327T9_NODE4_EN      R870  -1          A10X+053744Y+072658X0180Y0200R090 S1      
327NNAME10948       R983  -2          A01X+052844Y+073073X0180Y0200R270 S2      
327NNAME10972       R983  -1          A01X+052844Y+072758X0180Y0200R270 S2      
327NNAME10921       R959  -2          A10X+052844Y+072973X0180Y0200R090 S1      
327NNAME10942       R959  -1          A10X+052844Y+072658X0180Y0200R090 S1      
317GND              VIA   -     D0100PA00X+053770Y+073566               S3      
317GND              VIA   -     D0100PA00X+054194Y+073568               S3      
317GND              VIA   -     D0100PA00X+052844Y+073568               S3      
317GND              VIA   -     D0100PA00X+053185Y+072410               S3      
317NNAME10973       VIA   -     D0100PA00X+053294Y+073481               S3      
317NNAME10941       VIA   -     D0100PA00X+053103Y+073314               S3      
327T10_NODE4_EN_R   C645  -1          A01X+054194Y+074223X0180Y0200R090 S2      
327T9_NODE4_EN_R    C633  -1          A10X+053744Y+074123X0180Y0200R270 S1      
327T9_NODE3_EN_R    C630  -1          A10X+054194Y+074123X0180Y0200R270 S1      
327NNAME10948       C746  -1          A01X+052994Y+074223X0180Y0200R090 S2      
327NNAME10921       C722  -1          A10X+052844Y+074123X0180Y0200R270 S1      
327NNAME10974       R980  -2          A01X+053444Y+074223X0180Y0200R270 S2      
327NNAME10947       R956  -2          A10X+053294Y+074123X0180Y0200R090 S1      
327T9_NODE2_EN_R    VIA   -           A10X+053156Y+078639X0260Y0260     S1      
327T9_NODE1_EN_R    VIA   -           A10X+053732Y+078630X0260Y0260     S1      
317T10_NODE4_EN_R   VIA   -     D0100PA00X+053965Y+078094               S1      
317NNAME10948       VIA   -     D0100PA00X+052930Y+077134               S1      
327NNAME10975       VIA   -           A10X+054308Y+077558X0260Y0260     S1      
317NNAME10974       VIA   -     D0100PA00X+053360Y+077878               S1      
327T9_NODE3_EN_R    VIA   -           A10X+052762Y+078132X0260Y0260     S1      
327T9_NODE2_EN_R    J18   -A51        A10X+053156Y+080787X0300Y1660R180 S1      
327T9_NODE1_EN_R    J18   -A50        A10X+053549Y+080787X0300Y1660R180 S1      
327GND              J18   -A49        A10X+053943Y+080787X0300Y1660R180 S1      
327NNAME10975       J18   -A48        A10X+054337Y+080787X0300Y1660R180 S1      
327NNAME10974       J18   -B51        A01X+053156Y+080787X0300Y1660R180 S2      
327GND              J18   -B50        A01X+053549Y+080787X0300Y1660R180 S2      
327T10_NODE4_EN_R   J18   -B49        A01X+053943Y+080787X0300Y1660R180 S2      
327T10_NODE3_EN_R   J18   -B48        A01X+054337Y+080590X0300Y1260R180 S2      
317GND              VIA   -     D0100PA00X+053943Y+079148               S3      
317GND              VIA   -     D0100PA00X+053549Y+079148               S3      
317GND              J20   -2    D0460PA00X+055478Y+002880               S0      
317JTAG_CPLD1_TCK   J20   -1    D0460PA00X+055478Y+003880               S0      
317GND              J8    -1    D0410PA00X+054618Y+008189               S0      
317P5V_NODE1        J8    -2    D0410PA00X+055618Y+008189               S0      
327GND              C493  -2          A01X+054725Y+010316X0180Y0200R270 S2      
327P5V_NODE1        C493  -1          A01X+054725Y+010001X0180Y0200R270 S2      
327GNDA             C482  -2          A01X+055594Y+010005X0180Y0200R090 S2      
327SIO_AVCC         C482  -1          A01X+055594Y+010320X0180Y0200R090 S2      
327UART_DSR_P6_N    R1139 -2          A01X+055145Y+010320X0180Y0200R270 S2      
327P3V3_NODE1       R1139 -1          A01X+055145Y+010005X0180Y0200R270 S2      
317GND              VIA   -     D0100PA00X+054725Y+010658               S3      
317GNDA             VIA   -     D0100PA00X+055594Y+009729               S3      
317P3V3_NODE1       VIA   -     D0100PA00X+055145Y+009715               S3      
317P5V_NODE1        VIA   -     D0100PA00X+054748Y+009663               S3      
327SIO_AVCC         U43   -99         A01X+055812Y+011842X0110Y0710R180 S2      
327N/C              U43   -98         A01X+055615Y+011842X0110Y0710R180 S2      
327N/C              U43   -97         A01X+055418Y+011842X0110Y0710R180 S2      
327N/C              U43   -96         A01X+055221Y+011842X0110Y0710R180 S2      
327UART_DSR_P6_N    U43   -95         A01X+055024Y+011842X0110Y0710R180 S2      
327N/C              U43   -94         A01X+054827Y+011842X0110Y0710R180 S2      
327UART_RX_P6       U43   -93         A01X+054631Y+011842X0110Y0710R180 S2      
327UART_CTS_P6_N    U43   -92         A01X+054434Y+011842X0110Y0710R180 S2      
317SIO_AVCC         VIA   -     D0100PA00X+055800Y+011024               S1      
317UART_RX_P6       VIA   -     D0100PA00X+054631Y+011019               S3      
317UART_DSR_P6_N    VIA   -     D0100PA00X+055049Y+011299               S1      
327GND              R1186 -2          A10X+054476Y+013542X0180Y0200     S1      
327GND              R1184 -2          A10X+054476Y+013942X0180Y0200     S1      
317GND              VIA   -     D0100PA00X+054837Y+013542               S3      
317GND              VIA   -     D0100PA00X+054801Y+013942               S3      
317NNAME10951       VIA   -     D0100PA00X+055217Y+013853               S1      
317NNAME10950       VIA   -     D0100PA00X+055060Y+013260               S1      
327CPLD_WDT3_R      R1179 -1          A10X+054476Y+015142X0180Y0200R180 S1      
327NNAME10976       R1190 -1          A10X+054476Y+015542X0180Y0200R180 S1      
327NNAME10977       R1187 -1          A10X+054476Y+014742X0180Y0200R180 S1      
327GND              R1182 -2          A10X+054476Y+014342X0180Y0200     S1      
327NNAME10978       R1056 -1          A10X+055670Y+014927X0180Y0200     S1      
317GND              VIA   -     D0100PA00X+054754Y+014342               S3      
317NNAME10976       VIA   -     D0100PA00X+055055Y+015168               S1      
317NNAME10979       VIA   -     D0100PA00X+055806Y+015425               S1      
317NNAME10977       VIA   -     D0100PA00X+055835Y+014251               S1      
317NNAME10952       VIA   -     D0100PA00X+055146Y+014386               S1      
327NNAME10978       R1080 -1          A10X+054476Y+016342X0180Y0200R180 S1      
327NNAME10953       R1189 -2          A10X+055160Y+016254X0180Y0200R180 S1      
327NNAME10979       R1189 -1          A10X+055475Y+016254X0180Y0200R180 S1      
327NNAME10976       R1065 -1          A10X+054476Y+015942X0180Y0200R180 S1      
317UART_CTS_P2_N    VIA   -     D0100PA00X+055060Y+016807               S1      
317GND              VIA   -     D0100PA00X+055885Y+015870               S3      
317NNAME10978       VIA   -     D0100PA00X+055037Y+015746               S1      
327UART_DCD_P3_N    U43   -11         A01X+054434Y+018583X0110Y0710R180 S2      
327N/C              U43   -10         A01X+054631Y+018583X0110Y0710R180 S2      
327N/C              U43   -9          A01X+054827Y+018583X0110Y0710R180 S2      
327N/C              U43   -8          A01X+055024Y+018583X0110Y0710R180 S2      
327N/C              U43   -7          A01X+055221Y+018583X0110Y0710R180 S2      
327UART_RX_P2       U43   -6          A01X+055418Y+018583X0110Y0710R180 S2      
327UART_TX_P2       U43   -5          A01X+055615Y+018583X0110Y0710R180 S2      
327P5V_NODE1        U43   -4          A01X+055812Y+018583X0110Y0710R180 S2      
327P5V_NODE1        C481  -1          A10X+055586Y+018302X0180Y0200     S1      
327UART_DCD_P3_N    R1264 -2          A10X+054600Y+018643X0180Y0200R090 S1      
327P5V_NODE1        R1264 -1          A10X+054600Y+018328X0180Y0200R090 S1      
317UART_DSR_P2_N    VIA   -     D0100PA00X+055767Y+017653               S1      
317UART_TX_P2       VIA   -     D0100PA00X+055551Y+017387               S3      
317UART_RX_P2       VIA   -     D0100PA00X+055140Y+017417               S1      
317P5V_NODE1        VIA   -     D0100PA00X+055584Y+017926               S3      
317P5V_NODE1        VIA   -     D0100PA00X+054600Y+018000               S3      
327UART_TX_P2       R1024 -2          A01X+055391Y+020109X0180Y0200R090 S2      
327UART_TX_P2       R1020 -2          A01X+054991Y+020109X0180Y0200R090 S2      
327UART_RTS_P2_N    R1017 -2          A01X+055791Y+020109X0180Y0200R090 S2      
327UART_CTS_P3_N    R777  -2          A01X+054450Y+020093X0180Y0200R090 S2      
317GND              VIA   -     D0100PA00X+055877Y+019122               S3      
317UART_CTS_P3_N    VIA   -     D0100PA00X+054450Y+019750               S1      
317UART_DCD_P3_N    VIA   -     D0100PA00X+054600Y+019200               S1      
327GND              R1024 -1          A01X+055391Y+020424X0180Y0200R090 S2      
327P5V_NODE1        R1020 -1          A01X+054991Y+020424X0180Y0200R090 S2      
327P5V_NODE1        R1017 -1          A01X+055791Y+020424X0180Y0200R090 S2      
327GND              R1156 -2          A01X+054481Y+021163X0180Y0200R180 S2      
327P5V_NODE1        R777  -1          A01X+054450Y+020408X0180Y0200R090 S2      
317GND              VIA   -     D0100PA00X+055391Y+020740               S3      
317GND              VIA   -     D0100PA00X+054793Y+021219               S3      
317GND              VIA   -     D0100PA00X+055842Y+021068               S3      
317GND              VIA   -     D0100PA00X+054470Y+021610               S3      
317P5V_NODE1        VIA   -     D0100PA00X+054991Y+020706               S3      
317P5V_NODE1        VIA   -     D0100PA00X+055791Y+020754               S1      
317P5V_NODE1        VIA   -     D0100PA00X+055575Y+021203               S3      
317P5V_NODE1        VIA   -     D0100PA00X+054450Y+020700               S3      
327N/C              U30   -1          A01X+055721Y+023589X0070Y0440R180 S2      
327NNAME10980       R512  -2          A01X+054328Y+023499X0180Y0200R180 S2      
327P1V0_NODE1       R804  -1          A01X+055600Y+022253X0440Y0540R180 S2      
317GND              VIA   -     D0100PA00X+054715Y+022022               S1      
317P5V_NODE1        VIA   -     D0100PA00X+054542Y+022672               S3      
327P1V0_SATA        VIA   -           A10X+055466Y+023078X0260Y0260     S1      
317P1V0_NODE1       VIA   -     D0100PA00X+054669Y+023307               S3      
317P1V0_NODE1       VIA   -     D0100PA00X+054499Y+023109               S3      
317P1V0_NODE1       VIA   -     D0100PA00X+054949Y+023300               S3      
317P1V0_NODE1       VIA   -     D0100PA00X+054936Y+023015               S3      
317P1V0_NODE1       VIA   -     D0100PA00X+055212Y+023239               S3      
317P1V0_NODE1       VIA   -     D0100PA00X+055205Y+022912               S3      
327N/C              U30   -76         A01X+055390Y+023921X0070Y0440R090 S2      
327NNAME10980       U30   -75         A01X+055390Y+024078X0070Y0440R090 S2      
327NNAME10981       U30   -74         A01X+055390Y+024235X0070Y0440R090 S2      
327P3V3_NODE1       U30   -73         A01X+055390Y+024393X0070Y0440R090 S2      
327N/C              U30   -72         A01X+055390Y+024550X0070Y0440R090 S2      
327P1V0_SATA        U30   -71         A01X+055390Y+024708X0070Y0440R090 S2      
327N/C              U30   -70         A01X+055390Y+024865X0070Y0440R090 S2      
327N/C              U30   -69         A01X+055390Y+025023X0070Y0440R090 S2      
327GND              C352  -2          A10X+055571Y+023950X0180Y0200     S1      
327P3V3_NODE1       C352  -1          A10X+055256Y+023950X0180Y0200     S1      
327GND              C353  -2          A10X+055575Y+024340X0180Y0200     S1      
327P3V3_NODE1       C353  -1          A10X+055260Y+024340X0180Y0200     S1      
327GND              C340  -2          A10X+055575Y+024760X0180Y0200     S1      
327P1V0_SATA        C340  -1          A10X+055260Y+024760X0180Y0200     S1      
327NNAME10980       R511  -2          A01X+054328Y+023899X0180Y0200R180 S2      
327NNAME10981       R510  -2          A01X+054328Y+024699X0180Y0200R180 S2      
327NNAME10981       R509  -2          A01X+054328Y+024299X0180Y0200R180 S2      
317P3V3_NODE1       VIA   -     D0100PA00X+055004Y+024393               S3      
317NNAME10981       VIA   -     D0100PA00X+054570Y+024573               S1      
317NNAME10980       VIA   -     D0100PA00X+054598Y+023629               S1      
317P1V0_SATA        VIA   -     D0100PA00X+055009Y+024708               S3      
327N/C              U30   -68         A01X+055390Y+025180X0070Y0440R090 S2      
327N/C              U30   -67         A01X+055390Y+025338X0070Y0440R090 S2      
327N/C              U30   -66         A01X+055390Y+025495X0070Y0440R090 S2      
327N/C              U30   -65         A01X+055390Y+025653X0070Y0440R090 S2      
327P1V0_SATA        U30   -64         A01X+055390Y+025810X0070Y0440R090 S2      
327N/C              U30   -63         A01X+055390Y+025968X0070Y0440R090 S2      
327N/C              U30   -62         A01X+055390Y+026125X0070Y0440R090 S2      
327N/C              U30   -61         A01X+055390Y+026283X0070Y0440R090 S2      
327N/C              U30   -60         A01X+055390Y+026440X0070Y0440R090 S2      
327N/C              U30   -59         A01X+055390Y+026598X0070Y0440R090 S2      
327GND              C342  -2          A10X+055575Y+025810X0180Y0200     S1      
327P1V0_SATA        C342  -1          A10X+055260Y+025810X0180Y0200     S1      
327P1V0_SATA        Q12   -3          A01X+054361Y+026336X0240Y0280R270 S2      
317P1V0_SATA        VIA   -     D0100PA00X+054512Y+026685               S1      
317P1V0_SATA        VIA   -     D0100PA00X+054793Y+025810               S1      
327N/C              U30   -58         A01X+055390Y+026755X0070Y0440R090 S2      
327P3V3_NODE1       U30   -57         A01X+055721Y+027086X0070Y0440R180 S2      
327GND              C351  -2          A10X+055717Y+026902X0180Y0200R270 S1      
327P3V3_NODE1       C351  -1          A10X+055717Y+027217X0180Y0200R270 S1      
327NNAME10982       D5    -C          A01X+055113Y+028053X0320Y0320     S2      
327NNAME10983       D5    -A          A01X+054522Y+028053X0320Y0320     S2      
327P3V3_NODE1       R501  -2          A01X+054835Y+027426X0180Y0200R180 S2      
327NNAME10983       R501  -1          A01X+054520Y+027426X0180Y0200R180 S2      
317P3V3_NODE1       VIA   -     D0100PA00X+055721Y+027483               S3      
317P3V3_NODE1       VIA   -     D0100PA00X+055134Y+027426               S3      
317NNAME10983       VIA   -     D0100PA00X+054522Y+027690               S1      
317NNAME10982       VIA   -     D0100PA00X+055721Y+028033               S1      
327NNAME10984       R508  -2          A01X+055055Y+029252X0180Y0200R180 S2      
327NNAME10884       R508  -1          A01X+054740Y+029252X0180Y0200R180 S2      
327NNAME10985       R507  -2          A01X+055025Y+029682X0180Y0200R180 S2      
327NNAME10926       R507  -1          A01X+054710Y+029682X0180Y0200R180 S2      
317NNAME10984       VIA   -     D0100PA00X+055507Y+028956               S1      
317NNAME10269       VIA   -     D0100PA00X+055722Y+028511               S3      
327NNAME10986       R506  -2          A01X+055025Y+030112X0180Y0200R180 S2      
327NNAME10885       R506  -1          A01X+054710Y+030112X0180Y0200R180 S2      
317P1V0_NODE1       VIA   -     D0100PA00X+055369Y+034083               S3      
317P1V0_NODE1       VIA   -     D0100PA00X+054734Y+033910               S3      
317GND              VIA   -     D0100PA00X+055571Y+038915               S3      
317NNAME10930       VIA   -     D0100PA00X+055209Y+038895               S1      
317NNAME10691       VIA   -     D0100PA00X+054847Y+037813               S3      
317P3V3_NODE1       VIA   -     D0100PA00X+054976Y+040725               S3      
317P3V3_NODE1       VIA   -     D0100PA00X+055323Y+040725               S1      
327P3V3_NODE1       R1    -1          A10X+054868Y+041162X0280Y0320R090 S1      
317P3V3_NODE1       VIA   -     D0100PA00X+055375Y+041042               S3      
317P3V3_CLK_NODE1   VIA   -     D0100PA00X+054450Y+042258               S3      
327P3V3_CLK_NODE1   R22   -2          A01X+054594Y+042508X0180Y0200R090 S2      
327NNAME10959       R22   -1          A01X+054594Y+042823X0180Y0200R090 S2      
327NNAME10473       R10   -2          A01X+054994Y+042508X0180Y0200R090 S2      
327NNAME10959       R10   -1          A01X+054994Y+042823X0180Y0200R090 S2      
327P3V3_CLK_NODE1   R20   -2          A01X+055384Y+043901X0180Y0200R180 S2      
327SEL_DOT_SRC5     R20   -1          A01X+055069Y+043901X0180Y0200R180 S2      
317P3V3_CLK_NODE1   VIA   -     D0100PA00X+055702Y+043897               S3      
317P3V3_CLK_NODE1   VIA   -     D0100PA00X+054957Y+043258               S1      
327P3V3_CLK_NODE1   R21   -2          A01X+055514Y+044875X0180Y0200R090 S2      
327NNAME10961       R21   -1          A01X+055514Y+045190X0180Y0200R090 S2      
327NNAME10961       R25   -2          A01X+055114Y+045190X0180Y0200R270 S2      
327GND              R25   -1          A01X+055114Y+044875X0180Y0200R270 S2      
327SEL_DOT_SRC5     R24   -2          A01X+055067Y+044305X0180Y0200     S2      
327GND              R24   -1          A01X+055382Y+044305X0180Y0200     S2      
317GND              VIA   -     D0100PA00X+054338Y+044843               S3      
317GND              VIA   -     D0100PA00X+055677Y+045616               S3      
317GND              VIA   -     D0100PA00X+055696Y+044301               S3      
317GND              VIA   -     D0100PA00X+055114Y+044579               S3      
317P3V3_CLK_NODE1   VIA   -     D0100PA00X+055514Y+044594               S3      
317SEL_DOT_SRC5     VIA   -     D0100PA00X+054638Y+044511               S1      
317NNAME10961       VIA   -     D0100PA00X+054749Y+045237               S1      
327SEL_PCI_27M      R18   -2          A01X+055097Y+046066X0180Y0200     S2      
327GND              R18   -1          A01X+055412Y+046066X0180Y0200     S2      
327NNAME10960       R15   -2          A01X+055087Y+045616X0180Y0200     S2      
327GND              R15   -1          A01X+055402Y+045616X0180Y0200     S2      
317GND              VIA   -     D0100PA00X+055697Y+046066               S3      
317P1V5_CLK_NODE1   VIA   -     D0100PA00X+055455Y+046967               S1      
317P1V5_CLK_NODE1   VIA   -     D0100PA00X+054551Y+046974               S1      
317P3V3_CLK_NODE1   VIA   -     D0100PA00X+054334Y+045932               S3      
317SEL_PCI_27M      VIA   -     D0100PA00X+054764Y+046236               S1      
317NNAME10960       VIA   -     D0100PA00X+054604Y+045752               S1      
327P1V5_CLK_NODE1   L1    -2          A01X+055474Y+047392X0440Y0540R090 S2      
327NNAME10987       L1    -1          A01X+055474Y+048140X0440Y0540R090 S2      
327P1V5_CLK_NODE1   C6    -1          A01X+054734Y+047376X0280Y0320     S2      
327GND              C6    -2          A01X+054734Y+047956X0280Y0320     S2      
317GND              VIA   -     D0100PA00X+054734Y+048403               S3      
317NNAME10702       VIA   -     D0100PA00X+054625Y+049030               S1      
317GND              VIA   -     D0100PA00X+054800Y+050949               S3      
317GND              VIA   -     D0100PA00X+054788Y+051574               S3      
317NNAME10934       VIA   -     D0100PA00X+054437Y+051027               S3      
317NNAME10966       VIA   -     D0100PA00X+054437Y+051527               S3      
327PCIE_SW_PRSNT1   U125  -128        A01X+055015Y+053475X0070Y0600R180 S2      
327NNAME10988       U125  -127        A01X+054858Y+053475X0070Y0600R180 S2      
327PCIE_SW_TEST6    U125  -126        A01X+054700Y+053475X0070Y0600R180 S2      
327GND              U125  -125        A01X+054543Y+053475X0070Y0600R180 S2      
327P3V3_NODE1       U125  -124        A01X+054385Y+053475X0070Y0600R180 S2      
327GND              C870  -2          A10X+054544Y+053325X0180Y0200R270 S1      
317GND              VIA   -     D0100PA00X+054414Y+053013               S3      
317PCIE_SW_PRSNT1   VIA   -     D0100PA00X+055486Y+053170               S1      
317PCIE_SW_TEST6    VIA   -     D0100PA00X+054992Y+052724               S1      
327PCIE_SW_WAKE_N   U125  -6          A01X+055625Y+054872X0070Y0600R090 S2      
327P3V3_NODE1       U125  -5          A01X+055625Y+054715X0070Y0600R090 S2      
327P1V0_NODE1       U125  -4          A01X+055625Y+054557X0070Y0600R090 S2      
327GND              U125  -3          A01X+055625Y+054400X0070Y0600R090 S2      
327GND              U125  -2          A01X+055625Y+054242X0070Y0600R090 S2      
327P1V0_NODE1       U125  -1          A01X+055625Y+054085X0070Y0600R090 S2      
327GND              C890  -2          A10X+055761Y+054423X0180Y0200     S1      
327P1V0_NODE1       C890  -1          A10X+055446Y+054423X0180Y0200     S1      
327GND              C888  -2          A10X+055771Y+054813X0180Y0200     S1      
327P3V3_NODE1       C888  -1          A10X+055456Y+054813X0180Y0200     S1      
327P3V3_NODE1       C870  -1          A10X+054544Y+053640X0180Y0200R270 S1      
327GND              C867  -2          A10X+054824Y+054795X0180Y0200R270 S1      
327GND              C330  -2          A10X+055761Y+054033X0180Y0200     S1      
327P1V0_NODE1       C330  -1          A10X+055446Y+054033X0180Y0200     S1      
317GND              VIA   -     D0100PA00X+054541Y+054795               S3      
317P3V3_NODE1       VIA   -     D0100PA00X+055116Y+054715               S3      
317P3V3_NODE1       VIA   -     D0100PA00X+054514Y+053973               S3      
317P1V0_NODE1       VIA   -     D0100PA00X+055154Y+054033               S3      
317P1V0_NODE1       VIA   -     D0100PA00X+055134Y+054423               S3      
327NNAME10989       U125  -16         A01X+055625Y+056447X0070Y0600R090 S2      
327P1V0_NODE1       U125  -15         A01X+055625Y+056290X0070Y0600R090 S2      
327GND              U125  -14         A01X+055625Y+056132X0070Y0600R090 S2      
327NNAME10990       U125  -13         A01X+055625Y+055975X0070Y0600R090 S2      
327PCIE_SW_TEST3    U125  -12         A01X+055625Y+055817X0070Y0600R090 S2      
327PCIE_SW_TEST4    U125  -11         A01X+055625Y+055660X0070Y0600R090 S2      
327PCIE_SW_TEST5    U125  -10         A01X+055625Y+055502X0070Y0600R090 S2      
327N/C              U125  -9          A01X+055625Y+055345X0070Y0600R090 S2      
327P3V3_NODE1       U125  -8          A01X+055625Y+055187X0070Y0600R090 S2      
327PCIE_SW_PRSNT2   U125  -7          A01X+055625Y+055030X0070Y0600R090 S2      
327GND              C889  -2          A10X+055514Y+056145X0180Y0200R270 S1      
327P1V0_NODE1       C889  -1          A10X+055514Y+056460X0180Y0200R270 S1      
327P3V3_NODE1       C867  -1          A10X+054824Y+055110X0180Y0200R270 S1      
317GND              VIA   -     D0100PA00X+055144Y+056123               S3      
317P3V3_NODE1       VIA   -     D0100PA00X+055134Y+055110               S3      
317P1V0_NODE1       VIA   -     D0100PA00X+055144Y+056383               S3      
327PCIE_SW_GPIO5    U125  -26         A01X+055625Y+058022X0070Y0600R090 S2      
327N/C              U125  -25         A01X+055625Y+057864X0070Y0600R090 S2      
327N/C              U125  -24         A01X+055625Y+057707X0070Y0600R090 S2      
327N/C              U125  -23         A01X+055625Y+057549X0070Y0600R090 S2      
327N/C              U125  -22         A01X+055625Y+057392X0070Y0600R090 S2      
327N/C              U125  -21         A01X+055625Y+057235X0070Y0600R090 S2      
327P3V3_NODE1       U125  -20         A01X+055625Y+057077X0070Y0600R090 S2      
327GND              U125  -19         A01X+055625Y+056920X0070Y0600R090 S2      
327NNAME10991       U125  -18         A01X+055625Y+056762X0070Y0600R090 S2      
327NNAME10992       U125  -17         A01X+055625Y+056605X0070Y0600R090 S2      
327GND              C866  -2          A10X+055514Y+056835X0180Y0200R270 S1      
327P3V3_NODE1       C866  -1          A10X+055514Y+057150X0180Y0200R270 S1      
317GND              VIA   -     D0100PA00X+055154Y+056853               S3      
317P3V3_NODE1       VIA   -     D0100PA00X+055124Y+057173               S3      
327P1V0_NODE1       U125  -37         A01X+054385Y+059577X0070Y0600R180 S2      
327GND              U125  -36         A01X+054543Y+059577X0070Y0600R180 S2      
327P3V3_NODE1       U125  -35         A01X+054700Y+059577X0070Y0600R180 S2      
327GND              U125  -34         A01X+054858Y+059577X0070Y0600R180 S2      
327NNAME10993       U125  -33         A01X+055015Y+059577X0070Y0600R180 S2      
327NNAME10994       U125  -32         A01X+055625Y+058967X0070Y0600R090 S2      
327PCIE_SW_TEST1    U125  -31         A01X+055625Y+058809X0070Y0600R090 S2      
327GND              U125  -30         A01X+055625Y+058652X0070Y0600R090 S2      
327P1V0_NODE1       U125  -29         A01X+055625Y+058494X0070Y0600R090 S2      
327PCIE_SW_GPIO7    U125  -28         A01X+055625Y+058337X0070Y0600R090 S2      
327PCIE_SW_GPIO6    U125  -27         A01X+055625Y+058179X0070Y0600R090 S2      
327GND              C874  -2          A10X+054424Y+059720X0180Y0200R090 S1      
327P1V0_NODE1       C874  -1          A10X+054424Y+059405X0180Y0200R090 S1      
327GND              C863  -2          A10X+055514Y+058740X0180Y0200R090 S1      
327P1V0_NODE1       C863  -1          A10X+055514Y+058425X0180Y0200R090 S1      
327GND              C868  -2          A10X+054814Y+059720X0180Y0200R090 S1      
327P3V3_NODE1       C868  -1          A10X+054814Y+059405X0180Y0200R090 S1      
317GND              VIA   -     D0100PA00X+055094Y+058733               S3      
317P3V3_NODE1       VIA   -     D0100PA00X+054700Y+059016               S3      
317P1V0_NODE1       VIA   -     D0100PA00X+055124Y+058403               S3      
317P1V0_NODE1       VIA   -     D0100PA00X+054385Y+059031               S3      
327GND              U13   -4          A01X+055920Y+060120X0220Y0680R270 S2      
327N49382752        U13   -3          A01X+055920Y+060620X0220Y0680R270 S2      
327N49382752        U13   -2          A01X+055920Y+061120X0220Y0680R270 S2      
327NNAME10993       R279  -2          A01X+054694Y+060785X0180Y0200R090 S2      
327GND              R279  -1          A01X+054694Y+061100X0180Y0200R090 S2      
317GND              VIA   -     D0100PA00X+054814Y+060043               S3      
317GND              VIA   -     D0100PA00X+054464Y+060053               S3      
317GND              VIA   -     D0100PA00X+055362Y+060120               S3      
317NNAME10993       VIA   -     D0100PA00X+055015Y+060464               S1      
327P3V3_NODE1       OSC6  -4          A01X+055745Y+062476X0380Y0480R270 S2      
327N31521711        OSC6  -3          A01X+054879Y+062476X0380Y0480R270 S2      
327N49382752        U13   -1          A01X+055920Y+061620X0220Y0680R270 S2      
327N49382752        R1226 -2          A01X+054878Y+061710X0180Y0200R180 S2      
327GND              R1226 -1          A01X+054563Y+061710X0180Y0200R180 S2      
317GND              VIA   -     D0100PA00X+054694Y+061383               S3      
317N31521711        VIA   -     D0100PA00X+054340Y+062596               S1      
317N49382752        VIA   -     D0100PA00X+055235Y+061403               S1      
327NNAME10945       U129  -71         A01X+055719Y+064314X0110Y0590     S2      
327NNAME10995       U129  -70         A01X+055522Y+064314X0110Y0590     S2      
327NNAME10973       U129  -69         A01X+055325Y+064314X0110Y0590     S2      
327NNAME10972       U129  -68         A01X+055128Y+064314X0110Y0590     S2      
327NNAME10889       U129  -67         A01X+054931Y+064314X0110Y0590     S2      
327NNAME10971       U129  -66         A01X+054735Y+064314X0110Y0590     S2      
327GND              U129  -65         A01X+054538Y+064314X0110Y0590     S2      
327CLK_33K_CPLD23   U129  -64         A01X+054341Y+064314X0110Y0590     S2      
327GND              OSC6  -2          A01X+054879Y+063165X0380Y0480R270 S2      
327N31521709        OSC6  -1          A01X+055745Y+063165X0380Y0480R270 S2      
327CLK_33K_CPLD23   R1055 -2          A01X+054340Y+063246X0180Y0200R270 S2      
327N31521711        R1055 -1          A01X+054340Y+062931X0180Y0200R270 S2      
327NNAME10912       R989  -2          A10X+054849Y+064316X0180Y0200R180 S1      
327NNAME10995       R989  -1          A10X+055164Y+064316X0180Y0200R180 S1      
327NNAME10996       R995  -1          A10X+055551Y+064212X0180Y0200R090 S1      
317GND              VIA   -     D0100PA00X+055285Y+063165               S3      
317NNAME10996       VIA   -     D0100PA00X+055828Y+063784               S1      
317NNAME10995       VIA   -     D0100PA00X+055103Y+063720               S1      
317CLK_33K_CPLD23   VIA   -     D0100PA00X+054340Y+063562               S1      
327GND              C905  -2          A10X+054477Y+064493X0180Y0200     S1      
327NNAME10971       R977  -1          A10X+054503Y+065028X0180Y0200R180 S1      
327NNAME10919       R995  -2          A10X+055551Y+064527X0180Y0200R090 S1      
317GND              VIA   -     D0100PA00X+054538Y+064759               S3      
317NNAME10889       VIA   -     D0100PA00X+054931Y+064759               S1      
317NNAME10973       VIA   -     D0100PA00X+055123Y+065284               S1      
327P3V3_NODE1       R743  -1          A10X+055777Y+066916X0180Y0200     S1      
327P5V_NODE1        R728  -2          A10X+055777Y+067316X0180Y0200R180 S1      
327P3V3_NODE1       R734  -1          A10X+055777Y+066516X0180Y0200     S1      
317P3V3_NODE1       VIA   -     D0100PA00X+055536Y+066516               S3      
317P3V3_NODE1       VIA   -     D0100PA00X+055536Y+066916               S3      
317P5V_NODE1        VIA   -     D0100PA00X+055531Y+067316               S3      
317NNAME10972       VIA   -     D0100PA00X+055128Y+067080               S1      
327P5V_NODE1        R729  -2          A10X+055777Y+067716X0180Y0200R180 S1      
327P5V_NODE1        R732  -2          A10X+055777Y+068916X0180Y0200R180 S1      
327P5V_NODE1        R731  -2          A10X+055777Y+068516X0180Y0200R180 S1      
327P5V_NODE1        R730  -2          A10X+055777Y+068116X0180Y0200R180 S1      
317P5V_NODE1        VIA   -     D0100PA00X+055536Y+068916               S3      
317P5V_NODE1        VIA   -     D0100PA00X+055528Y+068516               S3      
317P5V_NODE1        VIA   -     D0100PA00X+055524Y+068116               S3      
317P5V_NODE1        VIA   -     D0100PA00X+055531Y+067716               S3      
327CPLD_WDT3        U129  -12         A01X+054341Y+070417X0110Y0590     S2      
327GND              U129  -11         A01X+054538Y+070417X0110Y0590     S2      
327GND              U129  -10         A01X+054735Y+070417X0110Y0590     S2      
327P3V3_NODE1       U129  -9          A01X+054931Y+070417X0110Y0590     S2      
327UART3_RESET_N    U129  -8          A01X+055128Y+070417X0110Y0590     S2      
327UART_SW_S5_N     U129  -7          A01X+055325Y+070417X0110Y0590     S2      
327UART_SW_S4_N     U129  -6          A01X+055522Y+070417X0110Y0590     S2      
327UART_SW_S3_N     U129  -5          A01X+055719Y+070417X0110Y0590     S2      
327P5V_NODE1        R733  -2          A10X+055777Y+069316X0180Y0200R180 S1      
327P5V_NODE1        R740  -2          A10X+055777Y+070116X0180Y0200R180 S1      
327P5V_NODE1        R736  -2          A10X+055777Y+069716X0180Y0200R180 S1      
317GND              VIA   -     D0100PA00X+054735Y+069758               S3      
317GND              VIA   -     D0100PA00X+054498Y+069942               S3      
317UART3_RESET_N    VIA   -     D0100PA00X+055128Y+069924               S1      
317P5V_NODE1        VIA   -     D0100PA00X+055515Y+069716               S3      
317P5V_NODE1        VIA   -     D0100PA00X+055527Y+069316               S3      
327GND              C901  -2          A01X+054994Y+071617X0180Y0200R270 S2      
327P3V3_NODE1       C901  -1          A01X+054994Y+071302X0180Y0200R270 S2      
317P3V3_NODE1       VIA   -     D0100PA00X+054754Y+071152               S3      
317T9_NODE3_EN      VIA   -     D0100PA00X+054493Y+072082               S1      
317T10_NODE2_EN     VIA   -     D0100PA00X+055054Y+072190               S1      
317NNAME10997       VIA   -     D0100PA00X+055555Y+072234               S1      
317UART_SW_S2_N     VIA   -     D0100PA00X+055749Y+071371               S1      
317UART_SW_S3_N     VIA   -     D0100PA00X+055373Y+071725               S1      
317UART_SW_S5_N     VIA   -     D0100PA00X+055000Y+070956               S1      
317UART_SW_S4_N     VIA   -     D0100PA00X+055506Y+070868               S1      
317CPLD_WDT3        VIA   -     D0100PA00X+054506Y+070868               S1      
327GND              C624  -2          A10X+055094Y+073808X0180Y0200R270 S1      
327GND              C642  -2          A01X+054644Y+073908X0180Y0200R090 S2      
327GND              C627  -2          A10X+054644Y+073808X0180Y0200R270 S1      
327GND              C741  -2          A10X+055544Y+073838X0180Y0200R270 S1      
327GND              C639  -2          A01X+055094Y+073908X0180Y0200R090 S2      
327GND              C636  -2          A01X+055544Y+073908X0180Y0200R090 S2      
327T10_NODE3_EN_R   R879  -2          A01X+054644Y+073073X0180Y0200R270 S2      
327T10_NODE3_EN     R879  -1          A01X+054644Y+072758X0180Y0200R270 S2      
327T9_NODE2_EN_R    R864  -2          A10X+054644Y+072973X0180Y0200R090 S1      
327T9_NODE2_EN      R864  -1          A10X+054644Y+072658X0180Y0200R090 S1      
327NNAME10975       R978  -2          A10X+055544Y+072973X0180Y0200R090 S1      
327NNAME10997       R978  -1          A10X+055544Y+072658X0180Y0200R090 S1      
327T10_NODE2_EN_R   R876  -2          A01X+055094Y+073073X0180Y0200R270 S2      
327T10_NODE2_EN     R876  -1          A01X+055094Y+072758X0180Y0200R270 S2      
327T10_NODE1_EN_R   R873  -2          A01X+055544Y+073073X0180Y0200R270 S2      
327T10_NODE1_EN     R873  -1          A01X+055544Y+072758X0180Y0200R270 S2      
327T9_NODE1_EN_R    R861  -2          A10X+055094Y+072973X0180Y0200R090 S1      
327T9_NODE1_EN      R861  -1          A10X+055094Y+072658X0180Y0200R090 S1      
317GND              VIA   -     D0100PA00X+055515Y+073558               S3      
317GND              VIA   -     D0100PA00X+055094Y+073568               S3      
317GND              VIA   -     D0100PA00X+054644Y+073568               S3      
317UART_DTR_P3_N    VIA   -     D0100PA00X+055319Y+072485               S3      
317T10_NODE3_EN     VIA   -     D0100PA00X+054657Y+072412               S3      
317T10_NODE4_EN     VIA   -     D0100PA00X+054408Y+072446               S3      
317T9_NODE2_EN      VIA   -     D0100PA00X+054905Y+072441               S3      
317T10_NODE1_EN     VIA   -     D0100PA00X+055743Y+072444               S3      
317NNAME10998       VIA   -     D0100PA00X+055798Y+073405               S1      
327T9_NODE1_EN_R    C624  -1          A10X+055094Y+074123X0180Y0200R270 S1      
327T10_NODE3_EN_R   C642  -1          A01X+054644Y+074223X0180Y0200R090 S2      
327T9_NODE2_EN_R    C627  -1          A10X+054644Y+074123X0180Y0200R270 S1      
327NNAME10975       C741  -1          A10X+055544Y+074153X0180Y0200R270 S1      
327T10_NODE2_EN_R   C639  -1          A01X+055094Y+074223X0180Y0200R090 S2      
327T10_NODE1_EN_R   C636  -1          A01X+055544Y+074223X0180Y0200R090 S2      
317T10_NODE3_EN_R   VIA   -     D0100PA00X+054530Y+078315               S1      
317T10_NODE2_EN_R   VIA   -     D0100PA00X+055094Y+077186               S1      
317T10_NODE1_EN_R   VIA   -     D0100PA00X+055487Y+077944               S1      
327NNAME10999       VIA   -           A10X+054935Y+077742X0260Y0260     S1      
327NNAME11000       VIA   -           A10X+055283Y+078502X0260Y0260     S1      
327NNAME11001       VIA   -           A10X+055836Y+077576X0260Y0260     S1      
327NNAME10999       J18   -A47        A10X+054731Y+080787X0300Y1660R180 S1      
327NNAME11000       J18   -A46        A10X+055124Y+080787X0300Y1660R180 S1      
327NNAME11001       J18   -A45        A10X+055518Y+080787X0300Y1660R180 S1      
327GND              J18   -A44        A10X+055912Y+080787X0300Y1660R180 S1      
327T10_NODE2_EN_R   J18   -B47        A01X+054731Y+080787X0300Y1660R180 S2      
327T10_NODE1_EN_R   J18   -B46        A01X+055124Y+080787X0300Y1660R180 S2      
327GND              J18   -B45        A01X+055518Y+080787X0300Y1660R180 S2      
327NNAME11002       J18   -B44        A01X+055912Y+080787X0300Y1660R180 S2      
317GND              VIA   -     D0100PA00X+055518Y+079148               S3      
327SIO_AVCC         C483  -1          A01X+056094Y+010652X0280Y0320R180 S2      
327GNDA             C483  -2          A01X+056094Y+010072X0280Y0320R180 S2      
327GNDA             L37   -2          A01X+057236Y+010312X0180Y0200     S2      
327P5V_NODE1        L36   -2          A01X+056594Y+010005X0180Y0200R090 S2      
327SIO_AVCC         L36   -1          A01X+056594Y+010320X0180Y0200R090 S2      
317SIO_AVCC         VIA   -     D0100PA00X+056609Y+010914               S3      
317GNDA             VIA   -     D0100PA00X+056094Y+009720               S3      
317GNDA             VIA   -     D0100PA00X+056956Y+010312               S1      
317P5V_NODE1        VIA   -     D0100PA00X+056594Y+009682               S3      
327N/C              U43   -102        A01X+056402Y+011842X0110Y0710R180 S2      
327N/C              U43   -101        A01X+056205Y+011842X0110Y0710R180 S2      
327N/C              U43   -100        A01X+056009Y+011842X0110Y0710R180 S2      
327GNDA             VIA   -           A10X+056611Y+011252X0260Y0260     S1      
327NNAME10950       U43   -109        A01X+057312Y+013933X0110Y0710R270 S2      
327N/C              U43   -108        A01X+057312Y+013736X0110Y0710R270 S2      
327N/C              U43   -107        A01X+057312Y+013539X0110Y0710R270 S2      
327N/C              U43   -106        A01X+057312Y+013342X0110Y0710R270 S2      
327N/C              U43   -105        A01X+057312Y+013146X0110Y0710R270 S2      
327N/C              U43   -104        A01X+057312Y+012949X0110Y0710R270 S2      
327N/C              U43   -103        A01X+057312Y+012752X0110Y0710R270 S2      
327P3V3_NODE1       R1194 -2          A10X+057208Y+013640X0180Y0200     S1      
327NNAME10950       R1194 -1          A10X+056893Y+013640X0180Y0200     S1      
327P3V3_NODE1       R1193 -2          A10X+057208Y+014040X0180Y0200     S1      
327NNAME10951       R1193 -1          A10X+056893Y+014040X0180Y0200     S1      
327GND              U43   -117        A01X+057312Y+015508X0110Y0710R270 S2      
327NNAME10979       U43   -116        A01X+057312Y+015311X0110Y0710R270 S2      
327NNAME10978       U43   -115        A01X+057312Y+015114X0110Y0710R270 S2      
327NNAME10976       U43   -114        A01X+057312Y+014917X0110Y0710R270 S2      
327NNAME10977       U43   -113        A01X+057312Y+014720X0110Y0710R270 S2      
327CPLD_WDT3_R      U43   -112        A01X+057312Y+014524X0110Y0710R270 S2      
327NNAME10952       U43   -111        A01X+057312Y+014327X0110Y0710R270 S2      
327NNAME10951       U43   -110        A01X+057312Y+014130X0110Y0710R270 S2      
327P3V3_NODE1       R1078 -2          A10X+057208Y+014440X0180Y0200     S1      
327NNAME10952       R1078 -1          A10X+056893Y+014440X0180Y0200     S1      
327P3V3_NODE1       R1077 -2          A10X+057208Y+014840X0180Y0200     S1      
327NNAME10977       R1077 -1          A10X+056893Y+014840X0180Y0200     S1      
327P3V3_NODE1       R1195 -2          A10X+057208Y+015240X0180Y0200     S1      
327CPLD_WDT3_R      R1195 -1          A10X+056893Y+015240X0180Y0200     S1      
327P3V3_NODE1       R816  -2          A10X+057208Y+015640X0180Y0200     S1      
327NNAME10979       R816  -1          A10X+056893Y+015640X0180Y0200     S1      
327P3V3_NODE1       R1056 -2          A10X+055985Y+014927X0180Y0200     S1      
317P3V3_NODE1       VIA   -     D0100PA00X+056323Y+015022               S3      
317CPLD_WDT3_R      VIA   -     D0100PA00X+056408Y+014537               S1      
327UART_RX_P1       U43   -125        A01X+057312Y+017083X0110Y0710R270 S2      
327UART_TX_P1       U43   -124        A01X+057312Y+016886X0110Y0710R270 S2      
327UART_DSR_P1_N    U43   -123        A01X+057312Y+016689X0110Y0710R270 S2      
327UART_RTS_P1_N    U43   -122        A01X+057312Y+016492X0110Y0710R270 S2      
327UART_DTR_P1_N    U43   -121        A01X+057312Y+016295X0110Y0710R270 S2      
327UART_CTS_P1_N    U43   -120        A01X+057312Y+016098X0110Y0710R270 S2      
327UART_RI_P1_N     U43   -119        A01X+057312Y+015902X0110Y0710R270 S2      
327N/C              U43   -118        A01X+057312Y+015705X0110Y0710R270 S2      
327UART_RI_P1_N     R814  -2          A10X+056893Y+016040X0180Y0200R180 S1      
327P3V3_NODE1       R814  -1          A10X+057208Y+016040X0180Y0200R180 S1      
317UART_RX_P1       VIA   -     D0100PA00X+056341Y+016529               S1      
317UART_DSR_P1_N    VIA   -     D0100PA00X+056327Y+016217               S3      
317UART_RI_P1_N     VIA   -     D0100PA00X+056220Y+015902               S1      
327UART_CTS_P2_N    U43   -128        A01X+057312Y+017673X0110Y0710R270 S2      
327UART_RI_P2_N     U43   -127        A01X+057312Y+017476X0110Y0710R270 S2      
327N/C              U43   -126        A01X+057312Y+017279X0110Y0710R270 S2      
327UART_DSR_P2_N    U43   -3          A01X+056009Y+018583X0110Y0710R180 S2      
327UART_RTS_P2_N    U43   -2          A01X+056205Y+018583X0110Y0710R180 S2      
327UART_DTR_P2_N    U43   -1          A01X+056402Y+018583X0110Y0710R180 S2      
327GND              C481  -2          A10X+055901Y+018302X0180Y0200     S1      
317UART_DTR_P2_N    VIA   -     D0100PA00X+056313Y+017837               S1      
317UART_RTS_P2_N    VIA   -     D0100PA00X+055965Y+017448               S3      
327UART_RTS_P2_N    R1018 -2          A01X+056191Y+020109X0180Y0200R090 S2      
327P5V_NODE1        R629  -1          A01X+057118Y+019969X0440Y0540R270 S2      
317P5V_NODE1        VIA   -     D0100PA00X+056968Y+019520               S1      
317P5V_NODE1        VIA   -     D0100PA00X+057278Y+019520               S3      
327GND              R1018 -1          A01X+056191Y+020424X0180Y0200R090 S2      
327UART_DTR_P2_N    R1016 -2          A01X+056498Y+021068X0180Y0200R180 S2      
327GND              R1016 -1          A01X+056183Y+021068X0180Y0200R180 S2      
327UART_DTR_P2_N    R1015 -2          A01X+056498Y+021468X0180Y0200R180 S2      
327P5V_NODE1        R1015 -1          A01X+056183Y+021468X0180Y0200R180 S2      
327SATA_P7          R629  -2          A01X+057118Y+020717X0440Y0540R270 S2      
317GND              VIA   -     D0100PA00X+056191Y+020739               S3      
327N/C              U30   -11         A01X+057296Y+023589X0070Y0440R180 S2      
327N/C              U30   -10         A01X+057138Y+023589X0070Y0440R180 S2      
327P3V3_NODE1       U30   -9          A01X+056981Y+023589X0070Y0440R180 S2      
327N/C              U30   -8          A01X+056823Y+023589X0070Y0440R180 S2      
327N/C              U30   -7          A01X+056666Y+023589X0070Y0440R180 S2      
327N/C              U30   -6          A01X+056508Y+023589X0070Y0440R180 S2      
327P1V0_SATA        U30   -5          A01X+056351Y+023589X0070Y0440R180 S2      
327N/C              U30   -4          A01X+056193Y+023589X0070Y0440R180 S2      
327N/C              U30   -3          A01X+056036Y+023589X0070Y0440R180 S2      
327N/C              U30   -2          A01X+055878Y+023589X0070Y0440R180 S2      
327P1V0_SATA        C341  -1          A10X+056347Y+023452X0180Y0200R090 S1      
327P3V3_NODE1       C354  -1          A10X+056987Y+023452X0180Y0200R090 S1      
327P1V0_SATA        R804  -2          A01X+056348Y+022253X0440Y0540R180 S2      
317P3V3_NODE1       VIA   -     D0100PA00X+056987Y+023180               S3      
327P1V0_SATA        VIA   -           A10X+056378Y+022702X0260Y0260     S1      
317P1V0_SATA        VIA   -     D0100PA00X+057269Y+022657               S3      
317P1V0_SATA        VIA   -     D0100PA00X+057202Y+022239               S3      
317P1V0_SATA        VIA   -     D0100PA00X+056798Y+022235               S3      
317P1V0_SATA        VIA   -     D0100PA00X+056841Y+022665               S3      
317P1V0_SATA        VIA   -     D0100PA00X+056126Y+023015               S3      
317P1V0_SATA        VIA   -     D0100PA00X+056625Y+023028               S3      
317P1V0_SATA        VIA   -     D0100PA00X+056351Y+023203               S3      
327GND              U30   -TH         A01X+057138Y+025338X1560Y1560R090 S2      
327GND              C341  -2          A10X+056347Y+023767X0180Y0200R090 S1      
327GND              C354  -2          A10X+056987Y+023767X0180Y0200R090 S1      
317GND              VIA   -     D0100PA00X+057158Y+024669               S3      
317GND              VIA   -     D0100PA00X+056468Y+024669               S3      
317GND              VIA   -     D0100PA00X+057148Y+026009               S3      
317GND              VIA   -     D0100PA00X+056468Y+026009               S3      
317GND              VIA   -     D0100PA00X+056468Y+025369               S3      
327N/C              U30   -56         A01X+055878Y+027086X0070Y0440R180 S2      
327N/C              U30   -55         A01X+056036Y+027086X0070Y0440R180 S2      
327NNAME10982       U30   -54         A01X+056193Y+027086X0070Y0440R180 S2      
327NNAME11003       U30   -53         A01X+056351Y+027086X0070Y0440R180 S2      
327NNAME11004       U30   -52         A01X+056508Y+027086X0070Y0440R180 S2      
327P1V0_SATA        U30   -51         A01X+056666Y+027086X0070Y0440R180 S2      
327NNAME10984       U30   -50         A01X+056823Y+027086X0070Y0440R180 S2      
327NNAME10927       U30   -49         A01X+056981Y+027086X0070Y0440R180 S2      
327NNAME10985       U30   -48         A01X+057138Y+027086X0070Y0440R180 S2      
327NNAME10986       U30   -47         A01X+057296Y+027086X0070Y0440R180 S2      
327GND              C338  -2          A10X+056677Y+026902X0180Y0200R270 S1      
327P1V0_SATA        C338  -1          A10X+056677Y+027217X0180Y0200R270 S1      
327GND              C337  -2          A10X+057087Y+026902X0180Y0200R270 S1      
327P1V0_SATA        C337  -1          A10X+057087Y+027217X0180Y0200R270 S1      
317NNAME11004       VIA   -     D0100PA00X+056427Y+027940               S1      
317P1V0_SATA        VIA   -     D0100PA00X+056677Y+027520               S3      
327NNAME10269       R513  -2          A01X+056435Y+028628X0180Y0200R270 S2      
327NNAME11004       R513  -1          A01X+056435Y+028313X0180Y0200R270 S2      
317NNAME10927       VIA   -     D0100PA00X+056688Y+028989               S3      
317NNAME10985       VIA   -     D0100PA00X+056153Y+029819               S1      
317NNAME11003       VIA   -     D0100PA00X+056087Y+028543               S1      
317NNAME10986       VIA   -     D0100PA00X+056595Y+030164               S1      
327N/C                    -1          A10X+057788Y+039524X0390Y0390R270 S1      
327N/C                    -1          A01X+057788Y+039524X0390Y0390R270 S2      
317GND              VIA   -     D0100PA00X+056732Y+041509               S3      
317NNAME10473       VIA   -     D0100PA00X+056531Y+041270               S1      
327CLK_48M_SIO      R135  -2          A01X+055914Y+044875X0180Y0200R090 S2      
327NNAME10961       R135  -1          A01X+055914Y+045190X0180Y0200R090 S2      
317P3V3_CLK_NODE1   VIA   -     D0100PA00X+056598Y+045616               S3      
327P3V3_CLK_NODE1   R12   -2          A01X+056362Y+046096X0180Y0200R180 S2      
327SEL_PCI_27M      R12   -1          A01X+056047Y+046096X0180Y0200R180 S2      
327P3V3_CLK_NODE1   R13   -2          A01X+056352Y+045616X0180Y0200R180 S2      
327NNAME10960       R13   -1          A01X+056037Y+045616X0180Y0200R180 S2      
317P3V3_CLK_NODE1   VIA   -     D0100PA00X+056606Y+046096               S3      
317NNAME10906       VIA   -     D0100PA00X+057244Y+046432               S1      
317NNAME10905       VIA   -     D0100PA00X+057244Y+046932               S1      
327P1V5_NODE1       R2    -1          A01X+056234Y+047526X0280Y0320     S2      
327NNAME10987       R2    -2          A01X+056234Y+048106X0280Y0320     S2      
317NNAME10987       VIA   -     D0100PA00X+056234Y+048425               S1      
317GND              VIA   -     D0100PA00X+056161Y+050389               S3      
317GND              VIA   -     D0100PA00X+056096Y+051015               S3      
317GND              VIA   -     D0100PA00X+057183Y+050941               S3      
317NNAME10962       VIA   -     D0100PA00X+057384Y+051211               S3      
317NNAME10933       VIA   -     D0100PA00X+056437Y+050412               S3      
317NNAME10932       VIA   -     D0100PA00X+056437Y+050912               S3      
327GND              R1228 -2          A01X+056421Y+052833X0180Y0200R180 S2      
327PCIE_SW_PRSNT1   R1228 -1          A01X+056106Y+052833X0180Y0200R180 S2      
327P3V3_NODE1       R305  -2          A01X+056421Y+053223X0180Y0200R180 S2      
327NNAME10988       R305  -1          A01X+056106Y+053223X0180Y0200R180 S2      
327PCIE_SW_TEST6    R289  -2          A01X+056106Y+052433X0180Y0200     S2      
327GND              R289  -1          A01X+056421Y+052433X0180Y0200     S2      
317GND              VIA   -     D0100PA00X+056779Y+052833               S1      
317GND              VIA   -     D0100PA00X+056807Y+052531               S3      
317P3V3_NODE1       VIA   -     D0100PA00X+056749Y+053223               S3      
327PCIE_SW_TEST5    R288  -2          A01X+056896Y+054543X0180Y0200     S2      
327GND              R288  -1          A01X+057211Y+054543X0180Y0200     S2      
327NNAME10269       R263  -2          A01X+057211Y+054083X0180Y0200R180 S2      
327PCIE_SW_WAKE_N   R263  -1          A01X+056896Y+054083X0180Y0200R180 S2      
317GND              VIA   -     D0100PA00X+056107Y+054400               S3      
317GND              VIA   -     D0100PA00X+056084Y+054033               S3      
317NNAME10988       VIA   -     D0100PA00X+056231Y+053690               S1      
317PCIE_SW_TEST5    VIA   -     D0100PA00X+056630Y+054847               S1      
317PCIE_SW_WAKE_N   VIA   -     D0100PA00X+056319Y+054193               S1      
327PCIE_SW_TEST3    R286  -2          A01X+056896Y+055203X0180Y0200     S2      
327GND              R286  -1          A01X+057211Y+055203X0180Y0200     S2      
327NNAME10989       R233  -2          A01X+056906Y+055983X0180Y0200     S2      
327NNAME10069       R233  -1          A01X+057221Y+055983X0180Y0200     S2      
327NNAME10990       R232  -2          A01X+056896Y+055593X0180Y0200     S2      
327NNAME10068       R232  -1          A01X+057211Y+055593X0180Y0200     S2      
317PCIE_SW_TEST3    VIA   -     D0100PA00X+056634Y+055424               S1      
317NNAME10989       VIA   -     D0100PA00X+056117Y+056447               S1      
327NNAME10992       R276  -2          A01X+056896Y+056773X0180Y0200     S2      
327GND              R276  -1          A01X+057211Y+056773X0180Y0200     S2      
327NNAME10991       R277  -2          A01X+056896Y+057173X0180Y0200     S2      
327GND              R277  -1          A01X+057211Y+057173X0180Y0200     S2      
327PCIE_SW_GPIO5    R308  -2          A01X+056826Y+057563X0180Y0200     S2      
327GND              R308  -1          A01X+057141Y+057563X0180Y0200     S2      
327PCIE_SW_GPIO6    R306  -2          A01X+056826Y+057953X0180Y0200     S2      
327GND              R306  -1          A01X+057141Y+057953X0180Y0200     S2      
317GND              VIA   -     D0100PA00X+057474Y+057953               S1      
317PCIE_SW_GPIO5    VIA   -     D0100PA00X+056586Y+057620               S1      
317PCIE_SW_GPIO6    VIA   -     D0100PA00X+056120Y+058179               S1      
317NNAME10992       VIA   -     D0100PA00X+056638Y+056773               S1      
317NNAME10991       VIA   -     D0100PA00X+056161Y+057178               S1      
327NNAME10994       R278  -2          A01X+056846Y+059133X0180Y0200     S2      
327GND              R278  -1          A01X+057161Y+059133X0180Y0200     S2      
327PCIE_SW_GPIO7    R307  -2          A01X+056836Y+058353X0180Y0200     S2      
327GND              R307  -1          A01X+057151Y+058353X0180Y0200     S2      
327PCIE_SW_TEST1    R285  -2          A01X+056836Y+058743X0180Y0200     S2      
327GND              R285  -1          A01X+057151Y+058743X0180Y0200     S2      
317GND              VIA   -     D0100PA00X+057454Y+059133               S1      
317GND              VIA   -     D0100PA00X+057474Y+058743               S3      
317GND              VIA   -     D0100PA00X+057465Y+058353               S3      
317PCIE_SW_GPIO7    VIA   -     D0100PA00X+056540Y+058477               S1      
317NNAME10994       VIA   -     D0100PA00X+056816Y+059512               S1      
317PCIE_SW_TEST1    VIA   -     D0100PA00X+056157Y+058936               S1      
317NNAME10969       VIA   -     D0100PA00X+057407Y+060620               S1      
317NNAME10968       VIA   -     D0100PA00X+056893Y+060775               S1      
327P3V3_NODE1       R1057 -1          A01X+056281Y+062751X0180Y0200R270 S2      
317P3V3_NODE1       VIA   -     D0100PA00X+056605Y+062751               S3      
317NNAME10766       VIA   -     D0100PA00X+057165Y+062600               S3      
317NNAME10791       VIA   -     D0100PA00X+057473Y+062552               S1      
327NNAME10913       U129  -75         A01X+056506Y+064314X0110Y0590     S2      
327NNAME11005       U129  -74         A01X+056309Y+064314X0110Y0590     S2      
327NNAME10943       U129  -73         A01X+056113Y+064314X0110Y0590     S2      
327NNAME10996       U129  -72         A01X+055916Y+064314X0110Y0590     S2      
327NNAME10915       R1001 -2          A10X+055933Y+064312X0180Y0200R180 S1      
327NNAME11005       R1001 -1          A10X+056248Y+064312X0180Y0200R180 S1      
327N31521709        R1057 -2          A01X+056281Y+063066X0180Y0200R270 S2      
317NNAME11005       VIA   -     D0100PA00X+056565Y+063771               S1      
317N31521709        VIA   -     D0100PA00X+056556Y+063243               S1      
327NNAME11006       U129  -81         A01X+057195Y+065988X0110Y0590R270 S2      
327P3V3_NODE1       U129  -80         A01X+057195Y+065791X0110Y0590R270 S2      
327GND              U129  -79         A01X+057195Y+065594X0110Y0590R270 S2      
327UART_RTS_P3_N    U129  -78         A01X+057195Y+065397X0110Y0590R270 S2      
327NNAME11007       U129  -77         A01X+057195Y+065200X0110Y0590R270 S2      
327NNAME11008       U129  -76         A01X+057195Y+065003X0110Y0590R270 S2      
317I2C_PSU3_SDA     VIA   -     D0100PA00X+057179Y+064680               S1      
317NNAME10943       VIA   -     D0100PA00X+055944Y+065077               S1      
317NNAME11006       VIA   -     D0100PA00X+056695Y+065944               S1      
317NNAME11009       VIA   -     D0100PA00X+056385Y+065958               S3      
317NNAME10913       VIA   -     D0100PA00X+056384Y+065352               S3      
327N21698959        U66   -3          A10X+057144Y+067420X0140Y0590R270 S1      
327N21698757        U66   -2          A10X+057144Y+067164X0140Y0590R270 S1      
327N21700156        U66   -1          A10X+057144Y+066908X0140Y0590R270 S1      
327NNAME11010       U129  -89         A01X+057195Y+067562X0110Y0590R270 S2      
327NNAME11011       U129  -88         A01X+057195Y+067366X0110Y0590R270 S2      
327NNAME11012       U129  -87         A01X+057195Y+067169X0110Y0590R270 S2      
327NNAME10998       U129  -86         A01X+057195Y+066972X0110Y0590R270 S2      
327NNAME10997       U129  -85         A01X+057195Y+066775X0110Y0590R270 S2      
327NNAME11013       U129  -84         A01X+057195Y+066578X0110Y0590R270 S2      
327NNAME11009       U129  -83         A01X+057195Y+066381X0110Y0590R270 S2      
327NNAME11014       U129  -82         A01X+057195Y+066185X0110Y0590R270 S2      
327N21698757        R743  -2          A10X+056092Y+066916X0180Y0200     S1      
327T9_NODE1_EN      R728  -1          A10X+056092Y+067316X0180Y0200R180 S1      
327N21700156        R734  -2          A10X+056092Y+066516X0180Y0200     S1      
327N21698757        VIA   -           A10X+057149Y+066357X0260Y0260     S1      
317N21700156        VIA   -     D0100PA00X+056517Y+066461               S1      
317NNAME11015       VIA   -     D0100PA00X+056517Y+067461               S1      
317NNAME11011       VIA   -     D0100PA00X+056517Y+066961               S1      
327T10_NODE2_EN     U66   -9          A10X+057144Y+068955X0140Y0590R270 S1      
327T10_NODE1_EN     U66   -8          A10X+057144Y+068700X0140Y0590R270 S1      
327T9_NODE4_EN      U66   -7          A10X+057144Y+068444X0140Y0590R270 S1      
327T9_NODE3_EN      U66   -6          A10X+057144Y+068188X0140Y0590R270 S1      
327T9_NODE2_EN      U66   -5          A10X+057144Y+067932X0140Y0590R270 S1      
327T9_NODE1_EN      U66   -4          A10X+057144Y+067676X0140Y0590R270 S1      
327NNAME11016       U129  -97         A01X+057195Y+069137X0110Y0590R270 S2      
327NNAME11017       U129  -96         A01X+057195Y+068940X0110Y0590R270 S2      
327NNAME11018       U129  -95         A01X+057195Y+068744X0110Y0590R270 S2      
327P3V3_NODE1       U129  -94         A01X+057195Y+068547X0110Y0590R270 S2      
327GND              U129  -93         A01X+057195Y+068350X0110Y0590R270 S2      
327NNAME11019       U129  -92         A01X+057195Y+068153X0110Y0590R270 S2      
327NNAME11020       U129  -91         A01X+057195Y+067956X0110Y0590R270 S2      
327NNAME11015       U129  -90         A01X+057195Y+067759X0110Y0590R270 S2      
327T9_NODE2_EN      R729  -1          A10X+056092Y+067716X0180Y0200R180 S1      
327T10_NODE1_EN     R732  -1          A10X+056092Y+068916X0180Y0200R180 S1      
327T9_NODE4_EN      R731  -1          A10X+056092Y+068516X0180Y0200R180 S1      
327T9_NODE3_EN      R730  -1          A10X+056092Y+068116X0180Y0200R180 S1      
317GND              VIA   -     D0100PA00X+056517Y+068461               S1      
317T9_NODE3_EN      VIA   -     D0100PA00X+056359Y+068214               S3      
317T10_NODE2_EN     VIA   -     D0100PA00X+056358Y+069228               S3      
317T9_NODE1_EN      VIA   -     D0100PA00X+056344Y+067687               S3      
317T9_NODE2_EN      VIA   -     D0100PA00X+056517Y+067961               S1      
317T9_NODE4_EN      VIA   -     D0100PA00X+056339Y+068691               S3      
317T10_NODE1_EN     VIA   -     D0100PA00X+056517Y+068961               S1      
327GND              U66   -12         A10X+057144Y+069723X0140Y0590R270 S1      
327T10_NODE4_EN     U66   -11         A10X+057144Y+069467X0140Y0590R270 S1      
327T10_NODE3_EN     U66   -10         A10X+057144Y+069211X0140Y0590R270 S1      
327UART_SW_S2_N     U129  -4          A01X+055916Y+070417X0110Y0590     S2      
327UART_SW_S1_N     U129  -3          A01X+056113Y+070417X0110Y0590     S2      
327UART_SW_S0_N     U129  -2          A01X+056309Y+070417X0110Y0590     S2      
327NNAME11021       U129  -1          A01X+056506Y+070417X0110Y0590     S2      
327NNAME11022       U129  -100        A01X+057195Y+069728X0110Y0590R270 S2      
327NNAME11023       U129  -99         A01X+057195Y+069531X0110Y0590R270 S2      
327NNAME10883       U129  -98         A01X+057195Y+069334X0110Y0590R270 S2      
327T10_NODE2_EN     R733  -1          A10X+056092Y+069316X0180Y0200R180 S1      
327T10_NODE4_EN     R740  -1          A10X+056092Y+070116X0180Y0200R180 S1      
327T10_NODE3_EN     R736  -1          A10X+056092Y+069716X0180Y0200R180 S1      
317GND              VIA   -     D0100PA00X+056822Y+070234               S3      
317T10_NODE3_EN     VIA   -     D0100PA00X+056517Y+069461               S1      
317T10_NODE4_EN     VIA   -     D0100PA00X+056517Y+069961               S1      
327GND              R807  -2          A01X+056507Y+071617X0180Y0200R270 S2      
327NNAME11021       R807  -1          A01X+056507Y+071302X0180Y0200R270 S2      
317GND              VIA   -     D0100PA00X+056829Y+071555               S3      
317T9_NODE1_EN      VIA   -     D0100PA00X+056054Y+071809               S1      
317NNAME11009       VIA   -     D0100PA00X+056960Y+072125               S1      
317NNAME11020       VIA   -     D0100PA00X+057419Y+071781               S1      
317NNAME11018       VIA   -     D0100PA00X+056432Y+072159               S1      
317UART_SW_S0_N     VIA   -     D0100PA00X+056254Y+071345               S1      
317UART_SW_S1_N     VIA   -     D0100PA00X+056006Y+070868               S1      
317NNAME11016       VIA   -     D0100PA00X+057061Y+071324               S1      
317NNAME11021       VIA   -     D0100PA00X+056506Y+070868               S1      
327GND              C732  -2          A10X+056894Y+072658X0180Y0200R270 S1      
327NNAME11013       C732  -1          A10X+056894Y+072973X0180Y0200R270 S1      
327GND              C735  -2          A10X+056444Y+073858X0180Y0200R270 S1      
327GND              C762  -2          A01X+056444Y+072758X0180Y0200R090 S2      
327NNAME11017       C762  -1          A01X+056444Y+073073X0180Y0200R090 S2      
327GND              C759  -2          A01X+056894Y+073908X0180Y0200R090 S2      
327GND              C729  -2          A10X+057344Y+073858X0180Y0200R270 S1      
327GND              C756  -2          A01X+057344Y+072758X0180Y0200R090 S2      
327NNAME11019       C756  -1          A01X+057344Y+073073X0180Y0200R090 S2      
327GND              C738  -2          A10X+055994Y+072658X0180Y0200R270 S1      
327NNAME10998       C738  -1          A10X+055994Y+072973X0180Y0200R270 S1      
327GND              C765  -2          A01X+055994Y+073908X0180Y0200R090 S2      
327NNAME11019       R993  -1          A01X+057344Y+073908X0180Y0200R270 S2      
327NNAME11013       R969  -1          A10X+056894Y+073858X0180Y0200R090 S1      
327NNAME11024       R996  -2          A01X+056894Y+073073X0180Y0200R270 S2      
327NNAME11020       R996  -1          A01X+056894Y+072758X0180Y0200R270 S2      
327NNAME11025       R966  -2          A10X+057344Y+072973X0180Y0200R090 S1      
327NNAME11006       R966  -1          A10X+057344Y+072658X0180Y0200R090 S1      
327NNAME11017       R999  -1          A01X+056444Y+073908X0180Y0200R270 S2      
327NNAME11000       R972  -2          A10X+056444Y+072973X0180Y0200R090 S1      
327NNAME11009       R972  -1          A10X+056444Y+072658X0180Y0200R090 S1      
327NNAME10998       R975  -1          A10X+055994Y+073858X0180Y0200R090 S1      
327NNAME11002       R1002 -2          A01X+055994Y+073073X0180Y0200R270 S2      
327NNAME11018       R1002 -1          A01X+055994Y+072758X0180Y0200R270 S2      
317GND              VIA   -     D0100PA00X+056891Y+073588               S3      
317GND              VIA   -     D0100PA00X+057344Y+073568               S3      
317GND              VIA   -     D0100PA00X+056444Y+073585               S3      
317GND              VIA   -     D0100PA00X+056035Y+073581               S3      
317GND              VIA   -     D0100PA00X+057344Y+072405               S3      
317GND              VIA   -     D0100PA00X+056894Y+072409               S3      
317GND              VIA   -     D0100PA00X+056240Y+072456               S3      
317NNAME11013       VIA   -     D0100PA00X+057123Y+073255               S3      
317NNAME11017       VIA   -     D0100PA00X+056680Y+073402               S1      
327NNAME11000       C735  -1          A10X+056444Y+074173X0180Y0200R270 S1      
327NNAME11024       C759  -1          A01X+056894Y+074223X0180Y0200R090 S2      
327NNAME11025       C729  -1          A10X+057344Y+074173X0180Y0200R270 S1      
327NNAME11002       C765  -1          A01X+055994Y+074223X0180Y0200R090 S2      
327NNAME11026       R993  -2          A01X+057344Y+074223X0180Y0200R270 S2      
327NNAME11001       R969  -2          A10X+056894Y+074173X0180Y0200R090 S1      
327NNAME11027       R999  -2          A01X+056444Y+074223X0180Y0200R270 S2      
327NNAME10999       R975  -2          A10X+055994Y+074173X0180Y0200R090 S1      
317NNAME11024       VIA   -     D0100PA00X+056968Y+077111               S1      
317NNAME11002       VIA   -     D0100PA00X+056015Y+078135               S1      
327NNAME11028       VIA   -           A10X+057123Y+078513X0260Y0260     S1      
317NNAME11027       VIA   -     D0100PA00X+056270Y+077239               S1      
317NNAME11026       VIA   -     D0100PA00X+057272Y+077718               S1      
327NNAME11029       VIA   -           A10X+056721Y+077853X0260Y0260     S1      
327NNAME11025       VIA   -           A10X+056305Y+078579X0260Y0260     S1      
327NNAME11025       J18   -A43        A10X+056305Y+080787X0300Y1660R180 S1      
327NNAME11029       J18   -A42        A10X+056699Y+080787X0300Y1660R180 S1      
327NNAME11028       J18   -A41        A10X+057093Y+080787X0300Y1660R180 S1      
327NNAME11030       J18   -A40        A10X+057486Y+080787X0300Y1660R180 S1      
327NNAME11027       J18   -B43        A01X+056305Y+080787X0300Y1660R180 S2      
327NNAME11024       J18   -B42        A01X+056699Y+080787X0300Y1660R180 S2      
327NNAME11026       J18   -B41        A01X+057093Y+080787X0300Y1660R180 S2      
327GND              J18   -B40        A01X+057486Y+080787X0300Y1660R180 S2      
317GND              VIA   -     D0100PA00X+055912Y+079148               S3      
317GND              J26   -10   D0460PA00X+057737Y+002880               S0      
317N/C              J26   -8    D0460PA00X+058737Y+002880               S0      
317JTAG_CPLD2_TDI   J26   -9    D0460PA00X+057737Y+003880               S0      
317N/C              J26   -7    D0460PA00X+058737Y+003880               S0      
317N/C              J6    -H1   D0470UA00X+058391Y+006917               S0      
317GND              J6    -4    D0360PA00X+059100Y+006917               S0      
317UART_RX_P4_BUF   J6    -3    D0360PA00X+059100Y+007704               S0      
317UART_TX_P4       J6    -2    D0360PA00X+059100Y+008492               S0      
317P3V3_NODE1       J6    -1    D0360PA00X+059100Y+009279               S0      
327GND              L37   -1          A01X+057551Y+010312X0180Y0200     S2      
317GND              VIA   -     D0100PA00X+057894Y+010312               S1      
317P3V3_NODE1       VIA   -     D0100PA00X+058894Y+009896               S3      
317P3V3_NODE1       VIA   -     D0100PA00X+058931Y+010399               S3      
327GND              C531  -1          A01X+058704Y+011773X0180Y0200R180 S2      
327GND              C530  -2          A01X+058732Y+012184X0180Y0200     S2      
317GND              VIA   -     D0100PA00X+058383Y+011773               S3      
317GND              VIA   -     D0100PA00X+058366Y+012184               S3      
327P3V3_NODE1       R650  -1          A01X+058704Y+013223X0180Y0200R180 S2      
327P3V3_NODE1       R649  -1          A01X+058704Y+012823X0180Y0200R180 S2      
317P3V3_NODE1       VIA   -     D0100PA00X+058050Y+013834               S1      
317P3V3_NODE1       VIA   -     D0100PA00X+058383Y+013223               S1      
317P3V3_NODE1       VIA   -     D0100PA00X+058355Y+012823               S3      
317P5V_NODE1        VIA   -     D0100PA00X+058797Y+013877               S1      
327UART_DTR_P1_N    R1008 -2          A01X+058684Y+015580X0180Y0200R090 S2      
317UART_CTS_P1_N    VIA   -     D0100PA00X+058157Y+015497               S1      
317P3V3_NODE1       VIA   -     D0100PA00X+058397Y+014459               S3      
317P3V3_NODE1       VIA   -     D0100PA00X+058018Y+014889               S3      
317P3V3_NODE1       VIA   -     D0100PA00X+057954Y+014330               S3      
327UART_RTS_P1_N    R1013 -2          A01X+058677Y+016646X0180Y0200R270 S2      
327GND              R1013 -1          A01X+058677Y+016331X0180Y0200R270 S2      
327UART_TX_P1       R1009 -2          A01X+058666Y+017191X0180Y0200     S2      
327P5V_NODE1        R1009 -1          A01X+058981Y+017191X0180Y0200     S2      
327GND              R1008 -1          A01X+058684Y+015895X0180Y0200R090 S2      
317UART_DTR_P1_N    VIA   -     D0100PA00X+057990Y+016136               S1      
317GND              VIA   -     D0100PA00X+058444Y+016093               S3      
317UART_TX_P1       VIA   -     D0100PA00X+058279Y+016763               S1      
327UART_RI_P2_N     R626  -2          A01X+058659Y+017996X0180Y0200     S2      
327P3V3_NODE1       R626  -1          A01X+058974Y+017996X0180Y0200     S2      
327UART_TX_P1       R1010 -2          A01X+058666Y+017591X0180Y0200     S2      
327GND              R1010 -1          A01X+058981Y+017591X0180Y0200     S2      
317UART_RI_P2_N     VIA   -     D0100PA00X+058192Y+017996               S1      
327GND              C496  -2          A01X+058581Y+020141X0280Y0320R180 S2      
327GND              R630  -1          A01X+057918Y+019969X0440Y0540R270 S2      
317GND              VIA   -     D0100PA00X+058292Y+019422               S3      
317GND              VIA   -     D0100PA00X+058869Y+019281               S1      
327SATA_P7          C496  -1          A01X+058581Y+020721X0280Y0320R180 S2      
327SATA_P7          R630  -2          A01X+057918Y+020717X0440Y0540R270 S2      
317SATA_P7          VIA   -     D0100PA00X+058558Y+021052               S1      
327NNAME11031       U30   -19         A01X+058555Y+023589X0070Y0440R180 S2      
327NNAME11032       U30   -18         A01X+058398Y+023589X0070Y0440R180 S2      
327NNAME11033       U30   -17         A01X+058240Y+023589X0070Y0440R180 S2      
327N/C              U30   -16         A01X+058083Y+023589X0070Y0440R180 S2      
327N/C              U30   -15         A01X+057925Y+023589X0070Y0440R180 S2      
327N/C              U30   -14         A01X+057768Y+023589X0070Y0440R180 S2      
327P1V0_SATA        U30   -13         A01X+057611Y+023589X0070Y0440R180 S2      
327N/C              U30   -12         A01X+057453Y+023589X0070Y0440R180 S2      
327P1V0_SATA        C339  -1          A10X+057607Y+023452X0180Y0200R090 S1      
327NNAME11032       R502  -2          A01X+058771Y+022697X0180Y0200R270 S2      
327P3V3_NODE1       R502  -1          A01X+058771Y+022382X0180Y0200R270 S2      
327NNAME11033       R515  -2          A01X+057971Y+022697X0180Y0200R270 S2      
327GND              R515  -1          A01X+057971Y+022382X0180Y0200R270 S2      
327NNAME11033       R514  -2          A01X+058371Y+022697X0180Y0200R270 S2      
327P3V3_NODE1       R514  -1          A01X+058371Y+022382X0180Y0200R270 S2      
317GND              VIA   -     D0100PA00X+057971Y+022066               S3      
317P3V3_NODE1       VIA   -     D0100PA00X+058371Y+022076               S3      
317P3V3_NODE1       VIA   -     D0100PA00X+058771Y+022073               S3      
317NNAME11033       VIA   -     D0100PA00X+057971Y+022940               S1      
317NNAME11032       VIA   -     D0100PA00X+058558Y+023010               S1      
317P1V0_SATA        VIA   -     D0100PA00X+057611Y+023163               S3      
327N/C              U30   -27         A01X+058887Y+025023X0070Y0440R090 S2      
327N/C              U30   -26         A01X+058887Y+024865X0070Y0440R090 S2      
327NNAME11034       U30   -25         A01X+058887Y+024708X0070Y0440R090 S2      
327N/C              U30   -24         A01X+058887Y+024550X0070Y0440R090 S2      
327N/C              U30   -23         A01X+058887Y+024393X0070Y0440R090 S2      
327TP_SATA_NODE1    U30   -22         A01X+058887Y+024235X0070Y0440R090 S2      
327P1V0_SATA        U30   -21         A01X+058887Y+024078X0070Y0440R090 S2      
327NNAME11035       U30   -20         A01X+058887Y+023921X0070Y0440R090 S2      
327GND              C336  -2          A10X+058700Y+024090X0180Y0200R180 S1      
327P1V0_SATA        C336  -1          A10X+059015Y+024090X0180Y0200R180 S1      
327GND              C339  -2          A10X+057607Y+023767X0180Y0200R090 S1      
317GND              VIA   -     D0100PA00X+057808Y+024669               S3      
327NNAME11036       U30   -37         A01X+058887Y+026598X0070Y0440R090 S2      
327NNAME11037       U30   -36         A01X+058887Y+026440X0070Y0440R090 S2      
327NNAME10930       U30   -35         A01X+058887Y+026283X0070Y0440R090 S2      
327NNAME11038       U30   -34         A01X+058887Y+026125X0070Y0440R090 S2      
327NNAME11039       U30   -33         A01X+058887Y+025968X0070Y0440R090 S2      
327NNAME11040       U30   -32         A01X+058887Y+025810X0070Y0440R090 S2      
327NNAME11041       U30   -31         A01X+058887Y+025653X0070Y0440R090 S2      
327NNAME11042       U30   -30         A01X+058887Y+025495X0070Y0440R090 S2      
327NNAME11043       U30   -29         A01X+058887Y+025338X0070Y0440R090 S2      
327GND              U30   -28         A01X+058887Y+025180X0070Y0440R090 S2      
317GND              VIA   -     D0100PA00X+057808Y+025339               S3      
317GND              VIA   -     D0100PA00X+057808Y+026009               S3      
327NNAME10956       U30   -38         A01X+058887Y+026755X0070Y0440R090 S2      
327NNAME10965       U30   -46         A01X+057453Y+027086X0070Y0440R180 S2      
327NNAME10964       U30   -45         A01X+057611Y+027086X0070Y0440R180 S2      
327NNAME10182       U30   -44         A01X+057768Y+027086X0070Y0440R180 S2      
327NNAME10184       U30   -43         A01X+057925Y+027086X0070Y0440R180 S2      
327NNAME11044       U30   -42         A01X+058083Y+027086X0070Y0440R180 S2      
327NNAME11044       U30   -41         A01X+058240Y+027086X0070Y0440R180 S2      
327NNAME11045       U30   -40         A01X+058398Y+027086X0070Y0440R180 S2      
327NNAME11046       U30   -39         A01X+058555Y+027086X0070Y0440R180 S2      
327GND              C350  -2          A10X+057837Y+027809X0180Y0200R180 S1      
327NNAME11044       C350  -1          A10X+058152Y+027809X0180Y0200R180 S1      
327NNAME11044       C349  -2          A10X+058152Y+028209X0180Y0200     S1      
327GND              C349  -1          A10X+057837Y+028209X0180Y0200     S1      
317GND              VIA   -     D0100PA00X+057587Y+028240               S3      
327NNAME11045       VIA   -           A01X+058417Y+027641X0160Y0042R090 S2      
327NNAME11044       VIA   -           A10X+058587Y+028200X0260Y0260     S1      
317NNAME11044       VIA   -     D0100PA00X+058147Y+027480               S3      
327NNAME11045       C333  -2          A01X+058911Y+028952X0180Y0200R090 S2      
327NNAME10087       C333  -1          A01X+058911Y+029267X0180Y0200R090 S2      
327GND              C348  -2          A10X+057837Y+028609X0180Y0200R180 S1      
327NNAME11044       C348  -1          A10X+058152Y+028609X0180Y0200R180 S1      
327GND              C347  -2          A10X+057837Y+029009X0180Y0200R180 S1      
327NNAME11044       C347  -1          A10X+058152Y+029009X0180Y0200R180 S1      
327NNAME11044       L31   -2          A10X+058152Y+029409X0180Y0200     S1      
327P1V8_NODE1       L31   -1          A10X+057837Y+029409X0180Y0200     S1      
317GND              VIA   -     D0100PA00X+057587Y+028990               S3      
317GND              VIA   -     D0100PA00X+057587Y+028600               S3      
317P1V8_NODE1       VIA   -     D0100PA00X+057588Y+029302               S3      
317P1V8_NODE1       VIA   -     D0100PA00X+057591Y+029561               S3      
317GND              VIA   -     D0100PA00X+058385Y+031378               S3      
317GND              VIA   -     D0100PA00X+058558Y+030888               S3      
317GND              VIA   -     D0100PA00X+057917Y+031364               S3      
317NNAME10087       VIA   -     D0100PA00X+058861Y+030503               S1      
317NNAME10182       VIA   -     D0100PA00X+057665Y+031145               S1      
317NNAME10184       VIA   -     D0100PA00X+058165Y+031145               S1      
317GND              VIA   -     D0100PA00X+058374Y+032120               S3      
317NNAME10965       VIA   -     D0100PA00X+058598Y+032325               S1      
317PCIE_SW_P0_ERR   VIA   -     D0100PA00X+057979Y+035474               S3      
317NNAME10633       VIA   -     D0100PA00X+058907Y+042353               S1      
317NNAME10900       VIA   -     D0100PA00X+057883Y+044819               S1      
317GND              VIA   -     D0100PA00X+057555Y+046378               S3      
317GND              VIA   -     D0100PA00X+057565Y+047000               S3      
317P1V5_NODE1       VIA   -     D0100PA00X+058815Y+045960               S3      
327GND              S3    -3          A01X+059543Y+050124X0400Y1260R090 S2      
327RST_BTN_L        S3    -1          A01X+059543Y+051699X0400Y1260R090 S2      
317GND              VIA   -     D0100PA00X+057960Y+050888               S3      
317NNAME10963       VIA   -     D0100PA00X+057884Y+051211               S3      
327GND              R1229 -2          A01X+058501Y+054063X0180Y0200R180 S2      
327PCIE_SW_PRSNT2   R1229 -1          A01X+058186Y+054063X0180Y0200R180 S2      
327PCIE_SW_TEST4    R284  -2          A01X+058186Y+054523X0180Y0200     S2      
327GND              R284  -1          A01X+058501Y+054523X0180Y0200     S2      
317GND              VIA   -     D0100PA00X+058501Y+054796               S1      
317GND              VIA   -     D0100PA00X+057544Y+054543               S3      
317GND              VIA   -     D0100PA00X+058904Y+054883               S3      
317NNAME10269       VIA   -     D0100PA00X+058389Y+053709               S3      
317PCIE_SW_PRSNT2   VIA   -     D0100PA00X+057621Y+054241               S1      
317PCIE_SW_TEST4    VIA   -     D0100PA00X+057584Y+054894               S1      
327P3V3_NODE1       R310  -2          A01X+058441Y+055945X0180Y0200R180 S2      
327NNAME10989       R310  -1          A01X+058126Y+055945X0180Y0200R180 S2      
327P3V3_NODE1       R309  -2          A01X+058448Y+055524X0180Y0200R180 S2      
327NNAME10990       R309  -1          A01X+058133Y+055524X0180Y0200R180 S2      
327SMB_LAN2_CLK     R570  -2          A01X+058844Y+056412X0180Y0200R270 S2      
327P3V3_NODE1       R570  -1          A01X+058844Y+056097X0180Y0200R270 S2      
317GND              VIA   -     D0100PA00X+057524Y+055203               S3      
317P3V3_NODE1       VIA   -     D0100PA00X+058854Y+055742               S3      
317P3V3_NODE1       VIA   -     D0100PA00X+058441Y+056320               S3      
317P3V3_NODE1       VIA   -     D0100PA00X+058354Y+055223               S3      
317NNAME10068       VIA   -     D0100PA00X+057504Y+055473               S3      
317NNAME10069       VIA   -     D0100PA00X+057514Y+055983               S3      
317NNAME10990       VIA   -     D0100PA00X+057778Y+055636               S1      
327NNAME10992       R275  -2          A01X+057887Y+056725X0180Y0200     S2      
327P3V3_NODE1       R275  -1          A01X+058202Y+056725X0180Y0200     S2      
317GND              VIA   -     D0100PA00X+057504Y+056773               S3      
317GND              VIA   -     D0100PA00X+057554Y+057173               S3      
317GND              VIA   -     D0100PA00X+057488Y+057563               S3      
317P3V3_NODE1       VIA   -     D0100PA00X+057811Y+058215               S3      
317P3V3_NODE1       VIA   -     D0100PA00X+058202Y+057124               S3      
327GND              R1227 -2          A01X+058637Y+059002X0180Y0200R090 S2      
327PCIE_SW_WP_N     R1227 -1          A01X+058637Y+059317X0180Y0200R090 S2      
327P3V3_NODE1       R303  -2          A01X+057840Y+058994X0180Y0200R090 S2      
327NNAME10968       R303  -1          A01X+057840Y+059309X0180Y0200R090 S2      
327P3V3_NODE1       R301  -2          A01X+058240Y+058994X0180Y0200R090 S2      
327NNAME10969       R301  -1          A01X+058240Y+059309X0180Y0200R090 S2      
317GND              VIA   -     D0100PA00X+058637Y+058580               S3      
317P3V3_NODE1       VIA   -     D0100PA00X+057840Y+058570               S3      
327PCIE_SW_WP_N     U13   -7          A01X+058000Y+061120X0220Y0680R270 S2      
327NNAME10969       U13   -6          A01X+058000Y+060620X0220Y0680R270 S2      
327NNAME10968       U13   -5          A01X+058000Y+060120X0220Y0680R270 S2      
317NNAME10056       VIA   -     D0100PA00X+058878Y+061106               S1      
317PCIE_SW_WP_N     VIA   -     D0100PA00X+058681Y+060334               S1      
327P3V3_NODE1       U13   -8          A01X+058000Y+061620X0220Y0680R270 S2      
327GND              C191  -2          A01X+058262Y+062596X0180Y0200R270 S2      
327P3V3_NODE1       C191  -1          A01X+058262Y+062281X0180Y0200R270 S2      
317GND              VIA   -     D0100PA00X+057950Y+062596               S3      
317NNAME10757       VIA   -     D0100PA00X+057700Y+062003               S3      
317P3V3_NODE1       VIA   -     D0100PA00X+058550Y+062093               S3      
317NNAME10055       VIA   -     D0100PA00X+058878Y+061606               S1      
327GND              C907  -2          A01X+058474Y+065785X0180Y0200R180 S2      
327P3V3_NODE1       C907  -1          A01X+058159Y+065785X0180Y0200R180 S2      
327UART_RTS_P3_N    R1158 -1          A01X+058877Y+065339X0180Y0200R180 S2      
317GND              VIA   -     D0100PA00X+058744Y+065696               S3      
317GND              VIA   -     D0100PA00X+057670Y+065559               S3      
317UART_RTS_P3_N    VIA   -     D0100PA00X+058895Y+065007               S3      
317NNAME10757       VIA   -     D0100PA00X+058393Y+065244               S1      
317P3V3_NODE1       VIA   -     D0100PA00X+057902Y+065825               S3      
317NNAME11007       VIA   -     D0100PA00X+057722Y+065200               S1      
317NNAME11014       VIA   -     D0100PA00X+057699Y+066018               S1      
317NNAME11008       VIA   -     D0100PA00X+058074Y+065329               S3      
327GND              C572  -1          A10X+058742Y+066383X0180Y0200     S1      
317GND              VIA   -     D0100PA00X+058490Y+066383               S3      
317NNAME11013       VIA   -     D0100PA00X+058064Y+066363               S1      
317NNAME11010       VIA   -     D0100PA00X+057685Y+067599               S3      
317NNAME10998       VIA   -     D0100PA00X+057908Y+066960               S3      
317NNAME10997       VIA   -     D0100PA00X+057652Y+066775               S3      
327GND              C904  -2          A01X+058455Y+068603X0180Y0200R180 S2      
327P3V3_NODE1       C904  -1          A01X+058140Y+068603X0180Y0200R180 S2      
327P3V3_NODE1       R1261 -2          A01X+058980Y+068391X0180Y0200R090 S2      
327NNAME10883       R1261 -1          A01X+058980Y+068706X0180Y0200R090 S2      
327GND              R794  -2          A01X+058454Y+069008X0180Y0200R180 S2      
327NNAME11016       R794  -1          A01X+058139Y+069008X0180Y0200R180 S2      
317GND              VIA   -     D0100PA00X+058606Y+068258               S3      
317GND              VIA   -     D0100PA00X+058704Y+068822               S3      
317P3V3_NODE1       VIA   -     D0100PA00X+058905Y+068016               S3      
317P3V3_NODE1       VIA   -     D0100PA00X+057998Y+068314               S3      
317NNAME11020       VIA   -     D0100PA00X+057664Y+067956               S3      
317NNAME11017       VIA   -     D0100PA00X+057803Y+069024               S3      
317NNAME11019       VIA   -     D0100PA00X+057701Y+068272               S3      
317NNAME11018       VIA   -     D0100PA00X+057652Y+068767               S3      
317NNAME10883       VIA   -     D0100PA00X+058950Y+069055               S3      
327P5V_NODE1        R742  -2          A10X+058365Y+070545X0180Y0200R090 S1      
327T11_NODE2_EN     R742  -1          A10X+058365Y+070230X0180Y0200R090 S1      
327P5V_NODE1        R741  -2          A10X+058815Y+070545X0180Y0200R090 S1      
327T11_NODE1_EN     R741  -1          A10X+058815Y+070230X0180Y0200R090 S1      
327P5V_NODE1        R744  -2          A10X+057915Y+070545X0180Y0200R090 S1      
327T11_NODE3_EN     R744  -1          A10X+057915Y+070230X0180Y0200R090 S1      
327GND              R806  -2          A01X+058454Y+069408X0180Y0200R180 S2      
327NNAME10883       R806  -1          A01X+058139Y+069408X0180Y0200R180 S2      
317GND              VIA   -     D0100PA00X+058700Y+069408               S3      
317P5V_NODE1        VIA   -     D0100PA00X+057915Y+070786               S3      
317P5V_NODE1        VIA   -     D0100PA00X+058815Y+070786               S3      
317P5V_NODE1        VIA   -     D0100PA00X+058410Y+070789               S3      
317T11_NODE3_EN     VIA   -     D0100PA00X+057644Y+070549               S3      
317NNAME11023       VIA   -     D0100PA00X+058540Y+069729               S3      
317T11_NODE2_EN     VIA   -     D0100PA00X+058431Y+071072               S1      
317NNAME11006       VIA   -     D0100PA00X+057922Y+072078               S3      
317NNAME11015       VIA   -     D0100PA00X+058569Y+072243               S3      
327GND              C726  -2          A10X+057794Y+072658X0180Y0200R270 S1      
327NNAME11014       C726  -1          A10X+057794Y+072973X0180Y0200R270 S1      
327GND              C753  -2          A01X+058344Y+073908X0180Y0200R090 S2      
327GND              C723  -2          A10X+058794Y+073808X0180Y0200R270 S1      
327GND              C750  -2          A01X+058794Y+072758X0180Y0200R090 S2      
327NNAME11015       C750  -1          A01X+058794Y+073073X0180Y0200R090 S2      
327NNAME11015       R987  -1          A01X+058794Y+073908X0180Y0200R270 S2      
327NNAME11047       R990  -2          A01X+058344Y+073073X0180Y0200R270 S2      
327NNAME11010       R990  -1          A01X+058344Y+072758X0180Y0200R270 S2      
327NNAME11028       R960  -2          A10X+058794Y+072973X0180Y0200R090 S1      
327NNAME11008       R960  -1          A10X+058794Y+072658X0180Y0200R090 S1      
327NNAME11014       R963  -1          A10X+057794Y+073858X0180Y0200R090 S1      
317GND              VIA   -     D0100PA00X+058344Y+073586               S3      
317GND              VIA   -     D0100PA00X+058794Y+073568               S3      
317GND              VIA   -     D0100PA00X+058796Y+072411               S3      
317GND              VIA   -     D0100PA00X+057794Y+072413               S3      
317NNAME11010       VIA   -     D0100PA00X+058344Y+072493               S1      
317NNAME11019       VIA   -     D0100PA00X+057757Y+073412               S1      
317NNAME11014       VIA   -     D0100PA00X+058051Y+072442               S3      
327NNAME11047       C753  -1          A01X+058344Y+074223X0180Y0200R090 S2      
327NNAME11028       C723  -1          A10X+058794Y+074123X0180Y0200R270 S1      
327NNAME11048       R987  -2          A01X+058794Y+074223X0180Y0200R270 S2      
327NNAME11029       R963  -2          A10X+057794Y+074173X0180Y0200R090 S1      
327T11_NODE3_EN_R   VIA   -           A10X+058668Y+078602X0260Y0260     S1      
327T11_NODE4_EN_R   VIA   -           A10X+058388Y+077925X0260Y0260     S1      
327NNAME11030       VIA   -           A10X+057833Y+078501X0260Y0260     S1      
317NNAME11048       VIA   -     D0100PA00X+058717Y+077377               S1      
317NNAME11047       VIA   -     D0100PA00X+057924Y+077515               S1      
327GND              J18   -A39        A10X+057880Y+080787X0300Y1660R180 S1      
327T11_NODE4_EN_R   J18   -A38        A10X+058274Y+080787X0300Y1660R180 S1      
327T11_NODE3_EN_R   J18   -A37        A10X+058668Y+080787X0300Y1660R180 S1      
327T11_NODE2_EN_R   J18   -A36        A10X+059061Y+080787X0300Y1660R180 S1      
327NNAME11047       J18   -B39        A01X+057880Y+080787X0300Y1660R180 S2      
327NNAME11048       J18   -B38        A01X+058274Y+080787X0300Y1660R180 S2      
327NNAME11049       J18   -B37        A01X+058668Y+080787X0300Y1660R180 S2      
327NNAME11050       J18   -B36        A01X+059061Y+080787X0300Y1660R180 S2      
317GND              VIA   -     D0100PA00X+057880Y+079148               S3      
317GND              VIA   -     D0100PA00X+057486Y+079148               S3      
317N/C              J26   -6    D0460PA00X+059737Y+002880               S0      
317P3V3_NODE1       J26   -4    D0460PA00X+060737Y+002880               S0      
317JTAG_CPLD2_TMS   J26   -5    D0460PA00X+059737Y+003880               S0      
317JTAG_CPLD2_TDO   J26   -3    D0460PA00X+060737Y+003880               S0      
317N/C              J5    -H1   D0470UA00X+060857Y+006917               S0      
317P3V3_NODE1       VIA   -     D0100PA00X+060316Y+009154               S3      
327N21624848        C533  -1          A01X+060304Y+010473X0180Y0200R180 S2      
317P3V3_NODE1       VIA   -     D0100PA00X+060137Y+009405               S3      
317P3V3_NODE1       VIA   -     D0100PA00X+060454Y+009489               S3      
317P3V3_NODE1       VIA   -     D0100PA00X+059812Y+010202               S3      
317P3V3_NODE1       VIA   -     D0100PA00X+059532Y+009885               S3      
317P3V3_NODE1       VIA   -     D0100PA00X+059385Y+010376               S3      
317P3V3_NODE1       VIA   -     D0100PA00X+059239Y+010062               S3      
327N21624848        U51   -28         A01X+060012Y+011510X0140Y0590R090 S2      
327N21624890        U51   -27         A01X+060012Y+011766X0140Y0590R090 S2      
327P3V3_NODE1       U51   -26         A01X+060012Y+012022X0140Y0590R090 S2      
327GND              U51   -25         A01X+060012Y+012278X0140Y0590R090 S2      
327N21624890        C531  -2          A01X+059019Y+011773X0180Y0200R180 S2      
327P3V3_NODE1       C530  -1          A01X+059047Y+012184X0180Y0200     S2      
317GND              VIA   -     D0100PA00X+059492Y+012337               S3      
317P3V3_NODE1       VIA   -     D0100PA00X+059535Y+012022               S3      
317N21624850        VIA   -     D0100PA00X+060507Y+012399               S1      
317N21624848        VIA   -     D0100PA00X+060012Y+011257               S1      
317N21624890        VIA   -     D0100PA00X+059294Y+011766               S1      
327N21624850        U51   -24         A01X+060012Y+012533X0140Y0590R090 S2      
327N21624804        U51   -23         A01X+060012Y+012789X0140Y0590R090 S2      
327N21624806        U51   -22         A01X+060012Y+013045X0140Y0590R090 S2      
327N/C              U51   -21         A01X+060012Y+013301X0140Y0590R090 S2      
327N/C              U51   -20         A01X+060012Y+013557X0140Y0590R090 S2      
327UART_RX_P1       U51   -19         A01X+060012Y+013813X0140Y0590R090 S2      
327N21624806        R650  -2          A01X+059019Y+013223X0180Y0200R180 S2      
327N21624804        R649  -2          A01X+059019Y+012823X0180Y0200R180 S2      
317UART_RX_P1       VIA   -     D0100PA00X+059544Y+013813               S3      
317UART_DSR_P1_N    VIA   -     D0100PA00X+059294Y+014069               S1      
317N21624806        VIA   -     D0100PA00X+059294Y+013323               S1      
317N21624804        VIA   -     D0100PA00X+059494Y+012789               S1      
327UART_DSR_P1_N    U51   -18         A01X+060012Y+014069X0140Y0590R090 S2      
327UART_CTS_P1_N    U51   -17         A01X+060012Y+014325X0140Y0590R090 S2      
327N/C              U51   -16         A01X+060012Y+014581X0140Y0590R090 S2      
327N/C              U51   -15         A01X+060012Y+014837X0140Y0590R090 S2      
327UART_DTR_P1_N    R1005 -2          A01X+059084Y+015580X0180Y0200R090 S2      
327UART_RTS_P1_N    R1011 -2          A01X+059077Y+016646X0180Y0200R270 S2      
327P5V_NODE1        R1011 -1          A01X+059077Y+016331X0180Y0200R270 S2      
327P5V_NODE1        R1005 -1          A01X+059084Y+015895X0180Y0200R090 S2      
317GND              J7    -8    D0560PA00X+060580Y+016516               S0      
317P5V_NODE1        VIA   -     D0100PA00X+059354Y+016102               S3      
317P5V_NODE1        VIA   -     D0100PA00X+059292Y+017191               S3      
317GND              J7    -1    D0260PA00X+060580Y+017485               S0      
317GND              VIA   -     D0100PA00X+059249Y+017591               S3      
317P3V3_NODE1       VIA   -     D0100PA00X+059328Y+017996               S3      
327GND              C495  -2          A01X+059060Y+020231X0180Y0200R090 S2      
317GND              J7    -4    D0260PA00X+060580Y+018985               S0      
317SATA_P7          J7    -7    D0260PA00X+060580Y+020485               S0      
327SATA_P7          C495  -1          A01X+059060Y+020546X0180Y0200R090 S2      
327NNAME11031       R517  -2          A01X+059171Y+022697X0180Y0200R270 S2      
327P3V3_NODE1       R517  -1          A01X+059171Y+022382X0180Y0200R270 S2      
327NNAME11031       R518  -2          A01X+059571Y+022697X0180Y0200R270 S2      
327GND              R518  -1          A01X+059571Y+022382X0180Y0200R270 S2      
317GND              VIA   -     D0100PA00X+059571Y+022100               S3      
317P3V3_NODE1       VIA   -     D0100PA00X+059171Y+022110               S3      
317NNAME11031       VIA   -     D0100PA00X+059171Y+023016               S1      
327GND              C358  -2          A10X+059674Y+024282X0180Y0200R270 S1      
327NNAME11034       C358  -1          A10X+059674Y+024597X0180Y0200R270 S1      
327GND              C356  -2          A10X+060474Y+024282X0180Y0200R270 S1      
327NNAME11034       C356  -1          A10X+060474Y+024597X0180Y0200R270 S1      
327NNAME11034       C357  -2          A10X+060074Y+024597X0180Y0200R090 S1      
327GND              C357  -1          A10X+060074Y+024282X0180Y0200R090 S1      
327NNAME11035       R503  -2          A01X+059900Y+023630X0180Y0200     S2      
327GND              R503  -1          A01X+060215Y+023630X0180Y0200     S2      
317GND              VIA   -     D0100PA00X+059707Y+024000               S3      
317GND              VIA   -     D0100PA00X+060087Y+023980               S3      
317GND              VIA   -     D0100PA00X+060477Y+024980               S3      
317GND              VIA   -     D0100PA00X+059677Y+024980               S3      
317GND              VIA   -     D0100PA00X+060087Y+024980               S3      
317GND              VIA   -     D0100PA00X+060467Y+024000               S3      
317GND              VIA   -     D0100PA00X+059287Y+025100               S3      
317GND              VIA   -     D0100PA00X+060567Y+023630               S3      
317NNAME11035       VIA   -     D0100PA00X+059537Y+023680               S1      
317NNAME11034       VIA   -     D0100PA00X+059286Y+024708               S3      
317P1V0_SATA        VIA   -     D0100PA00X+059346Y+024078               S3      
327GND              C346  -2          A10X+059674Y+025422X0180Y0200R270 S1      
327NNAME11041       C346  -1          A10X+059674Y+025737X0180Y0200R270 S1      
327GND              C362  -2          A10X+059664Y+026627X0180Y0200R090 S1      
327NNAME11038       C362  -1          A10X+059664Y+026312X0180Y0200R090 S1      
327GND              C344  -2          A10X+060474Y+025422X0180Y0200R270 S1      
327NNAME11041       C344  -1          A10X+060474Y+025737X0180Y0200R270 S1      
327NNAME11041       C345  -2          A10X+060074Y+025737X0180Y0200R090 S1      
327GND              C345  -1          A10X+060074Y+025422X0180Y0200R090 S1      
327GND              C360  -2          A10X+060464Y+026627X0180Y0200R090 S1      
327NNAME11038       C360  -1          A10X+060464Y+026312X0180Y0200R090 S1      
327NNAME11038       C361  -2          A10X+060064Y+026312X0180Y0200R270 S1      
327GND              C361  -1          A10X+060064Y+026627X0180Y0200R270 S1      
317NNAME10930       VIA   -     D0100PA00X+059407Y+026517               S3      
317NNAME11041       VIA   -     D0100PA00X+059417Y+025670               S3      
317NNAME11038       VIA   -     D0100PA00X+059387Y+026240               S3      
327NNAME11039       VIA   -           A01X+059529Y+026050X0160Y0042     S2      
327NNAME11037       R505  -2          A01X+059913Y+027189X0180Y0200     S2      
327GND              R505  -1          A01X+060228Y+027189X0180Y0200     S2      
327GND              R504  -2          A01X+060228Y+027639X0180Y0200R180 S2      
327NNAME11036       R504  -1          A01X+059913Y+027639X0180Y0200R180 S2      
317GND              VIA   -     D0100PA00X+059657Y+026870               S3      
317GND              VIA   -     D0100PA00X+060067Y+026880               S3      
317GND              VIA   -     D0100PA00X+060457Y+026880               S3      
317GND              VIA   -     D0100PA00X+060493Y+027848               S3      
317GND              VIA   -     D0100PA00X+060477Y+027189               S3      
317NNAME10956       VIA   -     D0100PA00X+059087Y+027520               S3      
317NNAME11037       VIA   -     D0100PA00X+059437Y+027140               S1      
317NNAME11036       VIA   -     D0100PA00X+059657Y+027639               S1      
327NNAME11046       C332  -2          A01X+059311Y+028952X0180Y0200R090 S2      
327NNAME10088       C332  -1          A01X+059311Y+029267X0180Y0200R090 S2      
327NNAME11046       VIA   -           A01X+059177Y+028499X0160Y0042R090 S2      
317GND              VIA   -     D0100PA00X+059220Y+030899               S3      
317NNAME10088       VIA   -     D0100PA00X+059361Y+030503               S1      
317GND              VIA   -     D0100PA00X+059198Y+031936               S3      
317NNAME10964       VIA   -     D0100PA00X+059098Y+032325               S1      
317NNAME10269       VIA   -     D0100PA00X+059855Y+032954               S3      
317NNAME11003       VIA   -     D0100PA00X+060145Y+032651               S3      
327NNAME11051       R528  -2          A01X+060434Y+034476X0180Y0200R270 S2      
327P3V3_NODE1       R528  -1          A01X+060434Y+034161X0180Y0200R270 S2      
317P3V3_NODE1       VIA   -     D0100PA00X+060434Y+033829               S1      
327NNAME11052       R530  -2          A01X+060409Y+035275X0180Y0200R270 S2      
327NNAME11053       R530  -1          A01X+060409Y+034960X0180Y0200R270 S2      
327P3V3_NODE1       R531  -2          A01X+060449Y+036114X0180Y0200R270 S2      
327NNAME11052       R531  -1          A01X+060449Y+035799X0180Y0200R270 S2      
317NNAME11003       VIA   -     D0100PA00X+060077Y+035870               S3      
317GND              VIA   -     D0100PA00X+060575Y+038784               S3      
317NNAME11054       VIA   -     D0100PA00X+059744Y+039169               S1      
317GND              VIA   -     D0100PA00X+060557Y+039392               S3      
317NNAME10269       VIA   -     D0100PA00X+059486Y+039509               S3      
317NNAME10269       VIA   -     D0100PA00X+060068Y+041278               S3      
317NNAME10541       VIA   -     D0100PA00X+059072Y+045608               S1      
317NNAME10627       VIA   -     D0100PA00X+059110Y+045013               S1      
317NNAME10048       VIA   -     D0100PA00X+060580Y+046317               S1      
317CPLD_ROW_LATCH   VIA   -     D0100PA00X+060382Y+048533               S1      
317GND              VIA   -     D0100PA00X+060580Y+050124               S1      
317NNAME10269       VIA   -     D0100PA00X+059867Y+050817               S3      
327RST_BTN_L        C801  -2          A01X+060298Y+053211X0180Y0200R180 S2      
327GND              C801  -1          A01X+059983Y+053211X0180Y0200R180 S2      
317GND              VIA   -     D0100PA00X+059675Y+053211               S1      
317RST_BTN_L        VIA   -     D0100PA00X+060301Y+052791               S1      
327NNAME11055       R1067 -2          A01X+059983Y+054411X0180Y0200     S2      
327NNAME11056       R1067 -1          A01X+060298Y+054411X0180Y0200     S2      
327RST_BTN_L        R1063 -2          A01X+059983Y+054011X0180Y0200     S2      
327NNAME11056       R1063 -1          A01X+060298Y+054011X0180Y0200     S2      
327P3V3_STB_NODE1   R1062 -2          A01X+059983Y+053611X0180Y0200     S2      
327RST_BTN_L        R1062 -1          A01X+060298Y+053611X0180Y0200     S2      
317P3V3_STB_NODE1   VIA   -     D0100PA00X+059656Y+053611               S3      
327SMB_LAN2_ALT_N   R569  -2          A01X+059644Y+056412X0180Y0200R270 S2      
327P3V3_NODE1       R569  -1          A01X+059644Y+056097X0180Y0200R270 S2      
327SMB_LAN2_ALT_N   R591  -2          A01X+060044Y+056412X0180Y0200R270 S2      
327NNAME10320       R591  -1          A01X+060044Y+056097X0180Y0200R270 S2      
327SMB_LAN2_DAT     R566  -2          A01X+060444Y+056412X0180Y0200R270 S2      
327P3V3_NODE1       R566  -1          A01X+060444Y+056097X0180Y0200R270 S2      
327SMB_LAN2_CLK     R593  -2          A01X+059244Y+056412X0180Y0200R270 S2      
327SMB_PCH_SCL      R593  -1          A01X+059244Y+056097X0180Y0200R270 S2      
317SMB_PCH_SCL      VIA   -     D0100PA00X+060630Y+055184               S3      
317NNAME10320       VIA   -     D0100PA00X+060482Y+055504               S1      
317P3V3_NODE1       VIA   -     D0100PA00X+060444Y+055796               S3      
317P3V3_NODE1       VIA   -     D0100PA00X+059605Y+055756               S3      
327GND              C528  -2          A01X+059949Y+057890X0180Y0200     S2      
327NNAME11057       C528  -1          A01X+060264Y+057890X0180Y0200     S2      
327GND              C529  -2          A01X+059949Y+057490X0180Y0200     S2      
327NNAME11058       C529  -1          A01X+060264Y+057490X0180Y0200     S2      
317GND              VIA   -     D0100PA00X+059653Y+057490               S3      
317GND              VIA   -     D0100PA00X+059650Y+057890               S3      
317SMB_LAN2_CLK     VIA   -     D0100PA00X+059244Y+056654               S1      
317SMB_LAN2_ALT_N   VIA   -     D0100PA00X+060104Y+056778               S1      
327GND              C527  -2          A01X+059949Y+058290X0180Y0200     S2      
327LAN2_LED_ACT_N   C527  -1          A01X+060264Y+058290X0180Y0200     S2      
327LAN2_TEST_EN     R588  -2          A01X+060264Y+058690X0180Y0200R180 S2      
327GND              R588  -1          A01X+059949Y+058690X0180Y0200R180 S2      
327LAN2_DISABLE_N   R597  -2          A01X+060261Y+059111X0180Y0200R180 S2      
327P3V3_NODE1       R597  -1          A01X+059946Y+059111X0180Y0200R180 S2      
317GND              VIA   -     D0100PA00X+059648Y+058290               S3      
317GND              VIA   -     D0100PA00X+059621Y+058690               S3      
317GND              VIA   -     D0100PA00X+059090Y+059716               S3      
317LAN2_TEST_EN     VIA   -     D0100PA00X+060540Y+059055               S1      
317LAN2_LED_ACT_N   VIA   -     D0100PA00X+060529Y+058415               S1      
317LAN2_DISABLE_N   VIA   -     D0100PA00X+060529Y+059417               S3      
317P3V3_NODE1       VIA   -     D0100PA00X+059640Y+058985               S3      
317NNAME10962       VIA   -     D0100PA00X+059387Y+059570               S1      
327NNAME11059       C435  -2          A01X+059651Y+061155X0180Y0200R180 S2      
327NNAME10056       C435  -1          A01X+059336Y+061155X0180Y0200R180 S2      
317GND              VIA   -     D0100PA00X+060552Y+060110               S3      
317GND              VIA   -     D0100PA00X+059084Y+060811               S3      
317GND              VIA   -     D0100PA00X+059102Y+060038               S3      
317GND              VIA   -     D0100PA00X+060536Y+060941               S3      
317NNAME10057       VIA   -     D0100PA00X+060231Y+060764               S1      
317NNAME10058       VIA   -     D0100PA00X+060231Y+060264               S1      
317NNAME10963       VIA   -     D0100PA00X+059387Y+060070               S1      
327NNAME11060       C436  -2          A01X+059651Y+061555X0180Y0200R180 S2      
327NNAME10055       C436  -1          A01X+059336Y+061555X0180Y0200R180 S2      
317GND              VIA   -     D0100PA00X+059065Y+061875               S3      
327NNAME11059       VIA   -           A01X+060070Y+061294X0160Y0050R180 S2      
327P1V05_LAN2       VIA   -           A10X+060543Y+062272X0260Y0260R270 S1      
317NNAME11061       VIA   -     D0100PA00X+060501Y+064144               S3      
317UART_TX_P4       VIA   -     D0100PA00X+060098Y+064153               S3      
327GND              R1158 -2          A01X+059192Y+065339X0180Y0200R180 S2      
317GND              VIA   -     D0100PA00X+059473Y+065339               S3      
317NNAME10728       VIA   -     D0100PA00X+059128Y+065622               S1      
317NNAME10727       VIA   -     D0100PA00X+059700Y+065801               S1      
317NNAME10726       VIA   -     D0100PA00X+059184Y+065957               S3      
317CPLD_WDT3        VIA   -     D0100PA00X+059647Y+065523               S3      
327P3V3_NODE1       U66   -24         A10X+059444Y+066908X0140Y0590R270 S1      
327I2C_COM3_SDA     U66   -23         A10X+059444Y+067164X0140Y0590R270 S1      
327I2C_COM3_SCL     U66   -22         A10X+059444Y+067420X0140Y0590R270 S1      
327P3V3_NODE1       C572  -2          A10X+059057Y+066383X0180Y0200     S1      
327N21698959        R750  -1          A10X+060497Y+067516X0180Y0200     S1      
317GND              VIA   -     D0100PA00X+060159Y+066480               S3      
317I2C_COM3_SCL     VIA   -     D0100PA00X+060233Y+067116               S3      
317I2C_COM3_SDA     VIA   -     D0100PA00X+060074Y+066843               S1      
317P3V3_NODE1       VIA   -     D0100PA00X+059314Y+066383               S3      
317N21698959        VIA   -     D0100PA00X+060072Y+067516               S1      
317NNAME10729       VIA   -     D0100PA00X+059730Y+066313               S1      
327N21698959        U66   -21         A10X+059444Y+067676X0140Y0590R270 S1      
327T12_NODE4_EN     U66   -20         A10X+059444Y+067932X0140Y0590R270 S1      
327T12_NODE3_EN     U66   -19         A10X+059444Y+068188X0140Y0590R270 S1      
327T12_NODE2_EN     U66   -18         A10X+059444Y+068444X0140Y0590R270 S1      
327T12_NODE1_EN     U66   -17         A10X+059444Y+068700X0140Y0590R270 S1      
327T11_NODE4_EN     U66   -16         A10X+059444Y+068955X0140Y0590R270 S1      
327T12_NODE4_EN     R749  -1          A10X+060497Y+067916X0180Y0200     S1      
327T12_NODE3_EN     R748  -1          A10X+060497Y+068316X0180Y0200     S1      
327T12_NODE2_EN     R747  -1          A10X+060497Y+068716X0180Y0200     S1      
327T12_NODE1_EN     R746  -1          A10X+060497Y+069116X0180Y0200     S1      
317T12_NODE1_EN     VIA   -     D0100PA00X+060069Y+069190               S1      
317T12_NODE3_EN     VIA   -     D0100PA00X+060073Y+068188               S1      
317T12_NODE4_EN     VIA   -     D0100PA00X+060202Y+067916               S3      
317T12_NODE2_EN     VIA   -     D0100PA00X+060073Y+068688               S1      
327T11_NODE3_EN     U66   -15         A10X+059444Y+069211X0140Y0590R270 S1      
327T11_NODE2_EN     U66   -14         A10X+059444Y+069467X0140Y0590R270 S1      
327T11_NODE1_EN     U66   -13         A10X+059444Y+069723X0140Y0590R270 S1      
327T11_NODE4_EN     R745  -1          A10X+060497Y+069516X0180Y0200     S1      
317T11_NODE4_EN     VIA   -     D0100PA00X+060422Y+070377               S1      
317NNAME11007       VIA   -     D0100PA00X+060065Y+070784               S3      
317NNAME11022       VIA   -     D0100PA00X+059296Y+070329               S1      
317GND              VIA   -     D0100PA00X+059244Y+072377               S3      
317GND              VIA   -     D0100PA00X+059686Y+072342               S3      
317T11_NODE3_EN     VIA   -     D0100PA00X+060186Y+071148               S1      
317T11_NODE2_EN     VIA   -     D0100PA00X+060615Y+071315               S3      
317T11_NODE4_EN     VIA   -     D0100PA00X+060181Y+071558               S3      
317NNAME11011       VIA   -     D0100PA00X+059888Y+071923               S3      
317NNAME11008       VIA   -     D0100PA00X+059595Y+070900               S1      
317NNAME11012       VIA   -     D0100PA00X+059417Y+071929               S1      
327GND              C744  -2          A01X+059694Y+072758X0180Y0200R090 S2      
327NNAME11011       C744  -1          A01X+059694Y+073073X0180Y0200R090 S2      
327GND              C666  -2          A01X+060144Y+073908X0180Y0200R090 S2      
327GND              C663  -2          A01X+060594Y+073908X0180Y0200R090 S2      
327GND              C654  -2          A10X+060144Y+073808X0180Y0200R270 S1      
327GND              C651  -2          A10X+060594Y+073808X0180Y0200R270 S1      
327GND              C657  -2          A10X+059694Y+073808X0180Y0200R270 S1      
327GND              C720  -2          A10X+059244Y+072658X0180Y0200R270 S1      
327NNAME11007       C720  -1          A10X+059244Y+072973X0180Y0200R270 S1      
327GND              C747  -2          A01X+059244Y+073908X0180Y0200R090 S2      
327NNAME11007       R957  -1          A10X+059244Y+073808X0180Y0200R090 S1      
327NNAME11049       R984  -2          A01X+059244Y+073073X0180Y0200R270 S2      
327NNAME11012       R984  -1          A01X+059244Y+072758X0180Y0200R270 S2      
327T11_NODE4_EN_R   R894  -2          A10X+059694Y+072973X0180Y0200R090 S1      
327T11_NODE4_EN     R894  -1          A10X+059694Y+072658X0180Y0200R090 S1      
327T12_NODE3_EN_R   R903  -2          A01X+060144Y+073073X0180Y0200R270 S2      
327T12_NODE3_EN     R903  -1          A01X+060144Y+072758X0180Y0200R270 S2      
327T12_NODE2_EN_R   R900  -2          A01X+060594Y+073073X0180Y0200R270 S2      
327T12_NODE2_EN     R900  -1          A01X+060594Y+072758X0180Y0200R270 S2      
327T11_NODE3_EN_R   R891  -2          A10X+060144Y+072973X0180Y0200R090 S1      
327T11_NODE3_EN     R891  -1          A10X+060144Y+072658X0180Y0200R090 S1      
327T11_NODE2_EN_R   R888  -2          A10X+060594Y+072973X0180Y0200R090 S1      
327T11_NODE2_EN     R888  -1          A10X+060594Y+072658X0180Y0200R090 S1      
327NNAME11011       R981  -1          A01X+059694Y+073908X0180Y0200R270 S2      
317GND              VIA   -     D0100PA00X+060144Y+073568               S3      
317GND              VIA   -     D0100PA00X+060594Y+073567               S3      
317GND              VIA   -     D0100PA00X+059694Y+073568               S3      
317GND              VIA   -     D0100PA00X+059300Y+073566               S3      
327T12_NODE3_EN_R   C666  -1          A01X+060144Y+074223X0180Y0200R090 S2      
327T12_NODE2_EN_R   C663  -1          A01X+060594Y+074223X0180Y0200R090 S2      
327T11_NODE3_EN_R   C654  -1          A10X+060144Y+074123X0180Y0200R270 S1      
327T11_NODE2_EN_R   C651  -1          A10X+060594Y+074123X0180Y0200R270 S1      
327T11_NODE4_EN_R   C657  -1          A10X+059694Y+074123X0180Y0200R270 S1      
327NNAME11049       C747  -1          A01X+059244Y+074223X0180Y0200R090 S2      
327NNAME11030       R957  -2          A10X+059244Y+074123X0180Y0200R090 S1      
327NNAME11050       R981  -2          A01X+059694Y+074223X0180Y0200R270 S2      
317T12_NODE4_EN_R   VIA   -     D0100PA00X+060394Y+075362               S1      
327I2C_PSU3_R_SDA   VIA   -           A10X+060242Y+077847X0260Y0260     S1      
327T11_NODE2_EN_R   VIA   -           A10X+059146Y+078010X0260Y0260     S1      
327T11_NODE1_EN_R   VIA   -           A10X+059659Y+078620X0260Y0260     S1      
317T12_NODE3_EN_R   VIA   -     D0100PA00X+060627Y+077462               S1      
317NNAME11050       VIA   -     D0100PA00X+059753Y+078019               S1      
317NNAME11049       VIA   -     D0100PA00X+059248Y+077151               S1      
327T11_NODE1_EN_R   J18   -A35        A10X+059455Y+080787X0300Y1660R180 S1      
327GND              J18   -A34        A10X+059849Y+080787X0300Y1660R180 S1      
327I2C_PSU3_R_SDA   J18   -A33        A10X+060242Y+080787X0300Y1660R180 S1      
327I2C_PSU3_R_SCL   J18   -A32        A10X+060636Y+080787X0300Y1660R180 S1      
327GND              J18   -B35        A01X+059455Y+080787X0300Y1660R180 S2      
327T12_NODE4_EN_R   J18   -B34        A01X+059849Y+080787X0300Y1660R180 S2      
327T12_NODE3_EN_R   J18   -B33        A01X+060242Y+080787X0300Y1660R180 S2      
327T12_NODE2_EN_R   J18   -B32        A01X+060636Y+080787X0300Y1660R180 S2      
317GND              VIA   -     D0100PA00X+059849Y+079148               S3      
317GND              VIA   -     D0100PA00X+059455Y+079148               S3      
317GND              J26   -2    D0460PA00X+061737Y+002880               S0      
317JTAG_CPLD2_TCK   J26   -1    D0460PA00X+061737Y+003880               S0      
317GND              J5    -4    D0360PA00X+061566Y+006917               S0      
317UART_RX_P3       J5    -3    D0360PA00X+061566Y+007704               S0      
317UART_TX_P3       J5    -2    D0360PA00X+061566Y+008492               S0      
317P3V3_NODE1       J5    -1    D0360PA00X+061566Y+009279               S0      
327N21624866        C534  -2          A01X+061054Y+010473X0180Y0200     S2      
327N21624861        C534  -1          A01X+061369Y+010473X0180Y0200     S2      
327GND              C532  -1          A01X+061862Y+010470X0180Y0200R180 S2      
327N21624850        C533  -2          A01X+060619Y+010473X0180Y0200R180 S2      
317GND              VIA   -     D0100PA00X+061862Y+010892               S3      
317N21624866        VIA   -     D0100PA00X+061054Y+010768               S1      
327UART_RX_P1_L     U51   -4          A01X+062312Y+012278X0140Y0590R090 S2      
327N21624894        U51   -3          A01X+062312Y+012022X0140Y0590R090 S2      
327N21624866        U51   -2          A01X+062312Y+011766X0140Y0590R090 S2      
327N21624861        U51   -1          A01X+062312Y+011510X0140Y0590R090 S2      
317N21624861        VIA   -     D0100PA00X+061793Y+011406               S1      
327UART_TX_P1_L     U51   -10         A01X+062312Y+013813X0140Y0590R090 S2      
327NNAME10113       U51   -9          A01X+062312Y+013557X0140Y0590R090 S2      
327N37284163        U51   -8          A01X+062312Y+013301X0140Y0590R090 S2      
327N37284163        U51   -7          A01X+062312Y+013045X0140Y0590R090 S2      
327NNAME10051       U51   -6          A01X+062312Y+012789X0140Y0590R090 S2      
327NNAME10075       U51   -5          A01X+062312Y+012533X0140Y0590R090 S2      
327UART_RTS_P1_N    U51   -14         A01X+062312Y+014837X0140Y0590R090 S2      
327UART_TX_P1       U51   -13         A01X+062312Y+014581X0140Y0590R090 S2      
327UART_DTR_P1_N    U51   -12         A01X+062312Y+014325X0140Y0590R090 S2      
327NNAME10074       U51   -11         A01X+062312Y+014069X0140Y0590R090 S2      
317UART_RTS_P1_N    VIA   -     D0100PA00X+061343Y+015353               S1      
317SATA_TX0_C_DN    J7    -3    D0260PA00X+061170Y+018569               S0      
317SATA_TX0_C_DP    J7    -2    D0260PA00X+061170Y+017900               S0      
317SATA_RX0_C_DP    J7    -6    D0260PA00X+061170Y+020069               S0      
317SATA_RX0_C_DN    J7    -5    D0260PA00X+061170Y+019400               S0      
317GND              J7    -9    D0560PA00X+060973Y+021567               S0      
327GND              C355  -2          A10X+060874Y+024282X0180Y0200R270 S1      
327NNAME11034       C355  -1          A10X+060874Y+024597X0180Y0200R270 S1      
327NNAME11034       L32   -2          A10X+061284Y+024597X0180Y0200R090 S1      
327P1V8_NODE1       L32   -1          A10X+061284Y+024282X0180Y0200R090 S1      
317GND              VIA   -     D0100PA00X+060827Y+024980               S3      
317GND              VIA   -     D0100PA00X+060877Y+024000               S3      
317TP_SATA_NODE1    VIA   -     D0100PA00X+061042Y+023744               S1      
327NNAME11034       VIA   -           A10X+061747Y+024650X0260Y0260     S1      
317P1V8_NODE1       VIA   -     D0100PA00X+061778Y+023887               S1      
327NNAME11039       C489  -2          A01X+061007Y+026180X0180Y0200     S2      
327SATA_TX0_C_DP    C489  -1          A01X+061322Y+026180X0180Y0200     S2      
327NNAME11040       C490  -2          A01X+061007Y+025780X0180Y0200     S2      
327SATA_TX0_C_DN    C490  -1          A01X+061322Y+025780X0180Y0200     S2      
327GND              C343  -2          A10X+060874Y+025422X0180Y0200R270 S1      
327NNAME11041       C343  -1          A10X+060874Y+025737X0180Y0200R270 S1      
327GND              C359  -2          A10X+060864Y+026627X0180Y0200R090 S1      
327NNAME11038       C359  -1          A10X+060864Y+026312X0180Y0200R090 S1      
327NNAME11038       L33   -2          A10X+061277Y+026312X0180Y0200R270 S1      
327P1V8_NODE1       L33   -1          A10X+061277Y+026627X0180Y0200R270 S1      
327NNAME11041       L30   -2          A10X+061284Y+025737X0180Y0200R090 S1      
327P1V8_NODE1       L30   -1          A10X+061284Y+025422X0180Y0200R090 S1      
327NNAME11041       VIA   -           A10X+061727Y+025760X0260Y0260     S1      
327NNAME11038       VIA   -           A10X+061737Y+026270X0260Y0260     S1      
327NNAME11040       VIA   -           A01X+060589Y+025879X0160Y0042     S2      
317GND              VIA   -     D0100PA00X+060827Y+026880               S3      
317P1V8_NODE1       VIA   -     D0100PA00X+061297Y+026910               S3      
327P1V0_ADJ_S       J28   -2          A01X+062037Y+029263X0180Y0200R090 S2      
327P1V0_NODE1       J28   -1          A01X+062037Y+029578X0200Y0400     S2      
317P1V0_NODE1       VIA   -     D0100PA00X+060915Y+032851               S3      
317P1V0_NODE1       VIA   -     D0100PA00X+061649Y+032753               S3      
327GND              U33   -4          A01X+061364Y+033982X0220Y0680R270 S2      
327NNAME11051       U33   -3          A01X+061364Y+034482X0220Y0680R270 S2      
317GND              VIA   -     D0100PA00X+061364Y+033699               S1      
317NNAME11051       VIA   -     D0100PA00X+060767Y+034482               S1      
317P1V0_NODE1       VIA   -     D0100PA00X+061919Y+033699               S3      
327NNAME11053       U33   -2          A01X+061364Y+034982X0220Y0680R270 S2      
327NNAME11062       U33   -1          A01X+061364Y+035482X0220Y0680R270 S2      
317P3V3_NODE1       VIA   -     D0100PA00X+060831Y+035997               S3      
317NNAME11052       VIA   -     D0100PA00X+061185Y+035978               S1      
317NNAME11053       VIA   -     D0100PA00X+060786Y+035234               S1      
317NNAME11062       VIA   -     D0100PA00X+061858Y+035482               S1      
317P3V3_NODE1       VIA   -     D0100PA00X+061759Y+036254               S3      
317P3V3_NODE1       VIA   -     D0100PA00X+062024Y+036437               S1      
317NNAME10966       VIA   -     D0100PA00X+060908Y+038856               S1      
327NNAME10936       C363  -1          A01X+061885Y+040205X0180Y0200R180 S2      
327NNAME10903       C364  -1          A01X+061885Y+039805X0180Y0200R180 S2      
327NNAME10269       R520  -1          A01X+061199Y+040785X0180Y0200R270 S2      
327P3V3_NODE1       R534  -1          A01X+061593Y+040785X0180Y0200R270 S2      
317GND              VIA   -     D0100PA00X+060887Y+039696               S3      
317GND              VIA   -     D0100PA00X+060882Y+040345               S3      
317P3V3_NODE1       VIA   -     D0100PA00X+061901Y+040835               S3      
317NNAME10934       VIA   -     D0100PA00X+060908Y+039356               S1      
317NNAME10903       VIA   -     D0100PA00X+061264Y+039748               S1      
317NNAME10936       VIA   -     D0100PA00X+061264Y+040248               S1      
327USB_WAKE_N       R520  -2          A01X+061199Y+041100X0180Y0200R270 S2      
327USB_WAKE_N       R534  -2          A01X+061593Y+041100X0180Y0200R270 S2      
327N34379705        R273  -2          A01X+061434Y+041882X0180Y0200R270 S2      
327NNAME10904       R273  -1          A01X+061434Y+041567X0180Y0200R270 S2      
327N34379705        R274  -2          A01X+061837Y+041883X0180Y0200R270 S2      
327NNAME11063       R274  -1          A01X+061837Y+041568X0180Y0200R270 S2      
317NNAME11063       VIA   -     D0100PA00X+061105Y+042309               S1      
317P3V3_NODE1       VIA   -     D0100PA00X+062140Y+042040               S3      
317NNAME10904       VIA   -     D0100PA00X+061113Y+041793               S3      
317N34379705        VIA   -     D0100PA00X+061626Y+042221               S1      
317NNAME10492       VIA   -     D0100PA00X+061058Y+044866               S1      
317NNAME10061       VIA   -     D0100PA00X+060937Y+045297               S3      
317NNAME10044       VIA   -     D0100PA00X+061001Y+045658               S1      
317NNAME10034       VIA   -     D0100PA00X+061798Y+046041               S1      
327GND              S3    -4          A01X+062220Y+050124X0400Y1260R090 S2      
327RST_BTN_L        S3    -2          A01X+062220Y+051699X0400Y1260R090 S2      
327GND              C802  -2          A01X+061787Y+052697X0440Y0540R180 S2      
327NNAME11056       C802  -1          A01X+061039Y+052697X0440Y0540R180 S2      
327GND              U58   -3          A01X+060930Y+053452X0180Y0520R270 S2      
327NNAME11055       U58   -4          A01X+061895Y+053452X0180Y0520R270 S2      
317GND              VIA   -     D0100PA00X+062176Y+052697               S1      
317GND              VIA   -     D0100PA00X+060930Y+053164               S3      
327GND              C565  -2          A01X+061683Y+054676X0180Y0200     S2      
327P3V3_STB_NODE1   C565  -1          A01X+061998Y+054676X0180Y0200     S2      
327N/C              U58   -1          A01X+060930Y+054200X0180Y0520R270 S2      
327NNAME11056       U58   -2          A01X+060930Y+053826X0180Y0520R270 S2      
327P3V3_STB_NODE1   U58   -5          A01X+061895Y+054200X0180Y0520R270 S2      
317GND              VIA   -     D0100PA00X+061354Y+054676               S3      
317NNAME11056       VIA   -     D0100PA00X+061347Y+053750               S1      
317TACKOVER_EN_N    VIA   -     D0100PA00X+061632Y+053707               S3      
327PU_LAN2_TMS      R568  -2          A01X+061294Y+056432X0180Y0200R270 S2      
327P3V3_NODE1       R568  -1          A01X+061294Y+056117X0180Y0200R270 S2      
327LAN2_AUX_PWR     R571  -2          A01X+061744Y+056432X0180Y0200R270 S2      
327P3V3_NODE1       R571  -1          A01X+061744Y+056117X0180Y0200R270 S2      
327SMB_LAN2_DAT     R592  -2          A01X+060844Y+056412X0180Y0200R270 S2      
327SMB_PCH_SDA      R592  -1          A01X+060844Y+056097X0180Y0200R270 S2      
317GND              VIA   -     D0100PA00X+060917Y+055485               S3      
317SMB_PCH_SDA      VIA   -     D0100PA00X+061007Y+055759               S1      
317P3V3_NODE1       VIA   -     D0100PA00X+062194Y+055828               S3      
317P3V3_NODE1       VIA   -     D0100PA00X+062184Y+055504               S3      
317P3V3_NODE1       VIA   -     D0100PA00X+060906Y+055210               S3      
317GND              VIA   -     D0100PA00X+060708Y+056692               S3      
317SMB_LAN2_DAT     VIA   -     D0100PA00X+061082Y+056649               S1      
317PU_LAN2_TDI      VIA   -     D0100PA00X+062194Y+056714               S1      
317NNAME11057       VIA   -     D0100PA00X+060903Y+057913               S1      
317NNAME11058       VIA   -     D0100PA00X+061727Y+058044               S1      
327P3V3_NODE1       U37   -32         A01X+061602Y+058798X0100Y0360R270 S2      
327NNAME11057       U37   -31         A01X+061602Y+058995X0100Y0360R270 S2      
327LAN2_LED_ACT_N   U37   -30         A01X+061602Y+059192X0100Y0360R270 S2      
327LAN2_TEST_EN     U37   -29         A01X+061602Y+059389X0100Y0360R270 S2      
327LAN2_DISABLE_N   U37   -28         A01X+061602Y+059586X0100Y0360R270 S2      
327SMB_LAN2_CLK     U37   -34         A01X+062114Y+058483X0100Y0360     S2      
327NNAME11058       U37   -33         A01X+061917Y+058483X0100Y0360     S2      
327GND              C442  -2          A10X+061901Y+058965X0180Y0200     S1      
327P3V3_NODE1       C442  -1          A10X+061586Y+058965X0180Y0200     S1      
327GND              C444  -2          A10X+061905Y+058554X0180Y0200     S1      
327P3V3_NODE1       C444  -1          A10X+061590Y+058554X0180Y0200     S1      
317P1V05_LAN2       VIA   -     D0100PA00X+061152Y+059659               S1      
317P3V3_NODE1       VIA   -     D0100PA00X+061227Y+058654               S3      
327P1V05_LAN2       U37   -27         A01X+061602Y+059782X0100Y0360R270 S2      
327NNAME10962       U37   -26         A01X+061602Y+059979X0100Y0360R270 S2      
327NNAME10963       U37   -25         A01X+061602Y+060176X0100Y0360R270 S2      
327NNAME10058       U37   -24         A01X+061602Y+060373X0100Y0360R270 S2      
327NNAME10057       U37   -23         A01X+061602Y+060570X0100Y0360R270 S2      
327P1V9_LAN2        U37   -22         A01X+061602Y+060767X0100Y0360R270 S2      
327NNAME11059       U37   -21         A01X+061602Y+060964X0100Y0360R270 S2      
327NNAME11060       U37   -20         A01X+061602Y+061160X0100Y0360R270 S2      
327GND              C464  -2          A10X+061905Y+059794X0180Y0200     S1      
327P1V05_LAN2       C464  -1          A10X+061590Y+059794X0180Y0200     S1      
327GND              C470  -2          A10X+061901Y+060885X0180Y0200     S1      
327P1V9_LAN2        C470  -1          A10X+061586Y+060885X0180Y0200     S1      
327NNAME11060       VIA   -           A01X+061080Y+061122X0160Y0050R180 S2      
317P1V9_LAN2        VIA   -     D0100PA00X+061249Y+060767               S3      
327P1V9_LAN2        U37   -19         A01X+061602Y+061357X0100Y0360R270 S2      
327P1V05_LAN2       U37   -18         A01X+061602Y+061554X0100Y0360R270 S2      
327PLT_RST_LAN2_N   U37   -17         A01X+061602Y+061751X0100Y0360R270 S2      
327NNAME10269       U37   -16         A01X+061917Y+062066X0100Y0360R180 S2      
327NNAME11061       U37   -15         A01X+062114Y+062066X0100Y0360R180 S2      
327GND              C466  -2          A10X+061905Y+061794X0180Y0200     S1      
327P1V05_LAN2       C466  -1          A10X+061590Y+061794X0180Y0200     S1      
327GND              C469  -2          A10X+061901Y+061375X0180Y0200     S1      
327P1V9_LAN2        C469  -1          A10X+061586Y+061375X0180Y0200     S1      
317P1V05_LAN2       VIA   -     D0100PA00X+061125Y+061794               S1      
317P1V9_LAN2        VIA   -     D0100PA00X+061237Y+061414               S3      
317NNAME10269       VIA   -     D0100PA00X+061569Y+062554               S1      
327PLT_RST_LAN2_N   R590  -2          A01X+061125Y+063313X0180Y0200R090 S2      
327NNAME10319       R590  -1          A01X+061125Y+063628X0180Y0200R090 S2      
327NNAME11061       R572  -2          A01X+061930Y+063307X0180Y0200R090 S2      
327P3V3_NODE1       R572  -1          A01X+061930Y+063622X0180Y0200R090 S2      
317GND              VIA   -     D0100PA00X+061458Y+064507               S3      
317NNAME11061       VIA   -     D0100PA00X+061673Y+063329               S1      
317NNAME11064       VIA   -     D0100PA00X+060831Y+064160               S3      
317PLT_RST_LAN2_N   VIA   -     D0100PA00X+061157Y+062989               S1      
317UART_RTS_P4_N    VIA   -     D0100PA00X+062051Y+063943               S3      
317P3V3_NODE1       VIA   -     D0100PA00X+061647Y+063622               S3      
327GND              U38   -4          A01X+062013Y+064507X0220Y0680R270 S2      
327LAN2_NVM_WP_N    U38   -3          A01X+062013Y+065007X0220Y0680R270 S2      
327LAN2_NVM_SO_R    U38   -2          A01X+062013Y+065507X0220Y0680R270 S2      
327NNAME11065       U38   -1          A01X+062013Y+066007X0220Y0680R270 S2      
327LAN2_NVM_SO_R    R579  -2          A01X+061004Y+065557X0180Y0200R180 S2      
327NNAME11064       R579  -1          A01X+060689Y+065557X0180Y0200R180 S2      
327P3V3_NODE1       R585  -2          A01X+060689Y+065057X0180Y0200     S2      
327LAN2_NVM_WP_N    R585  -1          A01X+061004Y+065057X0180Y0200     S2      
327NNAME11065       R573  -2          A01X+061004Y+066057X0180Y0200R180 S2      
327NNAME11061       R573  -1          A01X+060689Y+066057X0180Y0200R180 S2      
327NNAME11066       U142  -S          A10X+061920Y+065197X0400Y0500     S1      
317LAN2_NVM_WP_N    VIA   -     D0100PA00X+061380Y+064871               S1      
317LAN2_NVM_SO_R    VIA   -     D0100PA00X+061295Y+065614               S1      
317P3V3_NODE1       VIA   -     D0100PA00X+060762Y+064717               S3      
317TACKOVER_EN      VIA   -     D0100PA00X+061570Y+065776               S3      
327N54365623        C914  -2          A01X+061806Y+067518X0180Y0200R180 S2      
327GND              C914  -1          A01X+061491Y+067518X0180Y0200R180 S2      
327N54365829        C915  -2          A10X+060935Y+066994X0180Y0200R090 S1      
327N54365827        C915  -1          A10X+060935Y+066679X0180Y0200R090 S1      
327GND              R750  -2          A10X+060812Y+067516X0180Y0200     S1      
317GND              VIA   -     D0100PA00X+061065Y+067516               S3      
317GND              VIA   -     D0100PA00X+061491Y+067194               S3      
317NNAME11065       VIA   -     D0100PA00X+061320Y+066158               S1      
317N54365623        VIA   -     D0100PA00X+062016Y+067059               S1      
317N54365601        VIA   -     D0100PA00X+061594Y+066686               S1      
327N54365829        VIA   -           A10X+061603Y+067515X0260Y0260     S1      
327N54365603        C912  -2          A01X+060729Y+068140X0180Y0200R270 S2      
327N54365601        C912  -1          A01X+060729Y+067825X0180Y0200R270 S2      
327GND              C913  -2          A01X+061724Y+068270X0180Y0200R270 S2      
327P3V3_NODE1       C913  -1          A01X+061724Y+067955X0180Y0200R270 S2      
327N54365837        C917  -2          A10X+061724Y+068272X0180Y0200R270 S1      
327GND              C917  -1          A10X+061724Y+068587X0180Y0200R270 S1      
327N54365554        R1305 -2          A01X+060697Y+068880X0180Y0200R090 S2      
327P3V3_NODE1       R1305 -1          A01X+060697Y+069195X0180Y0200R090 S2      
327N54365556        R1304 -2          A01X+061388Y+069167X0180Y0200R090 S2      
327P5V_NODE1        R749  -2          A10X+060812Y+067916X0180Y0200     S1      
327P5V_NODE1        R748  -2          A10X+060812Y+068316X0180Y0200     S1      
327P5V_NODE1        R747  -2          A10X+060812Y+068716X0180Y0200     S1      
327P5V_NODE1        R746  -2          A10X+060812Y+069116X0180Y0200     S1      
317GND              VIA   -     D0100PA00X+061724Y+068904               S3      
317P3V3_NODE1       VIA   -     D0100PA00X+061069Y+067933               S3      
317P5V_NODE1        VIA   -     D0100PA00X+061057Y+069116               S3      
317P5V_NODE1        VIA   -     D0100PA00X+061055Y+068664               S3      
317P5V_NODE1        VIA   -     D0100PA00X+061081Y+068393               S3      
317N54365603        VIA   -     D0100PA00X+061267Y+068144               S1      
327N54365837        VIA   -           A10X+062018Y+067832X0260Y0260     S1      
317N54365554        VIA   -     D0100PA00X+061281Y+068842               S1      
327P3V3_NODE1       R1304 -1          A01X+061388Y+069482X0180Y0200R090 S2      
327N54365764        R1306 -2          A10X+061309Y+069740X0180Y0200R180 S1      
327GND              R1306 -1          A10X+061624Y+069740X0180Y0200R180 S1      
327NNAME11023       R1167 -2          A01X+061417Y+070508X0180Y0200R270 S2      
327NNAME11067       R1167 -1          A01X+061417Y+070193X0180Y0200R270 S2      
327GND              R1168 -2          A01X+061017Y+070508X0180Y0200R270 S2      
327NNAME11023       R1168 -1          A01X+061017Y+070193X0180Y0200R270 S2      
327P5V_NODE1        R745  -2          A10X+060812Y+069516X0180Y0200     S1      
317GND              VIA   -     D0100PA00X+062141Y+069694               S3      
317GND              VIA   -     D0100PA00X+060702Y+070464               S3      
317I2C_COM3_SCL     VIA   -     D0100PA00X+060898Y+070809               S3      
317I2C_COM3_SDA     VIA   -     D0100PA00X+061291Y+070763               S3      
317P3V3_NODE1       VIA   -     D0100PA00X+061054Y+069796               S3      
317P3V3_NODE1       VIA   -     D0100PA00X+061802Y+070000               S3      
317P5V_NODE1        VIA   -     D0100PA00X+061057Y+069516               S3      
317NNAME11023       VIA   -     D0100PA00X+060738Y+069967               S1      
317NNAME11067       VIA   -     D0100PA00X+061793Y+070352               S1      
327N54365764        VIA   -           A10X+061551Y+069278X0260Y0260     S1      
317N54365556        VIA   -     D0100PA00X+062048Y+069383               S1      
317GND              VIA   -     D0100PA00X+061124Y+070983               S3      
317GND              VIA   -     D0100PA00X+062125Y+071379               S3      
317GND              VIA   -     D0100PA00X+061709Y+070917               S3      
317FAN3_TACH        VIA   -     D0100PA00X+060907Y+072192               S1      
317FAN2_TACH        VIA   -     D0100PA00X+061607Y+072084               S3      
317I2C_PSU3_SCL     VIA   -     D0100PA00X+061373Y+071766               S1      
317FAN1_TACH        VIA   -     D0100PA00X+062067Y+072222               S1      
327T11_NODE1_EN     VIA   -           A10X+060694Y+071669X0260Y0260     S1      
317NNAME10729       VIA   -     D0100PA00X+062083Y+071752               S3      
317NNAME10726       VIA   -     D0100PA00X+060984Y+071362               S3      
327NNAME11068       VIA   -           A10X+061827Y+071334X0260Y0260     S1      
327GND              C597  -2          A10X+061944Y+073808X0180Y0200R270 S1      
327GND              C595  -2          A10X+061494Y+073808X0180Y0200R270 S1      
327GND              C660  -2          A01X+061044Y+073908X0180Y0200R090 S2      
327GND              C648  -2          A10X+061044Y+073808X0180Y0200R270 S1      
327GND              R1221 -2          A01X+061494Y+073908X0180Y0200R090 S2      
327GND              R1220 -2          A01X+061944Y+073908X0180Y0200R090 S2      
327FAN3_TACH_R      R825  -2          A01X+061494Y+073073X0180Y0200R270 S2      
327FAN3_TACH        R825  -1          A01X+061494Y+072758X0180Y0200R270 S2      
327FAN2_TACH_R      R823  -2          A01X+061944Y+073073X0180Y0200R270 S2      
327FAN2_TACH        R823  -1          A01X+061944Y+072758X0180Y0200R270 S2      
327I2C_PSU3_R_SCL   R828  -2          A10X+061944Y+072973X0180Y0200R090 S1      
327I2C_PSU3_SCL     R828  -1          A10X+061944Y+072658X0180Y0200R090 S1      
327I2C_PSU3_R_SDA   R826  -2          A10X+061494Y+072973X0180Y0200R090 S1      
327I2C_PSU3_SDA     R826  -1          A10X+061494Y+072658X0180Y0200R090 S1      
327T12_NODE1_EN_R   R897  -2          A01X+061044Y+073073X0180Y0200R270 S2      
327T12_NODE1_EN     R897  -1          A01X+061044Y+072758X0180Y0200R270 S2      
327T11_NODE1_EN_R   R885  -2          A10X+061044Y+072973X0180Y0200R090 S1      
327T11_NODE1_EN     R885  -1          A10X+061044Y+072658X0180Y0200R090 S1      
317GND              VIA   -     D0100PA00X+061959Y+073538               S3      
317GND              VIA   -     D0100PA00X+061473Y+073552               S3      
317GND              VIA   -     D0100PA00X+060879Y+073578               S3      
327I2C_PSU3_R_SCL   C597  -1          A10X+061944Y+074123X0180Y0200R270 S1      
327I2C_PSU3_R_SDA   C595  -1          A10X+061494Y+074123X0180Y0200R270 S1      
327T12_NODE1_EN_R   C660  -1          A01X+061044Y+074223X0180Y0200R090 S2      
327T11_NODE1_EN_R   C648  -1          A10X+061044Y+074123X0180Y0200R270 S1      
327FAN3_TACH_R      R1221 -1          A01X+061494Y+074223X0180Y0200R090 S2      
327FAN2_TACH_R      R1220 -1          A01X+061944Y+074223X0180Y0200R090 S2      
317FAN2_TACH_R      VIA   -     D0100PA00X+061908Y+077261               S1      
317FAN3_TACH_R      VIA   -     D0100PA00X+061903Y+077868               S1      
327FAN6_TACH_R      VIA   -           A10X+062203Y+078605X0260Y0260     S1      
327I2C_PSU3_R_SCL   VIA   -           A10X+060636Y+078539X0260Y0260     S1      
317T12_NODE1_EN_R   VIA   -     D0100PA00X+061226Y+078311               S1      
317T12_NODE2_EN_R   VIA   -     D0100PA00X+060935Y+077862               S1      
327GND              J18   -A31        A10X+061030Y+080787X0300Y1660R180 S1      
327FAN_PWM_R        J18   -A30        A10X+061424Y+080787X0300Y1660R180 S1      
327GND              J18   -A29        A10X+061817Y+080787X0300Y1660R180 S1      
327FAN6_TACH_R      J18   -A28        A10X+062211Y+080787X0300Y1660R180 S1      
327T12_NODE1_EN_R   J18   -B31        A01X+061030Y+080590X0300Y1260R180 S2      
327GND              J18   -B30        A01X+061424Y+080787X0300Y1660R180 S2      
327FAN3_TACH_R      J18   -B29        A01X+061817Y+080787X0300Y1660R180 S2      
327FAN2_TACH_R      J18   -B28        A01X+062211Y+080787X0300Y1660R180 S2      
317GND              VIA   -     D0100PA00X+061817Y+079148               S3      
317GND              VIA   -     D0100PA00X+061424Y+079148               S3      
317GND              VIA   -     D0100PA00X+061030Y+079148               S3      
317GND              J27   -10   D0460PA00X+063996Y+002880               S0      
317JTAG_CPLD3_TDI   J27   -9    D0460PA00X+063996Y+003880               S0      
317P3V3_NODE1       VIA   -     D0100PA00X+062638Y+008512               S3      
317P3V3_NODE1       VIA   -     D0100PA00X+062402Y+008324               S3      
317P3V3_NODE1       VIA   -     D0100PA00X+062375Y+008713               S3      
317P3V3_NODE1       VIA   -     D0100PA00X+062638Y+008852               S3      
317P3V3_NODE1       VIA   -     D0100PA00X+062373Y+009042               S3      
317P3V3_NODE1       VIA   -     D0100PA00X+062618Y+009192               S3      
317P3V3_NODE1       VIA   -     D0100PA00X+062382Y+009365               S3      
327N21624894        C532  -2          A01X+062177Y+010470X0180Y0200R180 S2      
317P3V3_NODE1       VIA   -     D0100PA00X+062632Y+009608               S3      
317P3V3_NODE1       VIA   -     D0100PA00X+062361Y+009713               S3      
317P3V3_NODE1       VIA   -     D0100PA00X+062618Y+009928               S3      
317N21624894        VIA   -     D0100PA00X+062884Y+012022               S1      
327N37284163        R656  -2          A01X+063307Y+013224X0180Y0200     S2      
327GND              R656  -1          A01X+063622Y+013224X0180Y0200     S2      
317N37284163        VIA   -     D0100PA00X+062874Y+013301               S1      
317SATA_TX0_C_DN    VIA   -     D0100PA00X+062480Y+018495               S1      
317SATA_TX0_C_DP    VIA   -     D0100PA00X+062480Y+017995               S1      
317GND              VIA   -     D0100PA00X+062436Y+017609               S3      
327NNAME11042       C494  -2          A10X+063072Y+019531X0180Y0200     S1      
327SATA_RX0_C_DN    C494  -1          A10X+062757Y+019531X0180Y0200     S1      
327NNAME11043       C492  -2          A10X+063072Y+019931X0180Y0200     S1      
327SATA_RX0_C_DP    C492  -1          A10X+062757Y+019931X0180Y0200     S1      
327SATA_RX0_C_DP    VIA   -           A10X+062330Y+020014X0260Y0260     S1      
327SATA_RX0_C_DN    VIA   -           A10X+062330Y+019454X0260Y0260     S1      
317GND              VIA   -     D0100PA00X+063248Y+019278               S3      
317GND              VIA   -     D0100PA00X+062495Y+018980               S3      
317GND              VIA   -     D0100PA00X+063249Y+020208               S3      
317NNAME11043       VIA   -     D0100PA00X+063496Y+020012               S1      
317NNAME11042       VIA   -     D0100PA00X+063496Y+019512               S1      
317P1V8_NODE1       VIA   -     D0100PA00X+062247Y+026163               S3      
317NNAME10949       VIA   -     D0100PA00X+063500Y+026540               S3      
317NNAME11069       VIA   -     D0100PA00X+063421Y+028167               S1      
327NNAME11069       C884  -2          A01X+063419Y+028909X0180Y0200     S2      
327GND              C884  -1          A01X+063734Y+028909X0180Y0200     S2      
327P1V0_ADJ_S       C851  -2          A01X+062698Y+029259X0180Y0200     S2      
327P1V0_ADJ         C851  -1          A01X+063013Y+029259X0180Y0200     S2      
327NNAME11069       R1218 -2          A01X+063421Y+028504X0180Y0200     S2      
327P3V3_STB_NODE1   R1218 -1          A01X+063736Y+028504X0180Y0200     S2      
327P1V0_ADJ         PR10  -2          A01X+063013Y+029653X0180Y0200R180 S2      
327GND              PR10  -1          A01X+062698Y+029653X0180Y0200R180 S2      
327P1V0_ADJ_S       PR9   -2          A01X+062698Y+028847X0180Y0200     S2      
327P1V0_ADJ         PR9   -1          A01X+063013Y+028847X0180Y0200     S2      
317GND              VIA   -     D0100PA00X+062410Y+029653               S3      
317P1V0_ADJ_S       VIA   -     D0100PA00X+062438Y+029259               S1      
327GND              PC29  -2          A01X+062737Y+030056X0180Y0200R090 S2      
327P1V0_NODE1       PC29  -1          A01X+062737Y+030371X0180Y0200R090 S2      
327NNAME11069       U130  -5          A01X+063635Y+030064X0110Y0360R090 S2      
327P1V0_NODE1       U130  -1          A01X+063635Y+030852X0110Y0360R270 S2      
327P1V0_ADJ         U130  -4          A01X+063635Y+030261X0110Y0360R270 S2      
327P1V0_NODE1       U130  -3          A01X+063635Y+030458X0110Y0360R270 S2      
327P1V0_NODE1       U130  -2          A01X+063635Y+030655X0110Y0360R270 S2      
317P1V0_ADJ         VIA   -     D0100PA00X+063167Y+030107               S1      
317P1V0_NODE1       VIA   -     D0100PA00X+063238Y+030526               S3      
317P1V0_NODE1       VIA   -     D0100PA00X+063170Y+030788               S3      
317P1V0_NODE1       VIA   -     D0100PA00X+063212Y+031290               S3      
317P1V0_NODE1       VIA   -     D0100PA00X+063377Y+031044               S1      
317P1V0_NODE1       VIA   -     D0100PA00X+063565Y+031312               S3      
317P1V0_NODE1       VIA   -     D0100PA00X+063696Y+031093               S3      
327P1V0_NODE1       PC27  -1          A01X+063860Y+031736X0440Y0540R180 S2      
327P1V0_NODE1       PC28  -1          A01X+063859Y+032500X0440Y0540R180 S2      
317P1V0_NODE1       VIA   -     D0100PA00X+062382Y+032106               S3      
317P1V0_NODE1       VIA   -     D0100PA00X+063347Y+032671               S3      
317P1V0_NODE1       VIA   -     D0100PA00X+062814Y+031761               S3      
317P1V0_NODE1       VIA   -     D0100PA00X+063186Y+032146               S3      
317P1V0_NODE1       VIA   -     D0100PA00X+062700Y+032793               S3      
317P1V0_NODE1       VIA   -     D0100PA00X+062289Y+032523               S3      
317P1V0_NODE1       VIA   -     D0100PA00X+063365Y+031520               S3      
327NNAME11070       U33   -6          A01X+063444Y+034482X0220Y0680R270 S2      
327NNAME11071       U33   -5          A01X+063444Y+033982X0220Y0680R270 S2      
317NNAME11070       VIA   -     D0100PA00X+062814Y+034482               S1      
317P1V0_NODE1       VIA   -     D0100PA00X+063019Y+033699               S3      
317P1V0_NODE1       VIA   -     D0100PA00X+062519Y+033699               S3      
327P3V3_NODE1       U33   -8          A01X+063444Y+035482X0220Y0680R270 S2      
327NNAME11072       U33   -7          A01X+063444Y+034982X0220Y0680R270 S2      
317P3V3_NODE1       VIA   -     D0100PA00X+062489Y+035778               S3      
327NNAME11073       R533  -2          A01X+063153Y+038718X0180Y0200R180 S2      
327P3V3_NODE1       R533  -1          A01X+062838Y+038718X0180Y0200R180 S2      
327NNAME11054       R527  -2          A01X+063301Y+038313X0180Y0200R180 S2      
327P3V3_NODE1       R527  -1          A01X+062986Y+038313X0180Y0200R180 S2      
317P1V05_NODE1      VIA   -     D0100PA00X+063774Y+039203               S3      
317P3V3_NODE1       VIA   -     D0100PA00X+063699Y+038646               S3      
317P3V3_NODE1       VIA   -     D0100PA00X+062702Y+038371               S3      
317NNAME11073       VIA   -     D0100PA00X+063451Y+038916               S1      
327NNAME11074       C363  -2          A01X+062200Y+040205X0180Y0200R180 S2      
327NNAME11075       C364  -2          A01X+062200Y+039805X0180Y0200R180 S2      
317GND              VIA   -     D0100PA00X+063363Y+040372               S3      
317P1V05_NODE1      VIA   -     D0100PA00X+063761Y+039726               S3      
317NNAME10933       VIA   -     D0100PA00X+063069Y+040501               S1      
327NNAME11074       VIA   -           A01X+062584Y+040035X0160Y0042     S2      
317P3V3_USB_NODE1   VIA   -     D0100PA00X+063694Y+040289               S3      
327P3V3_USB_NODE1   L34   -2          A10X+063815Y+041929X0320Y0400R090 S1      
327NNAME10633       R525  -2          A01X+062971Y+041877X0180Y0200R180 S2      
327P3V3_NODE1       R525  -1          A01X+062656Y+041877X0180Y0200R180 S2      
317GND              VIA   -     D0100PA00X+063366Y+041101               S3      
317NNAME10932       VIA   -     D0100PA00X+063069Y+041001               S1      
317USB_WAKE_N       VIA   -     D0100PA00X+063659Y+041091               S1      
327P3V3_NODE1       L34   -1          A10X+063815Y+042637X0320Y0400R090 S1      
317P3V3_NODE1       VIA   -     D0100PA00X+063346Y+042721               S3      
317P3V3_NODE1       VIA   -     D0100PA00X+063458Y+042496               S3      
317NNAME10782       VIA   -     D0100PA00X+063584Y+044989               S1      
317NNAME10204       VIA   -     D0100PA00X+062625Y+045025               S3      
317NNAME10047       VIA   -     D0100PA00X+063128Y+044601               S3      
317P3V3_RTC_NODE1   VIA   -     D0100PA00X+063512Y+045614               S3      
317NNAME10702       VIA   -     D0100PA00X+063057Y+045145               S3      
317GND              VIA   -     D0100PA00X+063495Y+046189               S1      
317GND              VIA   -     D0100PA00X+063555Y+046589               S3      
317NNAME10207       VIA   -     D0100PA00X+062210Y+046582               S3      
317NNAME10428       VIA   -     D0100PA00X+062590Y+046177               S3      
317NNAME10640       VIA   -     D0100PA00X+062825Y+047114               S1      
317NNAME10702       VIA   -     D0100PA00X+063268Y+046667               S3      
317NNAME10970       VIA   -     D0100PA00X+063601Y+047000               S3      
327NNAME10341       Q26   -C          A01X+063485Y+047494X0320Y0360R270 S2      
327NNAME10536       Q28   -C          A01X+063479Y+050147X0320Y0360R270 S2      
327NNAME10457       Q24   -C          A01X+063489Y+048827X0320Y0360R270 S2      
317NNAME10457       VIA   -     D0100PA00X+063042Y+049151               S1      
317NNAME10536       VIA   -     D0100PA00X+063617Y+049303               S1      
317NNAME10341       VIA   -     D0100PA00X+062260Y+048875               S1      
327NNAME11076       D21   -A          A01X+063541Y+051123X0320Y0320     S2      
327NNAME11076       R1032 -2          A01X+063529Y+051673X0180Y0200     S2      
317GND              VIA   -     D0100PA00X+062220Y+050654               S1      
317NNAME11076       VIA   -     D0100PA00X+063216Y+051123               S1      
327NNAME11077       S1    -2          A01X+063277Y+052781X0400Y1260R270 S2      
317NNAME11055       VIA   -     D0100PA00X+062513Y+053420               S1      
317CPLD123_RSV1     VIA   -     D0100PA00X+063453Y+052157               S1      
327GND              S1    -4          A01X+063277Y+054356X0400Y1260R270 S2      
317GND              VIA   -     D0100PA00X+063419Y+053827               S1      
317P3V3_STB_NODE1   VIA   -     D0100PA00X+062280Y+054676               S3      
327PU_LAN2_TDI      R567  -2          A01X+062194Y+056432X0180Y0200R270 S2      
327P3V3_NODE1       R567  -1          A01X+062194Y+056117X0180Y0200R270 S2      
327LAN2_XTAL_OUT    Y5    -2          A01X+062967Y+055925X0870Y0870R180 S2      
317GND              VIA   -     D0100PA00X+063236Y+056554               S3      
327GND              C438  -2          A01X+063236Y+056875X0180Y0200     S2      
327LAN2_XTAL_OUT    C438  -1          A01X+063551Y+056875X0180Y0200     S2      
317LAN2_XTAL_OUT    VIA   -     D0100PA00X+063689Y+057135               S1      
317LAN2_AUX_PWR     VIA   -     D0100PA00X+062487Y+057314               S1      
317PU_LAN2_TMS      VIA   -     D0100PA00X+062708Y+057826               S1      
317P1V05_LAN2       VIA   -     D0100PA00X+063492Y+058016               S1      
317P1V05_LAN2       VIA   -     D0100PA00X+062705Y+058107               S3      
327LAN2_XTAL_OUT    U37   -42         A01X+063689Y+058483X0100Y0360     S2      
327P1V05_LAN2       U37   -41         A01X+063492Y+058483X0100Y0360     S2      
327PU_LAN2_TDI      U37   -40         A01X+063295Y+058483X0100Y0360     S2      
327LAN2_AUX_PWR     U37   -39         A01X+063098Y+058483X0100Y0360     S2      
327PU_LAN2_TMS      U37   -38         A01X+062902Y+058483X0100Y0360     S2      
327P1V05_LAN2       U37   -37         A01X+062705Y+058483X0100Y0360     S2      
327SMB_LAN2_DAT     U37   -36         A01X+062508Y+058483X0100Y0360     S2      
327SMB_LAN2_ALT_N   U37   -35         A01X+062311Y+058483X0100Y0360     S2      
327GND              U37   -TH         A01X+063394Y+060275X2130Y2130R270 S2      
327GND              C461  -2          A10X+062697Y+058742X0180Y0200R090 S1      
327P1V05_LAN2       C461  -1          A10X+062697Y+058427X0180Y0200R090 S1      
327GND              C463  -2          A10X+063257Y+058762X0180Y0200R090 S1      
327P1V05_LAN2       C463  -1          A10X+063257Y+058447X0180Y0200R090 S1      
327GND              C454  -2          A10X+063687Y+058762X0180Y0200R090 S1      
327P1V9_LAN2        C454  -1          A10X+063687Y+058447X0180Y0200R090 S1      
317GND              VIA   -     D0100PA00X+063687Y+059314               S3      
317GND              VIA   -     D0100PA00X+063077Y+059324               S3      
317GND              VIA   -     D0100PA00X+062447Y+059324               S3      
317GND              VIA   -     D0100PA00X+062447Y+061214               S3      
317GND              VIA   -     D0100PA00X+062437Y+060594               S3      
317GND              VIA   -     D0100PA00X+062437Y+059974               S3      
317GND              VIA   -     D0100PA00X+062987Y+061224               S3      
317GND              VIA   -     D0100PA00X+063597Y+061224               S3      
327NNAME11064       U37   -14         A01X+062311Y+062066X0100Y0360R180 S2      
327NNAME11078       U37   -13         A01X+062508Y+062066X0100Y0360R180 S2      
327NNAME11079       U37   -12         A01X+062705Y+062066X0100Y0360R180 S2      
327P1V05_LAN2       U37   -11         A01X+062902Y+062066X0100Y0360R180 S2      
327P3V3_NODE1       U37   -10         A01X+063098Y+062066X0100Y0360R180 S2      
327NNAME11080       U37   -9          A01X+063295Y+062066X0100Y0360R180 S2      
327NNAME11081       U37   -8          A01X+063492Y+062066X0100Y0360R180 S2      
327NNAME11082       U37   -7          A01X+063689Y+062066X0100Y0360R180 S2      
327GND              C462  -2          A10X+062607Y+061947X0180Y0200R270 S1      
327P1V05_LAN2       C462  -1          A10X+062607Y+062262X0180Y0200R270 S1      
327GND              C440  -2          A10X+063314Y+061957X0180Y0200R270 S1      
327P3V3_NODE1       C440  -1          A10X+063314Y+062272X0180Y0200R270 S1      
317NNAME11078       VIA   -     D0100PA00X+062394Y+062872               S1      
317NNAME11082       VIA   -     D0100PA00X+063689Y+062710               S1      
317NNAME11080       VIA   -     D0100PA00X+062978Y+062856               S1      
317P1V05_LAN2       VIA   -     D0100PA00X+062799Y+062590               S3      
317P3V3_NODE1       VIA   -     D0100PA00X+063098Y+062483               S3      
327NNAME11080       R574  -2          A01X+063014Y+063374X0180Y0200R090 S2      
327P3V3_NODE1       R574  -1          A01X+063014Y+063689X0180Y0200R090 S2      
327NNAME11081       R576  -2          A01X+063414Y+063374X0180Y0200R090 S2      
327P3V3_NODE1       R576  -1          A01X+063414Y+063689X0180Y0200R090 S2      
317NNAME11064       VIA   -     D0100PA00X+062251Y+063554               S1      
317NNAME11081       VIA   -     D0100PA00X+063414Y+063134               S1      
317NNAME11079       VIA   -     D0100PA00X+062715Y+063893               S1      
317UART_DTR_P4_N    VIA   -     D0100PA00X+062329Y+064122               S3      
317P3V3_NODE1       VIA   -     D0100PA00X+063414Y+063935               S3      
317P3V3_NODE1       VIA   -     D0100PA00X+063014Y+063931               S3      
327NNAME10883       U141  -D          A10X+063694Y+065364X0400Y0500R180 S1      
327NNAME10728       U142  -D          A10X+062320Y+066077X0400Y0500     S1      
327TACKOVER_EN      U142  -G          A10X+062720Y+065197X0400Y0500     S1      
317NNAME10319       VIA   -     D0100PA00X+063193Y+065525               S3      
327N54365827        U59   -1          A10X+062746Y+067560X0140Y0590R270 S1      
327N54365601        U57   -28         A01X+062746Y+067560X0140Y0590R090 S2      
327TACKOVER_EN      U141  -G          A10X+063294Y+066244X0400Y0500R180 S1      
327N54365827        VIA   -           A10X+062634Y+066885X0260Y0260     S1      
327N54365764        U59   -7          A10X+062746Y+069095X0140Y0590R270 S1      
327N54365764        U59   -6          A10X+062746Y+068840X0140Y0590R270 S1      
327NNAME11083       U59   -5          A10X+062746Y+068584X0140Y0590R270 S1      
327UART_RX_RP6_L    U59   -4          A10X+062746Y+068328X0140Y0590R270 S1      
327N54365837        U59   -3          A10X+062746Y+068072X0140Y0590R270 S1      
327N54365829        U59   -2          A10X+062746Y+067816X0140Y0590R270 S1      
327N54365623        U57   -27         A01X+062746Y+067816X0140Y0590R090 S2      
327P3V3_NODE1       U57   -26         A01X+062746Y+068072X0140Y0590R090 S2      
327GND              U57   -25         A01X+062746Y+068328X0140Y0590R090 S2      
327N54365603        U57   -24         A01X+062746Y+068584X0140Y0590R090 S2      
327N54365554        U57   -23         A01X+062746Y+068840X0140Y0590R090 S2      
327N54365556        U57   -22         A01X+062746Y+069095X0140Y0590R090 S2      
317GND              VIA   -     D0100PA00X+063425Y+068349               S3      
327NNAME10726       U59   -13         A10X+062746Y+070631X0140Y0590R270 S1      
327NNAME11084       U59   -12         A10X+062746Y+070375X0140Y0590R270 S1      
327NNAME11085       U59   -11         A10X+062746Y+070119X0140Y0590R270 S1      
327UART_TX_RP6_L    U59   -10         A10X+062746Y+069863X0140Y0590R270 S1      
327NNAME11086       U59   -9          A10X+062746Y+069607X0140Y0590R270 S1      
327N54365764        U59   -8          A10X+062746Y+069351X0140Y0590R270 S1      
327N/C              U57   -21         A01X+062746Y+069351X0140Y0590R090 S2      
327N/C              U57   -20         A01X+062746Y+069607X0140Y0590R090 S2      
327NNAME11067       U57   -19         A01X+062746Y+069863X0140Y0590R090 S2      
327NNAME11087       U57   -18         A01X+062746Y+070119X0140Y0590R090 S2      
327N/C              U57   -17         A01X+062746Y+070375X0140Y0590R090 S2      
327N/C              U57   -16         A01X+062746Y+070631X0140Y0590R090 S2      
327NNAME11068       U59   -14         A10X+062746Y+070887X0140Y0590R270 S1      
327N/C              U57   -15         A01X+062746Y+070887X0140Y0590R090 S2      
327NNAME10729       R1175 -2          A10X+062396Y+071809X0180Y0200R090 S1      
327NNAME11068       R1175 -1          A10X+062396Y+071494X0180Y0200R090 S1      
327NNAME10725       R1176 -2          A10X+062796Y+071809X0180Y0200R090 S1      
327NNAME11084       R1176 -1          A10X+062796Y+071494X0180Y0200R090 S1      
317GND              VIA   -     D0100PA00X+062394Y+072350               S3      
317FAN_PWM          VIA   -     D0100PA00X+063397Y+072303               S1      
317I2C_PSU3_SDA     VIA   -     D0100PA00X+062229Y+070852               S3      
317T12_NODE4_EN     VIA   -     D0100PA00X+062816Y+072234               S1      
327NNAME11084       VIA   -           A10X+063253Y+071679X0260Y0260     S1      
327GND              C588  -2          A01X+062844Y+073908X0180Y0200R090 S2      
327GND              C669  -2          A10X+062394Y+072658X0180Y0200R270 S1      
327T12_NODE4_EN_R   C669  -1          A10X+062394Y+072973X0180Y0200R270 S1      
327GND              R1224 -2          A10X+062394Y+073808X0180Y0200R270 S1      
327GND              R1223 -2          A01X+063313Y+073891X0180Y0200R090 S2      
327GND              R1222 -2          A01X+063713Y+073891X0180Y0200R090 S2      
327GND              R1219 -2          A01X+062394Y+073908X0180Y0200R090 S2      
327FAN6_TACH        R830  -1          A10X+062844Y+073808X0180Y0200R090 S1      
327FAN_PWM_R        R819  -2          A01X+062844Y+073073X0180Y0200R270 S2      
327FAN_PWM          R819  -1          A01X+062844Y+072758X0180Y0200R270 S2      
327FAN1_TACH_R      R821  -2          A01X+062394Y+073073X0180Y0200R270 S2      
327FAN1_TACH        R821  -1          A01X+062394Y+072758X0180Y0200R270 S2      
327FAN4_TACH        R827  -1          A10X+063644Y+073808X0180Y0200R090 S1      
327FAN5_TACH        R829  -1          A10X+063244Y+073808X0180Y0200R090 S1      
327T12_NODE4_EN_R   R906  -2          A10X+062844Y+072972X0180Y0200R090 S1      
327T12_NODE4_EN     R906  -1          A10X+062844Y+072657X0180Y0200R090 S1      
317GND              VIA   -     D0100PA00X+062396Y+073514               S3      
317GND              VIA   -     D0100PA00X+062838Y+073548               S3      
317FAN4_TACH        VIA   -     D0100PA00X+063169Y+073374               S3      
317FAN5_TACH        VIA   -     D0100PA00X+063546Y+073513               S3      
317NNAME10725       VIA   -     D0100PA00X+063617Y+072934               S1      
327FAN_PWM_R        C588  -1          A01X+062844Y+074223X0180Y0200R090 S2      
327FAN6_TACH_R      R1224 -1          A10X+062394Y+074123X0180Y0200R270 S1      
327FAN5_TACH_R      R1223 -1          A01X+063313Y+074206X0180Y0200R090 S2      
327FAN4_TACH_R      R1222 -1          A01X+063713Y+074206X0180Y0200R090 S2      
327FAN1_TACH_R      R1219 -1          A01X+062394Y+074223X0180Y0200R090 S2      
327FAN6_TACH_R      R830  -2          A10X+062844Y+074123X0180Y0200R090 S1      
327FAN4_TACH_R      R827  -2          A10X+063644Y+074123X0180Y0200R090 S1      
327FAN5_TACH_R      R829  -2          A10X+063244Y+074123X0180Y0200R090 S1      
317FAN6_TACH        VIA   -     D0100PA00X+063004Y+074511               S3      
317FAN5_TACH_R      VIA   -     D0100PA00X+063230Y+074976               S1      
317FAN4_TACH_R      VIA   -     D0100PA00X+063691Y+074582               S1      
317FAN_PWM_R        VIA   -     D0100PA00X+062401Y+074635               S1      
317NNAME11088       VIA   -     D0100PA00X+062991Y+076920               S1      
327NNAME11089       TP10  -1          A10X+063152Y+078284X0300Y0300     S1      
327UART_CTS_RP6_L   TP12  -1          A10X+063566Y+077205X0300Y0300     S1      
317FAN1_TACH_R      VIA   -     D0100PA00X+062501Y+077828               S1      
317UART_CTS_RP6_L   VIA   -     D0100PA00X+063639Y+077540               S3      
317NNAME11089       VIA   -     D0100PA00X+063203Y+077914               S3      
317NNAME11090       VIA   -     D0100PA00X+063200Y+077540               S3      
327FAN5_TACH_R      J18   -A27        A10X+062605Y+080787X0300Y1660R180 S1      
327FAN4_TACH_R      J18   -A26        A10X+062998Y+080787X0300Y1660R180 S1      
327GND              J18   -A25        A10X+063392Y+080787X0300Y1660R180 S1      
327NNAME11090       J18   -A24        A10X+063786Y+080787X0300Y1660R180 S1      
327FAN1_TACH_R      J18   -B27        A01X+062605Y+080787X0300Y1660R180 S2      
327GND              J18   -B26        A01X+062998Y+080787X0300Y1660R180 S2      
327NNAME11088       J18   -B25        A01X+063392Y+080787X0300Y1660R180 S2      
327NNAME11089       J18   -B24        A01X+063786Y+080787X0300Y1660R180 S2      
317GND              VIA   -     D0100PA00X+062998Y+079148               S3      
317GND              VIA   -     D0100PA00X+063392Y+079148               S3      
317N/C              J27   -8    D0460PA00X+064996Y+002880               S0      
317N/C              J27   -7    D0460PA00X+064996Y+003880               S0      
327JTAG_CPLD3_TDI   R1214 -2          A01X+064396Y+004753X0180Y0200R090 S2      
327P3V3_NODE1       R1214 -1          A01X+064396Y+005068X0180Y0200R090 S2      
327JTAG_CPLD3_TDI   R1198 -2          A01X+063996Y+004753X0180Y0200R090 S2      
327NNAME10896       R1198 -1          A01X+063996Y+005068X0180Y0200R090 S2      
317P3V3_NODE1       VIA   -     D0100PA00X+064396Y+005369               S3      
317NNAME10896       VIA   -     D0100PA00X+063996Y+005385               S3      
317GND              VIA   -     D0100PA00X+063897Y+013224               S3      
317NNAME10949       VIA   -     D0100PA00X+063920Y+017010               S1      
317NNAME10883       VIA   -     D0100PA00X+063935Y+025012               S1      
327GND              C852  -2          A01X+064561Y+028871X0180Y0200     S2      
327N47241340        C852  -1          A01X+064876Y+028871X0180Y0200     S2      
327N47241340        PJ3   -2          A01X+064878Y+028470X0180Y0200R180 S2      
327NNAME11091       PJ3   -1          A01X+064563Y+028470X0200Y0400R090 S2      
317GND              VIA   -     D0100PA00X+064045Y+029442               S3      
317GND              VIA   -     D0100PA00X+064317Y+029428               S3      
317GND              VIA   -     D0100PA00X+064123Y+029707               S3      
317GND              VIA   -     D0100PA00X+064411Y+029707               S3      
317GND              VIA   -     D0100PA00X+065335Y+029139               S3      
317NNAME11091       VIA   -     D0100PA00X+064293Y+028477               S3      
317P3V3_STB_NODE1   VIA   -     D0100PA00X+064011Y+028504               S3      
317N47241340        VIA   -     D0100PA00X+065000Y+029643               S1      
327P5V_STB_NODE1    U130  -10         A01X+064856Y+030852X0110Y0360R270 S2      
327N47241340        U130  -6          A01X+064856Y+030064X0110Y0360R090 S2      
327P1V8_NODE1       U130  -9          A01X+064856Y+030655X0110Y0360R270 S2      
327P1V8_NODE1       U130  -8          A01X+064856Y+030458X0110Y0360R270 S2      
327P1V8_NODE1       U130  -7          A01X+064856Y+030261X0110Y0360R270 S2      
327GND              U130  -TH         A01X+064245Y+030458X0690Y1050     S2      
317GND              VIA   -     D0100PA00X+064017Y+031197               S3      
317GND              VIA   -     D0100PA00X+064411Y+031197               S3      
317P1V8_NODE1       VIA   -     D0100PA00X+065236Y+030660               S3      
327GND              PC27  -2          A01X+064608Y+031736X0440Y0540R180 S2      
327GND              PC28  -2          A01X+064607Y+032500X0440Y0540R180 S2      
317GND              VIA   -     D0100PA00X+065135Y+032394               S3      
317GND              VIA   -     D0100PA00X+065316Y+031840               S3      
317GND              VIA   -     D0100PA00X+065016Y+031840               S3      
317NNAME11071       VIA   -     D0100PA00X+064065Y+033985               S1      
317P1V0_NODE1       VIA   -     D0100PA00X+064845Y+033871               S3      
327GND              C367  -2          A01X+064601Y+035489X0180Y0200R180 S2      
327P3V3_NODE1       C367  -1          A01X+064286Y+035489X0180Y0200R180 S2      
327NNAME11072       R529  -2          A01X+064296Y+034979X0180Y0200     S2      
327P3V3_NODE1       R529  -1          A01X+064611Y+034979X0180Y0200     S2      
317GND              VIA   -     D0100PA00X+064601Y+035811               S3      
317P3V3_NODE1       VIA   -     D0100PA00X+064884Y+034979               S3      
317P3V3_NODE1       VIA   -     D0100PA00X+064286Y+035801               S3      
317NNAME11072       VIA   -     D0100PA00X+063984Y+034982               S1      
327NNAME11092       R522  -2          A01X+064524Y+037103X0180Y0200R270 S2      
327NNAME11070       R522  -1          A01X+064524Y+036788X0180Y0200R270 S2      
327NNAME11093       R523  -2          A01X+064124Y+037103X0180Y0200R270 S2      
327NNAME11062       R523  -1          A01X+064124Y+036788X0180Y0200R270 S2      
327NNAME11094       R524  -2          A01X+064924Y+037103X0180Y0200R270 S2      
327NNAME11071       R524  -1          A01X+064924Y+036788X0180Y0200R270 S2      
317NNAME11070       VIA   -     D0100PA00X+064617Y+036468               S3      
317NNAME11094       VIA   -     D0100PA00X+064843Y+037347               S1      
317USB_OC_PU        VIA   -     D0100PA00X+065214Y+037713               S1      
327USB_OC_PU        U32   -22         A01X+065214Y+038202X0070Y0470     S2      
327N/C              U32   -21         A01X+065056Y+038202X0070Y0470     S2      
327USB_OC_PU        U32   -20         A01X+064899Y+038202X0070Y0470     S2      
327NNAME11094       U32   -19         A01X+064741Y+038202X0070Y0470     S2      
327NNAME11092       U32   -18         A01X+064584Y+038167X0070Y0400     S2      
327NNAME11093       U32   -17         A01X+064272Y+038479X0070Y0400R090 S2      
327NNAME11052       U32   -16         A01X+064307Y+038636X0070Y0470R090 S2      
327P3V3_NODE1       U32   -15         A01X+064307Y+038794X0070Y0470R090 S2      
327NNAME11054       U32   -14         A01X+064307Y+038951X0070Y0470R090 S2      
327NNAME11073       U32   -13         A01X+064307Y+039109X0070Y0470R090 S2      
327GND              U32   -TH         A01X+065844Y+039739X2440Y2440     S2      
327P3V3_NODE1       C382  -2          A10X+064066Y+038729X0180Y0200R180 S1      
327GND              C382  -1          A10X+064381Y+038729X0180Y0200R180 S1      
327P1V05_NODE1      C376  -2          A10X+064066Y+039209X0180Y0200R180 S1      
327GND              C376  -1          A10X+064381Y+039209X0180Y0200R180 S1      
317GND              VIA   -     D0100PA00X+064744Y+038638               S3      
317NNAME11093       VIA   -     D0100PA00X+064124Y+038162               S1      
317NNAME11092       VIA   -     D0100PA00X+064524Y+037786               S1      
327P1V05_NODE1      U32   -12         A01X+064307Y+039266X0070Y0470R090 S2      
327NNAME10966       U32   -11         A01X+064307Y+039424X0070Y0470R090 S2      
327NNAME10934       U32   -10         A01X+064307Y+039581X0070Y0470R090 S2      
327P1V05_NODE1      U32   -9          A01X+064307Y+039739X0070Y0470R090 S2      
327NNAME11075       U32   -8          A01X+064307Y+039896X0070Y0470R090 S2      
327NNAME11074       U32   -7          A01X+064307Y+040054X0070Y0470R090 S2      
327P3V3_USB_NODE1   U32   -6          A01X+064307Y+040211X0070Y0470R090 S2      
327NNAME10933       U32   -5          A01X+064307Y+040368X0070Y0470R090 S2      
327NNAME10932       U32   -4          A01X+064307Y+040526X0070Y0470R090 S2      
327USB_WAKE_N       U32   -3          A01X+064307Y+040683X0070Y0470R090 S2      
327P1V05_NODE1      C374  -2          A10X+064066Y+039699X0180Y0200R180 S1      
327GND              C374  -1          A10X+064381Y+039699X0180Y0200R180 S1      
327GND              C385  -2          A10X+064381Y+040158X0180Y0200     S1      
327P3V3_USB_NODE1   C385  -1          A10X+064066Y+040158X0180Y0200     S1      
327P3V3_USB_NODE1   C386  -2          A10X+064066Y+040588X0180Y0200R180 S1      
327GND              C386  -1          A10X+064381Y+040588X0180Y0200R180 S1      
317GND              VIA   -     D0100PA00X+064734Y+039328               S3      
317GND              VIA   -     D0100PA00X+064744Y+040838               S3      
317GND              VIA   -     D0100PA00X+064734Y+040008               S3      
327NNAME11075       VIA   -           A01X+063754Y+039915X0160Y0042     S2      
327USB3_DN          U32   -68         A01X+064584Y+041310X0070Y0400     S2      
327USB3_DP          U32   -67         A01X+064741Y+041275X0070Y0470     S2      
327P3V3_NODE1       U32   -66         A01X+064899Y+041275X0070Y0470     S2      
327GND              U32   -65         A01X+065056Y+041275X0070Y0470     S2      
327GND              U32   -64         A01X+065214Y+041275X0070Y0470     S2      
327N34379705        U32   -2          A01X+064307Y+040841X0070Y0470R090 S2      
327NNAME10633       U32   -1          A01X+064272Y+040998X0070Y0400R090 S2      
327P3V3_NODE1       C381  -2          A10X+064884Y+041436X0180Y0200R090 S1      
327GND              C381  -1          A10X+064884Y+041121X0180Y0200R090 S1      
317GND              VIA   -     D0100PA00X+065114Y+041739               S3      
317P3V3_NODE1       VIA   -     D0100PA00X+064849Y+041722               S3      
317GND              VIA   -     D0100PA00X+064148Y+043029               S3      
317GND              VIA   -     D0100PA00X+065008Y+043029               S3      
317USB3_DP          VIA   -     D0100PA00X+064821Y+042782               S3      
317USB3_DN          VIA   -     D0100PA00X+064321Y+042782               S3      
317P1V05_NODE1      VIA   -     D0100PA00X+065307Y+042750               S3      
317TP_U3TXDN4       VIA   -     D0100PA00X+065082Y+042530               S1      
317NNAME10638       VIA   -     D0100PA00X+064169Y+044366               S3      
317NNAME10691       VIA   -     D0100PA00X+064728Y+044685               S1      
317NNAME10562       VIA   -     D0100PA00X+065336Y+044628               S3      
317NNAME10543       VIA   -     D0100PA00X+065108Y+045524               S1      
327NNAME10541       R134  -2          A01X+064211Y+046589X0180Y0200R180 S2      
327GND              R134  -1          A01X+063896Y+046589X0180Y0200R180 S2      
327GND              R176  -2          A01X+063896Y+046189X0180Y0200     S2      
327NNAME10627       R176  -1          A01X+064211Y+046189X0180Y0200     S2      
327P3V3_RTC_NODE1   R175  -2          A01X+063896Y+045789X0180Y0200     S2      
327NNAME10627       R175  -1          A01X+064211Y+045789X0180Y0200     S2      
327NNAME11095       Q26   -B          A01X+064273Y+047120X0320Y0360R270 S2      
317NNAME10209       VIA   -     D0100PA00X+065211Y+046524               S1      
317NNAME10049       VIA   -     D0100PA00X+065184Y+046001               S3      
317NNAME10059       VIA   -     D0100PA00X+064892Y+045785               S3      
317NNAME10701       VIA   -     D0100PA00X+064660Y+046357               S1      
317NNAME11096       VIA   -     D0100PA00X+064896Y+046932               S1      
327NNAME11097       Q24   -B          A01X+064276Y+048453X0320Y0360R270 S2      
327GND              Q26   -E          A01X+064273Y+047868X0320Y0360R270 S2      
317GND              VIA   -     D0100PA00X+064638Y+047868               S3      
317NNAME11097       VIA   -     D0100PA00X+065052Y+048293               S1      
317NNAME11095       VIA   -     D0100PA00X+064792Y+047578               S1      
317P3V3_STB_NODE1   VIA   -     D0100PA00X+065140Y+048727               S3      
327NNAME11098       Q28   -B          A01X+064266Y+049773X0320Y0360R270 S2      
327GND              Q24   -E          A01X+064276Y+049201X0320Y0360R270 S2      
317GND              VIA   -     D0100PA00X+064611Y+049201               S1      
317NNAME11098       VIA   -     D0100PA00X+065079Y+049773               S1      
317NNAME11099       VIA   -     D0100PA00X+065015Y+049434               S3      
327NNAME11100       D21   -C          A01X+064131Y+051123X0320Y0320     S2      
327P3V3_STB_NODE1   R1032 -1          A01X+063844Y+051673X0180Y0200     S2      
327GND              Q28   -E          A01X+064266Y+050521X0320Y0360R270 S2      
317GND              VIA   -     D0100PA00X+064691Y+050521               S1      
317NNAME10782       VIA   -     D0100PA00X+063835Y+050789               S3      
317P3V3_STB_NODE1   VIA   -     D0100PA00X+064184Y+051673               S3      
317NNAME10904       VIA   -     D0100PA00X+064646Y+051297               S1      
317NNAME11101       VIA   -     D0100PA00X+065269Y+053169               S1      
317CPLD123_RSV2     VIA   -     D0100PA00X+064047Y+052327               S3      
317CPLD123_RSV3     VIA   -     D0100PA00X+064504Y+052444               S1      
317JTAG_CPLD2_TCK   VIA   -     D0100PA00X+064515Y+053570               S3      
327LAN2_XTAL_IN     Y5    -1          A01X+064621Y+055925X0870Y0870R180 S2      
317GND              VIA   -     D0100PA00X+063817Y+056097               S3      
317GND              VIA   -     D0100PA00X+063829Y+055742               S3      
317GND              VIA   -     D0100PA00X+064301Y+056524               S3      
327GND              C437  -2          A01X+064301Y+056875X0180Y0200R180 S2      
327LAN2_XTAL_IN     C437  -1          A01X+063986Y+056875X0180Y0200R180 S2      
327LAN2_RST         R589  -2          A01X+065144Y+057572X0180Y0200R270 S2      
327GND              R589  -1          A01X+065144Y+057257X0180Y0200R270 S2      
327N21357353        TP3   -1          A10X+064342Y+056895X0300Y0300R270 S1      
317GND              VIA   -     D0100PA00X+065144Y+056968               S3      
317LAN2_XTAL_IN     VIA   -     D0100PA00X+063967Y+057689               S1      
317LAN2_RST         VIA   -     D0100PA00X+065144Y+057894               S1      
317P1V9_LAN2        VIA   -     D0100PA00X+064673Y+058078               S3      
317P1V9_LAN2        VIA   -     D0100PA00X+064187Y+058074               S3      
317N21357353        VIA   -     D0100PA00X+064687Y+056944               S3      
317N21357373        VIA   -     D0100PA00X+064687Y+057624               S3      
327LAN2_MDI2_DP     U37   -53         A01X+065185Y+059586X0100Y0360R270 S2      
327LAN2_MDI2_DN     U37   -52         A01X+065185Y+059389X0100Y0360R270 S2      
327P1V9_LAN2        U37   -51         A01X+065185Y+059192X0100Y0360R270 S2      
327LAN2_MDI3_DP     U37   -50         A01X+065185Y+058995X0100Y0360R270 S2      
327LAN2_MDI3_DN     U37   -49         A01X+065185Y+058798X0100Y0360R270 S2      
327LAN2_RST         U37   -48         A01X+064870Y+058483X0100Y0360     S2      
327P1V9_LAN2        U37   -47         A01X+064673Y+058483X0100Y0360     S2      
327N21357373        U37   -46         A01X+064476Y+058483X0100Y0360     S2      
327N21357353        U37   -45         A01X+064280Y+058483X0100Y0360     S2      
327P1V9_LAN2        U37   -44         A01X+064083Y+058483X0100Y0360     S2      
327LAN2_XTAL_IN     U37   -43         A01X+063886Y+058483X0100Y0360     S2      
327GND              C455  -2          A10X+064886Y+059175X0180Y0200R180 S1      
327P1V9_LAN2        C455  -1          A10X+065201Y+059175X0180Y0200R180 S1      
327GND              C459  -2          A10X+064524Y+058762X0180Y0200R090 S1      
327P1V9_LAN2        C459  -1          A10X+064524Y+058447X0180Y0200R090 S1      
327GND              C452  -2          A10X+064097Y+058772X0180Y0200R090 S1      
327P1V9_LAN2        C452  -1          A10X+064097Y+058457X0180Y0200R090 S1      
327GND              C456  -2          A10X+064880Y+059594X0180Y0200R180 S1      
327P1V9_LAN2        C456  -1          A10X+065195Y+059594X0180Y0200R180 S1      
317GND              VIA   -     D0100PA00X+064357Y+059324               S3      
327P1V9_LAN2        VIA   -           A10X+065330Y+058568X0260Y0260R270 S1      
327P1V9_LAN2        U37   -61         A01X+065185Y+061160X0100Y0360R270 S2      
327P1V05_LAN2       U37   -60         A01X+065185Y+060964X0100Y0360R270 S2      
327LAN2_DIS_REG10   U37   -59         A01X+065185Y+060767X0100Y0360R270 S2      
327LAN2_MDI0_DP     U37   -58         A01X+065185Y+060570X0100Y0360R270 S2      
327LAN2_MDI0_DN     U37   -57         A01X+065185Y+060373X0100Y0360R270 S2      
327P1V9_LAN2        U37   -56         A01X+065185Y+060176X0100Y0360R270 S2      
327LAN2_MDI1_DP     U37   -55         A01X+065185Y+059979X0100Y0360R270 S2      
327LAN2_MDI1_DN     U37   -54         A01X+065185Y+059782X0100Y0360R270 S2      
327GND              C472  -2          A10X+064886Y+061175X0180Y0200R180 S1      
327P1V9_LAN2        C472  -1          A10X+065201Y+061175X0180Y0200R180 S1      
327GND              C467  -2          A10X+064890Y+060754X0180Y0200R180 S1      
327P1V05_LAN2       C467  -1          A10X+065205Y+060754X0180Y0200R180 S1      
327GND              C453  -2          A10X+064886Y+060175X0180Y0200R180 S1      
327P1V9_LAN2        C453  -1          A10X+065201Y+060175X0180Y0200R180 S1      
317GND              VIA   -     D0100PA00X+064357Y+061234               S3      
317GND              VIA   -     D0100PA00X+064357Y+060664               S3      
317GND              VIA   -     D0100PA00X+064357Y+059954               S3      
327LAN2_CTRL_P1V9   U37   -64         A01X+065185Y+061751X0100Y0360R270 S2      
327P1V9_LAN2        U37   -63         A01X+065185Y+061554X0100Y0360R270 S2      
327N/C              U37   -62         A01X+065185Y+061357X0100Y0360R270 S2      
327NNAME11102       U37   -6          A01X+063886Y+062066X0100Y0360R180 S2      
327NNAME11103       U37   -5          A01X+064083Y+062066X0100Y0360R180 S2      
327P1V05_LAN2       U37   -4          A01X+064280Y+062066X0100Y0360R180 S2      
327NNAME11104       U37   -3          A01X+064476Y+062066X0100Y0360R180 S2      
327NNAME11105       U37   -2          A01X+064673Y+062066X0100Y0360R180 S2      
327P3V3_NODE1       U37   -1          A01X+064870Y+062066X0100Y0360R180 S2      
327GND              C441  -2          A10X+064607Y+061967X0180Y0200R270 S1      
327P3V3_NODE1       C441  -1          A10X+064607Y+062282X0180Y0200R270 S1      
327P3V3_NODE1       C443  -1          A10X+065150Y+062444X0180Y0200     S1      
327GND              C465  -2          A10X+064007Y+061967X0180Y0200R270 S1      
327P1V05_LAN2       C465  -1          A10X+064007Y+062282X0180Y0200R270 S1      
327GND              C471  -2          A10X+064886Y+061575X0180Y0200R180 S1      
327P1V9_LAN2        C471  -1          A10X+065201Y+061575X0180Y0200R180 S1      
317NNAME11103       VIA   -     D0100PA00X+064464Y+062726               S1      
317P1V05_LAN2       VIA   -     D0100PA00X+064280Y+062482               S3      
317P3V3_NODE1       VIA   -     D0100PA00X+064870Y+062477               S3      
327NNAME11102       R578  -2          A01X+064274Y+063384X0180Y0200R090 S2      
327P3V3_NODE1       R578  -1          A01X+064274Y+063699X0180Y0200R090 S2      
327NNAME11103       R580  -2          A01X+064674Y+063384X0180Y0200R090 S2      
327P3V3_NODE1       R580  -1          A01X+064674Y+063699X0180Y0200R090 S2      
327NNAME11104       R587  -2          A01X+065097Y+063374X0180Y0200R090 S2      
327GND              R587  -1          A01X+065097Y+063689X0180Y0200R090 S2      
327NNAME11082       R586  -2          A01X+063847Y+063374X0180Y0200R090 S2      
327GND              R586  -1          A01X+063847Y+063689X0180Y0200R090 S2      
317GND              VIA   -     D0100PA00X+063847Y+063929               S3      
317GND              VIA   -     D0100PA00X+065093Y+063929               S3      
317LAN2_NVM_SI_R    VIA   -     D0100PA00X+064694Y+064345               S1      
317NNAME11102       VIA   -     D0100PA00X+064126Y+063139               S1      
317NNAME11104       VIA   -     D0100PA00X+064917Y+062988               S1      
317P3V3_NODE1       VIA   -     D0100PA00X+064674Y+063941               S3      
317P3V3_NODE1       VIA   -     D0100PA00X+064274Y+063941               S3      
327P3V3_NODE1       U38   -8          A01X+064093Y+066007X0220Y0680R270 S2      
327NNAME11106       U38   -7          A01X+064093Y+065507X0220Y0680R270 S2      
327LAN2_NVM_SK_R    U38   -6          A01X+064093Y+065007X0220Y0680R270 S2      
327LAN2_NVM_SI_R    U38   -5          A01X+064093Y+064507X0220Y0680R270 S2      
327P3V3_NODE1       C434  -1          A01X+065123Y+066049X0180Y0200R180 S2      
327NNAME11106       R583  -1          A01X+065123Y+065507X0180Y0200R180 S2      
327LAN2_NVM_SK_R    R575  -2          A01X+065123Y+065007X0180Y0200     S2      
327LAN2_NVM_SI_R    R577  -2          A01X+065123Y+064507X0180Y0200     S2      
327NNAME10728       R1064 -2          A10X+065034Y+066042X0180Y0200R270 S1      
327NNAME10883       R1061 -2          A10X+064575Y+066043X0180Y0200R270 S1      
317LAN2_NVM_SK_R    VIA   -     D0100PA00X+064787Y+064978               S1      
317NNAME11106       VIA   -     D0100PA00X+064658Y+065478               S1      
327N54365821        U59   -28         A10X+065046Y+067560X0140Y0590R270 S1      
327N54365611        U57   -1          A01X+065046Y+067560X0140Y0590R090 S2      
327NNAME11066       R1064 -1          A10X+065034Y+066357X0180Y0200R270 S1      
327NNAME11087       R1061 -1          A10X+064575Y+066358X0180Y0200R270 S1      
327NNAME11087       U141  -S          A10X+064094Y+066244X0400Y0500R180 S1      
317P3V3_NODE1       VIA   -     D0100PA00X+065123Y+066629               S3      
327NNAME11087       VIA   -           A10X+064163Y+066878X0260Y0260     S1      
327NNAME11066       VIA   -           A10X+064737Y+066864X0260Y0260     S1      
327N54365835        U59   -27         A10X+065046Y+067816X0140Y0590R270 S1      
327P3V3_NODE1       U59   -26         A10X+065046Y+068072X0140Y0590R270 S1      
327GND              U59   -25         A10X+065046Y+068328X0140Y0590R270 S1      
327N54365823        U59   -24         A10X+065046Y+068584X0140Y0590R270 S1      
327N54365772        U59   -23         A10X+065046Y+068840X0140Y0590R270 S1      
327N54365776        U59   -22         A10X+065046Y+069095X0140Y0590R270 S1      
327N54365542        U57   -7          A01X+065046Y+069095X0140Y0590R090 S2      
327N54365542        U57   -6          A01X+065046Y+068840X0140Y0590R090 S2      
327NNAME11107       U57   -5          A01X+065046Y+068584X0140Y0590R090 S2      
327UART_RX_RP5_L    U57   -4          A01X+065046Y+068328X0140Y0590R090 S2      
327N54365625        U57   -3          A01X+065046Y+068072X0140Y0590R090 S2      
327N54365613        U57   -2          A01X+065046Y+067816X0140Y0590R090 S2      
317NNAME10883       VIA   -     D0100PA00X+063994Y+068784               S3      
317NNAME11087       VIA   -     D0100PA00X+064033Y+068444               S3      
317NNAME11066       VIA   -     D0100PA00X+064300Y+068578               S3      
327N/C              U59   -21         A10X+065046Y+069351X0140Y0590R270 S1      
327N/C              U59   -20         A10X+065046Y+069607X0140Y0590R270 S1      
327NNAME11108       U59   -19         A10X+065046Y+069863X0140Y0590R270 S1      
327NNAME11066       U59   -18         A10X+065046Y+070119X0140Y0590R270 S1      
327N/C              U59   -17         A10X+065046Y+070375X0140Y0590R270 S1      
327N/C              U59   -16         A10X+065046Y+070631X0140Y0590R270 S1      
327NNAME11022       U57   -13         A01X+065046Y+070631X0140Y0590R090 S2      
327NNAME11109       U57   -12         A01X+065046Y+070375X0140Y0590R090 S2      
327NNAME11110       U57   -11         A01X+065046Y+070119X0140Y0590R090 S2      
327UART_TX_RP5_L    U57   -10         A01X+065046Y+069863X0140Y0590R090 S2      
327NNAME11111       U57   -9          A01X+065046Y+069607X0140Y0590R090 S2      
327N54365542        U57   -8          A01X+065046Y+069351X0140Y0590R090 S2      
327N/C              U59   -15         A10X+065046Y+070887X0140Y0590R270 S1      
327NNAME11112       U57   -14         A01X+065046Y+070887X0140Y0590R090 S2      
327NNAME11016       R1169 -2          A01X+065123Y+071667X0180Y0200R180 S2      
327NNAME11112       R1169 -1          A01X+064808Y+071667X0180Y0200R180 S2      
327NNAME10727       R1173 -2          A10X+065123Y+072067X0180Y0200     S1      
327NNAME11108       R1173 -1          A10X+064808Y+072067X0180Y0200     S1      
327GND              R1172 -2          A01X+065123Y+072067X0180Y0200R180 S2      
327NNAME11016       R1172 -1          A01X+064808Y+072067X0180Y0200R180 S2      
327GND              R1174 -2          A10X+064808Y+071667X0180Y0200R180 S1      
327NNAME10727       R1174 -1          A10X+065123Y+071667X0180Y0200R180 S1      
317GND              VIA   -     D0100PA00X+064808Y+071357               S3      
317NNAME11021       VIA   -     D0100PA00X+064495Y+071911               S3      
327NNAME11109       VIA   -           A01X+064361Y+072409X0300Y0300     S2      
327NNAME11108       VIA   -           A10X+064374Y+071600X0260Y0260     S1      
327N54365776        VIA   -           A10X+064397Y+072265X0260Y0260     S1      
327N54365772        R1308 -2          A10X+064903Y+072867X0180Y0200R180 S1      
327P3V3_NODE1       R1308 -1          A10X+065218Y+072867X0180Y0200R180 S1      
327N54365776        R1307 -2          A10X+064808Y+072467X0180Y0200R180 S1      
327P3V3_NODE1       R1307 -1          A10X+065123Y+072467X0180Y0200R180 S1      
327NNAME11021       R1170 -2          A01X+065123Y+072467X0180Y0200R180 S2      
327NNAME11109       R1170 -1          A01X+064808Y+072467X0180Y0200R180 S2      
327GND              R1171 -2          A01X+065123Y+072867X0180Y0200R180 S2      
327NNAME11021       R1171 -1          A01X+064808Y+072867X0180Y0200R180 S2      
327NNAME11083       R1333 -2          A10X+064800Y+073893X0180Y0200R270 S1      
327NNAME11107       R1334 -1          A01X+064350Y+073893X0180Y0200R270 S2      
317GND              VIA   -     D0100PA00X+065350Y+073258               S3      
317GND              VIA   -     D0100PA00X+063993Y+073891               S3      
317T12_NODE4_EN_R   VIA   -     D0100PA00X+063889Y+073488               S3      
327NNAME11083       VIA   -           A10X+064540Y+073460X0260Y0260     S1      
327N54365772        VIA   -           A10X+065016Y+073340X0260Y0260     S1      
327NNAME11107       VIA   -           A01X+064300Y+073420X0300Y0300     S2      
327GND              C613  -2          A10X+065266Y+073936X0180Y0200R270 S1      
327I2C_PDB_R_SDA    C613  -1          A10X+065266Y+074251X0180Y0200R270 S1      
327NNAME11090       R1333 -1          A10X+064800Y+074208X0180Y0200R270 S1      
327NNAME11088       R1334 -2          A01X+064350Y+074208X0180Y0200R270 S2      
317I2C_PDB_R_SDA    VIA   -     D0100PA00X+065266Y+074900               S1      
327NNAME11085       VIA   -           A10X+064096Y+075064X0260Y0260     S1      
317UART_RX_RP5_L    VIA   -     D0100PA00X+063992Y+075353               S3      
317UART_TX_RP5_L    VIA   -     D0100PA00X+064668Y+075501               S1      
317NNAME11090       VIA   -     D0100PA00X+064650Y+074630               S1      
317UART_RX_RP6_L    VIA   -     D0100PA00X+065040Y+077052               S3      
317NNAME11110       VIA   -     D0100PA00X+063847Y+076221               S1      
317NNAME11110       VIA   -     D0100PA00X+064964Y+075753               S3      
317NNAME11111       VIA   -     D0100PA00X+064637Y+075925               S3      
317NNAME11111       VIA   -     D0100PA00X+064741Y+076705               S1      
327UART_DSR_RP5_L   TP9   -1          A10X+065126Y+078361X0300Y0300     S1      
317UART_RX_RP6_L    VIA   -     D0100PA00X+065169Y+077810               S1      
317UART_RX_RP5_L    VIA   -     D0100PA00X+064001Y+077822               S1      
327UART_TX_RP6_L    VIA   -           A10X+064411Y+077311X0260Y0260     S1      
317UART_DSR_RP5_L   VIA   -     D0100PA00X+065221Y+078670               S3      
327UART_CTS_RP6_L   J18   -A23        A10X+064179Y+080787X0300Y1660R180 S1      
327NNAME11085       J18   -A22        A10X+064573Y+080787X0300Y1660R180 S1      
327UART_TX_RP6_L    J18   -A21        A10X+064967Y+080787X0300Y1660R180 S1      
327UART_RX_RP6_L    J18   -A20        A10X+065361Y+080787X0300Y1660R180 S1      
327NNAME11110       J18   -B23        A01X+064179Y+080787X0300Y1660R180 S2      
327UART_TX_RP5_L    J18   -B22        A01X+064573Y+080787X0300Y1660R180 S2      
327UART_RX_RP5_L    J18   -B21        A01X+064967Y+080787X0300Y1660R180 S2      
327UART_DSR_RP5_L   J18   -B20        A01X+065361Y+080787X0300Y1660R180 S2      
317N/C              J27   -6    D0460PA00X+065996Y+002880               S0      
317P3V3_NODE1       J27   -4    D0460PA00X+066996Y+002880               S0      
317JTAG_CPLD3_TMS   J27   -5    D0460PA00X+065996Y+003880               S0      
317JTAG_CPLD3_TDO   J27   -3    D0460PA00X+066996Y+003880               S0      
327JTAG_CPLD3_TMS   R1213 -2          A01X+065595Y+004761X0180Y0200R090 S2      
327P3V3_NODE1       R1213 -1          A01X+065595Y+005076X0180Y0200R090 S2      
327JTAG_CPLD3_TMS   R1197 -2          A01X+065995Y+004761X0180Y0200R090 S2      
327NNAME10894       R1197 -1          A01X+065995Y+005076X0180Y0200R090 S2      
317P3V3_NODE1       VIA   -     D0100PA00X+065595Y+005368               S1      
317NNAME10894       VIA   -     D0100PA00X+065995Y+005372               S3      
327USB0_DP          L42   -4          A01X+066246Y+014943X0240Y0360R090 S2      
327USB0_DN          L42   -1          A01X+066246Y+014550X0240Y0360R090 S2      
327USB0_DP          R264  -2          A01X+066634Y+014943X0180Y0200     S2      
327USB0_DN          R265  -2          A01X+066634Y+014543X0180Y0200     S2      
317GND              VIA   -     D0100PA00X+065877Y+014363               S3      
317GND              VIA   -     D0100PA00X+065877Y+015101               S3      
317USB0_DN          VIA   -     D0100PA00X+065564Y+014492               S1      
317USB0_DP          VIA   -     D0100PA00X+065564Y+014992               S1      
327USB1_DP          L43   -4          A01X+066267Y+016404X0240Y0360R090 S2      
327USB1_DN          L43   -1          A01X+066267Y+016010X0240Y0360R090 S2      
327USB1_DP          R266  -2          A01X+066665Y+016409X0180Y0200     S2      
327USB1_DN          R267  -2          A01X+066665Y+016009X0180Y0200     S2      
317GND              VIA   -     D0100PA00X+065896Y+016563               S3      
317GND              VIA   -     D0100PA00X+065897Y+015834               S3      
317USB1_DN          VIA   -     D0100PA00X+065570Y+015957               S1      
317USB1_DP          VIA   -     D0100PA00X+065570Y+016457               S1      
317GND              VIA   -     D0100PA00X+066730Y+018811               S3      
327GND              C559  -2          A01X+066969Y+019312X0440Y0540     S2      
317GND              VIA   -     D0100PA00X+066070Y+020328               S3      
317GND              VIA   -     D0100PA00X+066925Y+020332               S3      
317GND              VIA   -     D0100PA00X+066532Y+020325               S3      
317GND              VIA   -     D0100PA00X+066456Y+019502               S3      
317GND              VIA   -     D0100PA00X+066456Y+019144               S3      
327GND              CE3   -2          A01X+066546Y+020907X0630Y1190R090 S2      
317GND              VIA   -     D0100PA00X+066077Y+021495               S3      
317GND              VIA   -     D0100PA00X+066539Y+021492               S3      
327USB2_DP          L44   -4          A01X+066229Y+022824X0240Y0360R090 S2      
327USB2_DN          L44   -1          A01X+066229Y+022430X0240Y0360R090 S2      
327USB2_DP          R268  -2          A01X+066631Y+022834X0180Y0200     S2      
327USB2_DN          R269  -2          A01X+066631Y+022434X0180Y0200     S2      
317GND              VIA   -     D0100PA00X+066116Y+023549               S3      
317GND              VIA   -     D0100PA00X+065858Y+022261               S3      
317GND              VIA   -     D0100PA00X+065860Y+022977               S3      
317USB2_DP          VIA   -     D0100PA00X+065503Y+022874               S1      
317USB2_DN          VIA   -     D0100PA00X+065503Y+022374               S1      
327USB3_DP          L45   -4          A01X+066291Y+024284X0240Y0360R090 S2      
327USB3_DN          L45   -1          A01X+066291Y+023891X0240Y0360R090 S2      
327USB3_DP          R270  -2          A01X+066690Y+024285X0180Y0200     S2      
327USB3_DN          R271  -2          A01X+066690Y+023885X0180Y0200     S2      
317GND              VIA   -     D0100PA00X+066119Y+024609               S3      
317USB3_DP          VIA   -     D0100PA00X+065784Y+024341               S1      
317USB3_DN          VIA   -     D0100PA00X+065784Y+023841               S1      
327N47241340        R1105 -2          A01X+065335Y+028518X0180Y0200R090 S2      
327GND              R1105 -1          A01X+065335Y+028833X0180Y0200R090 S2      
327GND              PC22  -2          A01X+066612Y+030444X0440Y0540R180 S2      
327P1V8_NODE1       PC22  -1          A01X+065864Y+030444X0440Y0540R180 S2      
327GND              C883  -2          A01X+065827Y+031137X0180Y0200R180 S2      
327P5V_STB_NODE1    C883  -1          A01X+065512Y+031137X0180Y0200R180 S2      
317GND              VIA   -     D0100PA00X+066090Y+031152               S1      
317P1V8_NODE1       VIA   -     D0100PA00X+065627Y+029938               S3      
317P1V8_NODE1       VIA   -     D0100PA00X+065496Y+030770               S1      
317P1V8_NODE1       VIA   -     D0100PA00X+065406Y+030246               S3      
317P1V8_NODE1       VIA   -     D0100PA00X+065935Y+029881               S3      
317GND              VIA   -     D0100PA00X+065435Y+032394               S3      
317P5V_STB_NODE1    VIA   -     D0100PA00X+065512Y+031507               S3      
317P1V0_NODE1       VIA   -     D0100PA00X+065673Y+033863               S3      
327USB_NODE1_XTA2   Y3    -1          A01X+065894Y+035955X0710Y0950     S2      
317GND              VIA   -     D0100PA00X+066627Y+035913               S3      
327GND              C366  -2          A01X+066086Y+036955X0180Y0200     S2      
327USB_NODE1_XTA2   C366  -1          A01X+066401Y+036955X0180Y0200     S2      
327P3V3_USB_NODE1   C384  -2          A10X+066842Y+037309X0180Y0200R090 S1      
327GND              C384  -1          A10X+066842Y+036994X0180Y0200R090 S1      
327USB_NODE1_XTA1   C365  -1          A01X+066786Y+036955X0180Y0200R180 S2      
327P3V3_NODE1       R532  -2          A01X+065394Y+036791X0180Y0200R090 S2      
327USB_OC_PU        R532  -1          A01X+065394Y+037106X0180Y0200R090 S2      
317GND              VIA   -     D0100PA00X+066014Y+036589               S3      
317P1V05_NODE1      VIA   -     D0100PA00X+065954Y+037709               S3      
317P3V3_NODE1       VIA   -     D0100PA00X+066239Y+037704               S3      
317P3V3_NODE1       VIA   -     D0100PA00X+065394Y+036489               S3      
317USB_NODE1_XTA1   VIA   -     D0100PA00X+066893Y+036489               S1      
317USB_NODE1_XTA2   VIA   -     D0100PA00X+066363Y+036670               S1      
327P3V3_USB_NODE1   U32   -32         A01X+066789Y+038202X0070Y0470     S2      
327USB_NODE1_XTA1   U32   -31         A01X+066631Y+038202X0070Y0470     S2      
327USB_NODE1_XTA2   U32   -30         A01X+066474Y+038202X0070Y0470     S2      
327P3V3_NODE1       U32   -29         A01X+066316Y+038202X0070Y0470     S2      
327P1V05_NODE1      U32   -28         A01X+066159Y+038202X0070Y0470     S2      
327N/C              U32   -27         A01X+066001Y+038202X0070Y0470     S2      
327USB_OC_PU        U32   -26         A01X+065844Y+038202X0070Y0470     S2      
327N/C              U32   -25         A01X+065686Y+038202X0070Y0470     S2      
327USB_OC_PU        U32   -24         A01X+065529Y+038202X0070Y0470     S2      
327N/C              U32   -23         A01X+065371Y+038202X0070Y0470     S2      
327GND              C370  -2          A10X+065994Y+038366X0180Y0200R090 S1      
327P1V05_NODE1      C370  -1          A10X+065994Y+038051X0180Y0200R090 S1      
327P3V3_NODE1       C380  -2          A10X+066394Y+038051X0180Y0200R270 S1      
327GND              C380  -1          A10X+066394Y+038366X0180Y0200R270 S1      
317GND              VIA   -     D0100PA00X+065434Y+038628               S3      
317GND              VIA   -     D0100PA00X+066114Y+038628               S3      
317P3V3_USB_NODE1   VIA   -     D0100PA00X+066922Y+037749               S1      
317GND              VIA   -     D0100PA00X+065484Y+040848               S3      
317GND              VIA   -     D0100PA00X+066194Y+040838               S3      
327P1V05_NODE1      U32   -63         A01X+065371Y+041275X0070Y0470     S2      
327TP_U3TXDN4       U32   -62         A01X+065529Y+041275X0070Y0470     S2      
327TP_U3TXDP4       U32   -61         A01X+065686Y+041275X0070Y0470     S2      
327P1V05_NODE1      U32   -60         A01X+065844Y+041275X0070Y0470     S2      
327USB2_DN          U32   -59         A01X+066001Y+041275X0070Y0470     S2      
327USB2_DP          U32   -58         A01X+066159Y+041275X0070Y0470     S2      
327P3V3_NODE1       U32   -57         A01X+066316Y+041275X0070Y0470     S2      
327GND              U32   -56         A01X+066474Y+041275X0070Y0470     S2      
327GND              U32   -55         A01X+066631Y+041275X0070Y0470     S2      
327P1V05_NODE1      U32   -54         A01X+066789Y+041275X0070Y0470     S2      
327P1V05_NODE1      C372  -2          A10X+065834Y+041436X0180Y0200R090 S1      
327GND              C372  -1          A10X+065834Y+041121X0180Y0200R090 S1      
327GND              C369  -2          A10X+065354Y+041131X0180Y0200R270 S1      
327P1V05_NODE1      C369  -1          A10X+065354Y+041446X0180Y0200R270 S1      
327P3V3_NODE1       C378  -2          A10X+066324Y+041446X0180Y0200R090 S1      
327GND              C378  -1          A10X+066324Y+041131X0180Y0200R090 S1      
327P1V05_NODE1      C375  -2          A10X+066754Y+041436X0180Y0200R090 S1      
327GND              C375  -1          A10X+066754Y+041121X0180Y0200R090 S1      
317GND              VIA   -     D0100PA00X+066631Y+041774               S3      
317P1V05_NODE1      VIA   -     D0100PA00X+065830Y+041766               S3      
317P1V05_NODE1      VIA   -     D0100PA00X+065365Y+041758               S3      
317P1V05_NODE1      VIA   -     D0100PA00X+066878Y+041714               S3      
317P3V3_NODE1       VIA   -     D0100PA00X+066367Y+041800               S3      
317TP_U3TXDP4       VIA   -     D0100PA00X+065581Y+042411               S1      
317GND              VIA   -     D0100PA00X+065602Y+042786               S3      
317GND              VIA   -     D0100PA00X+066577Y+042787               S3      
317USB2_DP          VIA   -     D0100PA00X+066334Y+042560               S3      
317USB2_DN          VIA   -     D0100PA00X+065834Y+042560               S3      
317NNAME10766       VIA   -     D0100PA00X+066445Y+043574               S1      
317NNAME10741       VIA   -     D0100PA00X+065868Y+044661               S3      
327NNAME10209       R1030 -2          A01X+065486Y+047007X0180Y0200     S2      
327NNAME11113       R1030 -1          A01X+065801Y+047007X0180Y0200     S2      
317GND              VIA   -     D0100PA00X+066453Y+046343               S1      
317GND              VIA   -     D0100PA00X+066743Y+046343               S3      
317GND              VIA   -     D0100PA00X+066693Y+046813               S3      
317NNAME11113       VIA   -     D0100PA00X+066046Y+047093               S1      
317NNAME11114       VIA   -     D0100PA00X+065983Y+046516               S1      
327NNAME11099       R1031 -2          A01X+065791Y+048727X0180Y0200R180 S2      
327P3V3_STB_NODE1   R1031 -1          A01X+065476Y+048727X0180Y0200R180 S2      
327NNAME11115       R1042 -2          A01X+065794Y+048293X0180Y0200R180 S2      
327NNAME11097       R1042 -1          A01X+065479Y+048293X0180Y0200R180 S2      
327NNAME11116       R1045 -2          A01X+065794Y+047863X0180Y0200R180 S2      
327NNAME11095       R1045 -1          A01X+065479Y+047863X0180Y0200R180 S2      
317NNAME10638       VIA   -     D0100PA00X+066777Y+047799               S1      
317NNAME11115       VIA   -     D0100PA00X+066116Y+048615               S1      
317NNAME11116       VIA   -     D0100PA00X+066707Y+048361               S1      
317NNAME10635       VIA   -     D0100PA00X+066278Y+047704               S1      
327NNAME11117       R1050 -2          A01X+065801Y+049167X0180Y0200R180 S2      
327NNAME11098       R1050 -1          A01X+065486Y+049167X0180Y0200R180 S2      
317NNAME11117       VIA   -     D0100PA00X+066052Y+049286               S1      
317NNAME10269       VIA   -     D0100PA00X+066263Y+050082               S3      
327CPLD1_RSV3       R661  -2          A01X+066857Y+051701X0180Y0200R090 S2      
327CPLD1_RSV2       R660  -2          A01X+066402Y+051699X0180Y0200R090 S2      
327CPLD1_RSV1       R627  -2          A01X+065993Y+051720X0180Y0200R090 S2      
317NNAME10617       VIA   -     D0100PA00X+065424Y+051157               S1      
317NNAME11100       VIA   -     D0100PA00X+065380Y+050533               S1      
317CPLD1_RSV1       VIA   -     D0100PA00X+065993Y+051393               S1      
317CPLD1_RSV2       VIA   -     D0100PA00X+066402Y+051341               S3      
317CPLD1_RSV3       VIA   -     D0100PA00X+066857Y+051416               S1      
327NNAME11077       S1    -1          A01X+065954Y+052781X0400Y1260R270 S2      
327CPLD123_RSV3     R661  -1          A01X+066857Y+052016X0180Y0200R090 S2      
327CPLD123_RSV2     R660  -1          A01X+066402Y+052014X0180Y0200R090 S2      
327CPLD123_RSV1     R627  -1          A01X+065993Y+052035X0180Y0200R090 S2      
317P1V05_NODE1      VIA   -     D0100PA00X+066882Y+053247               S3      
317P1V05_NODE1      VIA   -     D0100PA00X+066863Y+052772               S3      
327GND              S1    -3          A01X+065954Y+054356X0400Y1260R270 S2      
317GND              VIA   -     D0100PA00X+065974Y+053602               S1      
317NNAME11077       VIA   -     D0100PA00X+066705Y+053532               S1      
327N21357373        TP4   -1          A10X+065414Y+057169X0300Y0300R270 S1      
327GND              C451  -2          A10X+066155Y+059644X0180Y0200     S1      
327P1V9_LAN2        C451  -1          A10X+065840Y+059644X0180Y0200     S1      
327GND              C449  -2          A10X+066155Y+059214X0180Y0200     S1      
327P1V9_LAN2        C449  -1          A10X+065840Y+059214X0180Y0200     S1      
317GND              VIA   -     D0100PA00X+066517Y+059594               S3      
317GND              VIA   -     D0100PA00X+066140Y+058890               S3      
327LAN2_MDI3_DN     VIA   -           A01X+066832Y+058503X0160Y0041     S2      
317P1V9_LAN2        VIA   -     D0100PA00X+065545Y+059192               S3      
327LAN2_MDI2_DP     VIA   -           A01X+066647Y+059340X0160Y0041     S2      
327GND              C450  -2          A10X+066165Y+060198X0180Y0200     S1      
327P1V9_LAN2        C450  -1          A10X+065850Y+060198X0180Y0200     S1      
327LAN2_DIS_REG10   R581  -2          A10X+066431Y+060947X0180Y0200R180 S1      
327P3V3_NODE1       R581  -1          A10X+066746Y+060947X0180Y0200R180 S1      
317GND              VIA   -     D0100PA00X+066460Y+060198               S3      
327LAN2_MDI0_DN     VIA   -           A01X+065727Y+060385X0160Y0041     S2      
327LAN2_MDI1_DP     VIA   -           A01X+066793Y+059968X0160Y0041     S2      
317LAN2_DIS_REG10   VIA   -     D0100PA00X+065898Y+061004               S1      
317P1V05_LAN2       VIA   -     D0100PA00X+065598Y+060964               S3      
317P1V9_LAN2        VIA   -     D0100PA00X+065607Y+061274               S3      
317P1V9_LAN2        VIA   -     D0100PA00X+065569Y+060176               S3      
327GND              C457  -2          A10X+066171Y+061854X0180Y0200     S1      
327P1V9_LAN2        C457  -1          A10X+065856Y+061854X0180Y0200     S1      
327GND              C443  -2          A10X+065465Y+062444X0180Y0200     S1      
327GND              C458  -2          A10X+066175Y+061454X0180Y0200     S1      
327P1V9_LAN2        C458  -1          A10X+065860Y+061454X0180Y0200     S1      
327LAN2_DIS_REG10   R582  -2          A01X+066185Y+061743X0180Y0200     S2      
327GND              R582  -1          A01X+066500Y+061743X0180Y0200     S2      
317GND              VIA   -     D0100PA00X+066487Y+061454               S3      
317GND              VIA   -     D0100PA00X+065465Y+062706               S3      
317GND              VIA   -     D0100PA00X+066761Y+061720               S3      
317LAN2_CTRL_P1V9   VIA   -     D0100PA00X+066356Y+062502               S1      
317LAN2_CTRL_P1V9   VIA   -     D0100PA00X+065960Y+062379               S3      
317P1V9_LAN2        VIA   -     D0100PA00X+065587Y+061554               S3      
327NNAME11105       R584  -2          A01X+065517Y+063384X0180Y0200R090 S2      
327GND              R584  -1          A01X+065517Y+063699X0180Y0200R090 S2      
317GND              VIA   -     D0100PA00X+065517Y+063943               S3      
317NNAME11105       VIA   -     D0100PA00X+065422Y+063143               S1      
327GND              C434  -2          A01X+065438Y+066049X0180Y0200R180 S2      
327P3V3_NODE1       R583  -2          A01X+065438Y+065507X0180Y0200R180 S2      
327NNAME11078       R575  -1          A01X+065438Y+065007X0180Y0200     S2      
327NNAME11079       R577  -1          A01X+065438Y+064507X0180Y0200     S2      
317GND              VIA   -     D0100PA00X+065697Y+066049               S3      
317P3V3_NODE1       VIA   -     D0100PA00X+065755Y+065507               S1      
327N54365625        C564  -2          A01X+066487Y+067383X0180Y0200R090 S2      
327N54365613        C563  -2          A01X+066487Y+066942X0180Y0200R270 S2      
327N54365611        C563  -1          A01X+066487Y+066627X0180Y0200R270 S2      
327N54365823        C916  -2          A10X+066450Y+067213X0180Y0200R090 S1      
327N54365821        C916  -1          A10X+066450Y+066898X0180Y0200R090 S1      
317GND              VIA   -     D0100PA00X+066800Y+067660               S3      
327N54365823        VIA   -           A10X+066920Y+067304X0260Y0260     S1      
327N54365821        VIA   -           A10X+065387Y+066898X0260Y0260     S1      
327N54365613        VIA   -           A01X+065805Y+067212X0300Y0300     S2      
327N54365835        VIA   -           A10X+065822Y+067180X0260Y0260     S1      
317N54365611        VIA   -     D0100PA00X+065998Y+066627               S1      
327GND              C564  -1          A01X+066487Y+067698X0180Y0200R090 S2      
327N54365835        C919  -2          A10X+066089Y+067660X0180Y0200R180 S1      
327GND              C919  -1          A10X+066404Y+067660X0180Y0200R180 S1      
327GND              C918  -2          A10X+066103Y+068380X0180Y0200R090 S1      
327P3V3_NODE1       C918  -1          A10X+066103Y+068065X0180Y0200R090 S1      
327N54365542        R1303 -2          A01X+065968Y+068491X0180Y0200R090 S2      
327GND              R1303 -1          A01X+065968Y+068806X0180Y0200R090 S2      
317GND              VIA   -     D0100PA00X+065625Y+068328               S3      
317GND              VIA   -     D0100PA00X+066304Y+068806               S3      
317P3V3_NODE1       VIA   -     D0100PA00X+066505Y+068065               S3      
317N54365542        VIA   -     D0100PA00X+065734Y+069029               S1      
327N54365625        VIA   -           A01X+065837Y+067777X0300Y0300     S2      
317NNAME11022       VIA   -     D0100PA00X+065561Y+070631               S3      
317NNAME11066       VIA   -     D0100PA00X+065651Y+070119               S3      
317GND              VIA   -     D0100PA00X+065451Y+072067               S3      
317P3V3_NODE1       VIA   -     D0100PA00X+065732Y+072358               S3      
317NNAME10727       VIA   -     D0100PA00X+065405Y+071809               S3      
317NNAME11016       VIA   -     D0100PA00X+065665Y+071306               S3      
327NNAME11112       VIA   -           A01X+065903Y+071005X0300Y0300     S2      
317JTAG_CPLD3_TMS   VIA   -     D0100PA00X+065920Y+072145               S3      
317I2C_PDB_SCL      VIA   -     D0100PA00X+065930Y+073412               S1      
317I2C_PDB_SDA      VIA   -     D0100PA00X+065400Y+073640               S3      
317GND              VIA   -     D0100PA00X+065666Y+073622               S3      
317P3V3_NODE1       VIA   -     D0100PA00X+065557Y+072867               S3      
317JTAG_CPLD3_TDO   VIA   -     D0100PA00X+065757Y+073041               S3      
317JTAG_CPLD3_TCK   VIA   -     D0100PA00X+065886Y+072738               S3      
317JTAG_CPLD3_TDI   VIA   -     D0100PA00X+065600Y+073240               S3      
327GND              C610  -2          A10X+065666Y+073936X0180Y0200R270 S1      
327I2C_PDB_R_SCL    C610  -1          A10X+065666Y+074251X0180Y0200R270 S1      
327I2C_PDB_R_SCL    R841  -2          A01X+066066Y+074251X0180Y0200R270 S2      
327I2C_PDB_SCL      R841  -1          A01X+066066Y+073936X0180Y0200R270 S2      
327I2C_PDB_R_SDA    R844  -2          A01X+065466Y+074251X0180Y0200R270 S2      
327I2C_PDB_SDA      R844  -1          A01X+065466Y+073936X0180Y0200R270 S2      
317I2C_PDB_R_SCL    VIA   -     D0100PA00X+065750Y+076150               S1      
327NNAME11118       TP11  -1          A10X+065748Y+078281X0300Y0300     S1      
317N/C              VIA   -     D0100PA00X+066446Y+078589               S3      
327NNAME11086       VIA   -           A10X+065697Y+077276X0260Y0260     S1      
317NNAME11118       VIA   -     D0100PA00X+065701Y+078604               S3      
327NNAME11118       J18   -A19        A10X+065754Y+080787X0300Y1660R180 S1      
327NNAME11086       J18   -A18        A10X+066148Y+080787X0300Y1660R180 S1      
327GND              J18   -A17        A10X+066542Y+080787X0300Y1660R180 S1      
327N/C              J18   -A16        A10X+066935Y+080787X0300Y1660R180 S1      
327NNAME11111       J18   -B19        A01X+065754Y+080787X0300Y1660R180 S2      
327GND              J18   -B18        A01X+066148Y+080787X0300Y1660R180 S2      
327N/C              J18   -B17        A01X+066542Y+080590X0300Y1260R180 S2      
327GND37            J18   -B16        A01X+066935Y+080787X0300Y1660R180 S2      
317GND              VIA   -     D0100PA00X+066148Y+079148               S3      
317GND              VIA   -     D0100PA00X+066542Y+079148               S3      
317GND              J27   -2    D0460PA00X+067996Y+002880               S0      
317JTAG_CPLD3_TCK   J27   -1    D0460PA00X+067996Y+003880               S0      
327JTAG_CPLD3_TDO   R1199 -2          A01X+066999Y+004754X0180Y0200R090 S2      
327NNAME10863       R1199 -1          A01X+066999Y+005069X0180Y0200R090 S2      
327JTAG_CPLD3_TCK   R1200 -2          A01X+067593Y+004754X0180Y0200R090 S2      
327NNAME10895       R1200 -1          A01X+067593Y+005069X0180Y0200R090 S2      
327JTAG_CPLD3_TCK   R1212 -2          A01X+067993Y+004754X0180Y0200R090 S2      
327GND              R1212 -1          A01X+067993Y+005069X0180Y0200R090 S2      
317GND              VIA   -     D0100PA00X+067993Y+005388               S3      
317NNAME10895       VIA   -     D0100PA00X+067593Y+005378               S3      
317NNAME10863       VIA   -     D0100PA00X+066999Y+005367               S1      
317GND              VIA   -     D0100PA00X+067098Y+007706               S3      
317GND              H7    -1    D1500UA00X+068898Y+010532               S0      
317GND              VIA   -     D0100PA00X+067181Y+010647               S3      
327USB0_L_DP        L42   -3          A01X+067348Y+014943X0240Y0360R090 S2      
327USB0_L_DN        L42   -2          A01X+067348Y+014550X0240Y0360R090 S2      
327USB0_L_DP        R264  -1          A01X+066949Y+014943X0180Y0200     S2      
327USB0_L_DN        R265  -1          A01X+066949Y+014543X0180Y0200     S2      
327USB1_L_DP        L43   -3          A01X+067370Y+016404X0240Y0360R090 S2      
327USB1_L_DN        L43   -2          A01X+067370Y+016010X0240Y0360R090 S2      
327USB0_L_DP        U53   -4          A01X+068381Y+015854X0160Y0520R180 S2      
327USB1_L_DP        U53   -3          A01X+068381Y+016818X0160Y0520R180 S2      
327USB1_L_DP        R266  -1          A01X+066980Y+016409X0180Y0200     S2      
327USB1_L_DN        R267  -1          A01X+066980Y+016009X0180Y0200     S2      
327GND              C535  -2          A01X+067202Y+018526X0180Y0200     S2      
327P5V_NODE1        C535  -1          A01X+067517Y+018526X0180Y0200     S2      
317GND              VIA   -     D0100PA00X+067028Y+018811               S3      
317P5V_NODE1        VIA   -     D0100PA00X+067659Y+018820               S3      
317P5V_NODE1        VIA   -     D0100PA00X+068010Y+018818               S3      
327P5V_NODE1        C559  -1          A01X+067717Y+019312X0440Y0540     S2      
317USBPWR_P1        VIA   -     D0100PA00X+068022Y+020073               S3      
317USBPWR_P1        VIA   -     D0100PA00X+067865Y+020348               S3      
317USBPWR_P1        VIA   -     D0100PA00X+068177Y+020351               S3      
317P5V_NODE1        VIA   -     D0100PA00X+068214Y+019121               S3      
317P5V_NODE1        VIA   -     D0100PA00X+068214Y+019462               S3      
327USBPWR_P1        CE3   -1          A01X+068278Y+020907X0630Y1190R090 S2      
317USBPWR_P1        VIA   -     D0100PA00X+068031Y+021736               S3      
317USBPWR_P1        VIA   -     D0100PA00X+067875Y+021491               S3      
317USBPWR_P1        VIA   -     D0100PA00X+068187Y+021494               S3      
317GND              VIA   -     D0100PA00X+066932Y+021499               S3      
327USB2_L_DP        L44   -3          A01X+067332Y+022824X0240Y0360R090 S2      
327USB2_L_DN        L44   -2          A01X+067332Y+022430X0240Y0360R090 S2      
327USB2_L_DP        R268  -1          A01X+066946Y+022834X0180Y0200     S2      
327USB2_L_DN        R269  -1          A01X+066946Y+022434X0180Y0200     S2      
327USB3_L_DP        L45   -3          A01X+067393Y+024284X0240Y0360R090 S2      
327USB3_L_DN        L45   -2          A01X+067393Y+023891X0240Y0360R090 S2      
327USB2_L_DP        U54   -4          A01X+068384Y+023734X0160Y0520R180 S2      
327USB3_L_DP        U54   -3          A01X+068384Y+024699X0160Y0520R180 S2      
327USB3_L_DP        R270  -1          A01X+067005Y+024285X0180Y0200     S2      
327USB3_L_DN        R271  -1          A01X+067005Y+023885X0180Y0200     S2      
317GND              VIA   -     D0100PA00X+067113Y+030558               S3      
317GND              VIA   -     D0100PA00X+067117Y+030255               S3      
327USB_NODE1_XTA1   Y3    -2          A01X+067390Y+035955X0710Y0950     S2      
317NNAME11091       VIA   -     D0100PA00X+067959Y+035283               S1      
317NNAME11069       VIA   -     D0100PA00X+067943Y+035001               S3      
327GND              C383  -2          A10X+067252Y+036994X0180Y0200R270 S1      
327P3V3_USB_NODE1   C383  -1          A10X+067252Y+037309X0180Y0200R270 S1      
327GND              C365  -2          A01X+067101Y+036955X0180Y0200R180 S2      
327GND              R526  -2          A01X+067826Y+036960X0180Y0200R180 S2      
327USB_NODE1_RREF   R526  -1          A01X+067511Y+036960X0180Y0200R180 S2      
317GND              VIA   -     D0100PA00X+067275Y+036616               S3      
317GND              VIA   -     D0100PA00X+067955Y+037287               S3      
317USB_NODE1_RREF   VIA   -     D0100PA00X+067708Y+037512               S1      
327GND              U32   -34         A01X+067104Y+038167X0070Y0400     S2      
327USB_NODE1_RREF   U32   -33         A01X+066946Y+038202X0070Y0470     S2      
327GND              U32   -39         A01X+067381Y+039109X0070Y0470R090 S2      
327GND              U32   -38         A01X+067381Y+038951X0070Y0470R090 S2      
327P1V05_NODE1      U32   -37         A01X+067381Y+038794X0070Y0470R090 S2      
327TP_U3TXDN1       U32   -36         A01X+067381Y+038636X0070Y0470R090 S2      
327TP_U3TXDP1       U32   -35         A01X+067416Y+038479X0070Y0400R090 S2      
327GND              C368  -2          A10X+067236Y+038819X0180Y0200R180 S1      
327P1V05_NODE1      C368  -1          A10X+067551Y+038819X0180Y0200R180 S1      
327P3V3_NODE1       C379  -2          A10X+067551Y+039239X0180Y0200     S1      
327GND              C379  -1          A10X+067236Y+039239X0180Y0200     S1      
317GND              VIA   -     D0100PA00X+066954Y+038628               S3      
317GND              VIA   -     D0100PA00X+067810Y+038992               S3      
317GND              VIA   -     D0100PA00X+067424Y+037936               S3      
317P1V05_NODE1      VIA   -     D0100PA00X+067795Y+038721               S3      
317P3V3_NODE1       VIA   -     D0100PA00X+067899Y+039266               S3      
327P3V3_NODE1       U32   -49         A01X+067381Y+040683X0070Y0470R090 S2      
327GND              U32   -48         A01X+067381Y+040526X0070Y0470R090 S2      
327GND              U32   -47         A01X+067381Y+040368X0070Y0470R090 S2      
327P1V05_NODE1      U32   -46         A01X+067381Y+040211X0070Y0470R090 S2      
327TP_U3TXDN2       U32   -45         A01X+067381Y+040054X0070Y0470R090 S2      
327TP_U3TXDP2       U32   -44         A01X+067381Y+039896X0070Y0470R090 S2      
327P1V05_NODE1      U32   -43         A01X+067381Y+039739X0070Y0470R090 S2      
327USB0_DN          U32   -42         A01X+067381Y+039581X0070Y0470R090 S2      
327USB0_DP          U32   -41         A01X+067381Y+039424X0070Y0470R090 S2      
327P3V3_NODE1       U32   -40         A01X+067381Y+039266X0070Y0470R090 S2      
327P1V05_NODE1      C373  -2          A10X+067551Y+040179X0180Y0200     S1      
327GND              C373  -1          A10X+067236Y+040179X0180Y0200     S1      
327GND              C377  -2          A10X+067236Y+040679X0180Y0200R180 S1      
327P3V3_NODE1       C377  -1          A10X+067551Y+040679X0180Y0200R180 S1      
327P1V05_NODE1      C371  -2          A10X+067551Y+039759X0180Y0200     S1      
327GND              C371  -1          A10X+067236Y+039759X0180Y0200     S1      
317GND              VIA   -     D0100PA00X+066944Y+039518               S3      
317GND              VIA   -     D0100PA00X+066944Y+040848               S3      
317GND              VIA   -     D0100PA00X+066954Y+040278               S3      
317GND              VIA   -     D0100PA00X+067834Y+040519               S3      
317P1V05_NODE1      VIA   -     D0100PA00X+067914Y+039799               S3      
317P1V05_NODE1      VIA   -     D0100PA00X+068002Y+040314               S3      
317P3V3_NODE1       VIA   -     D0100PA00X+067884Y+040779               S3      
327TP_U3TXDN3       U32   -53         A01X+066946Y+041275X0070Y0470     S2      
327TP_U3TXDP3       U32   -52         A01X+067104Y+041310X0070Y0400     S2      
327USB1_DN          U32   -51         A01X+067416Y+040998X0070Y0400R090 S2      
327USB1_DP          U32   -50         A01X+067381Y+040841X0070Y0470R090 S2      
317TP_U3TXDP3       VIA   -     D0100PA00X+067337Y+041662               S1      
317TP_U3TXDN3       VIA   -     D0100PA00X+067106Y+042630               S1      
327GND              C793  -2          A10X+068323Y+045490X0280Y0320R180 S1      
317GND              VIA   -     D0100PA00X+068313Y+045133               S3      
317GND              VIA   -     D0100PA00X+068023Y+045143               S3      
317NNAME10711       VIA   -     D0100PA00X+067266Y+044101               S3      
317NNAME11119       VIA   -     D0100PA00X+067374Y+044989               S1      
317NNAME10842       VIA   -     D0100PA00X+068276Y+044483               S1      
317NNAME10114       VIA   -     D0100PA00X+067707Y+044482               S1      
327P3V3_STB_NODE1   C792  -1          A10X+068340Y+046803X0280Y0320R090 S1      
327GND              C792  -2          A10X+067760Y+046803X0280Y0320R090 S1      
327P3V3_STB_NODE1   C793  -1          A10X+068323Y+046070X0280Y0320R180 S1      
327NNAME11113       U102  -D10        A01X+067721Y+046994X0193Y0193R180 S2      
327NNAME11114       U102  -D9         A01X+068114Y+046994X0193Y0193R180 S2      
327NNAME11054       U102  -C10        A01X+067721Y+046601X0193Y0193R180 S2      
327NNAME11063       U102  -C9         A01X+068114Y+046601X0193Y0193R180 S2      
327NNAME10691       U102  -B10        A01X+067721Y+046207X0193Y0193R180 S2      
327NNAME10562       U102  -B9         A01X+068114Y+046207X0193Y0193R180 S2      
327NNAME10503       U102  -A10        A01X+067721Y+045813X0193Y0193R180 S2      
327NNAME10741       U102  -A9         A01X+068114Y+045813X0193Y0193R180 S2      
317GND              VIA   -     D0100PA00X+067043Y+046353               S3      
317GND              VIA   -     D0100PA00X+066973Y+046803               S3      
317GND              VIA   -     D0100PA00X+067263Y+046803               S3      
317NNAME11063       VIA   -     D0100PA00X+067918Y+046404               S3      
317NNAME10503       VIA   -     D0100PA00X+067219Y+045722               S3      
317NNAME11054       VIA   -     D0100PA00X+067435Y+046384               S3      
317NNAME11003       VIA   -     D0100PA00X+068311Y+046404               S3      
327P3V3_STB_NODE1   C784  -1          A10X+067946Y+048583X0280Y0320R090 S1      
327GND              C784  -2          A10X+067366Y+048583X0280Y0320R090 S1      
327P3V3_STB_NODE1   C785  -1          A10X+067946Y+048033X0280Y0320R090 S1      
327GND              C785  -2          A10X+067366Y+048033X0280Y0320R090 S1      
327P3V3_STB_NODE1   C790  -1          A10X+067946Y+047483X0280Y0320R090 S1      
327GND              C790  -2          A10X+067366Y+047483X0280Y0320R090 S1      
327NNAME11099       U102  -H10        A01X+067721Y+048569X0193Y0193R180 S2      
327NNAME11117       U102  -H9         A01X+068114Y+048569X0193Y0193R180 S2      
327NNAME11116       U102  -G10        A01X+067721Y+048176X0193Y0193R180 S2      
327NNAME11115       U102  -G9         A01X+068114Y+048176X0193Y0193R180 S2      
327NNAME10638       U102  -F10        A01X+067721Y+047782X0193Y0193R180 S2      
327NNAME10635       U102  -F9         A01X+068114Y+047782X0193Y0193R180 S2      
327NNAME11096       U102  -E10        A01X+067721Y+047388X0193Y0193R180 S2      
327NNAME10627       U102  -E9         A01X+068114Y+047388X0193Y0193R180 S2      
317NNAME10319       VIA   -     D0100PA00X+068311Y+048372               S3      
317NNAME10640       VIA   -     D0100PA00X+068311Y+047194               S3      
317CPLD_EXT_RST_N   VIA   -     D0100PA00X+068311Y+047979               S3      
327NNAME10269       U102  -K10        A01X+067721Y+049357X0193Y0193R180 S2      
327NNAME10763       U102  -K9         A01X+068114Y+049357X0193Y0193R180 S2      
327NNAME11100       U102  -J10        A01X+067721Y+048963X0193Y0193R180 S2      
327NNAME10800       U102  -J9         A01X+068114Y+048963X0193Y0193R180 S2      
317NNAME10800       VIA   -     D0100PA00X+067930Y+049147               S1      
317CPLD1_RSV1       VIA   -     D0100PA00X+068488Y+049739               S3      
317NNAME10238       VIA   -     D0100PA00X+068311Y+048766               S3      
317NNAME10763       VIA   -     D0100PA00X+067416Y+050366               S1      
317NNAME10527       VIA   -     D0100PA00X+067845Y+050844               S3      
317NNAME11101       VIA   -     D0100PA00X+068079Y+050452               S3      
327P1V05_NODE1      R1122 -2          A01X+067225Y+053247X0180Y0200     S2      
327N41777080        R1122 -1          A01X+067540Y+053247X0180Y0200     S2      
327P1V05_NODE1      R116  -2          A01X+067231Y+052772X0180Y0200R270 S2      
327NNAME10617       R116  -1          A01X+067231Y+052457X0180Y0200R270 S2      
327N41777073        R93   -2          A01X+067816Y+051938X0180Y0200R180 S2      
327NNAME10617       R93   -1          A01X+067501Y+051938X0180Y0200R180 S2      
327N41777073        Q41   -E          A01X+068095Y+052454X0320Y0360R090 S2      
327N41777080        Q41   -B          A01X+068095Y+053202X0320Y0360R090 S2      
317N41777080        VIA   -     D0100PA00X+067716Y+052942               S1      
317N41777073        VIA   -     D0100PA00X+067504Y+052458               S1      
327NNAME11077       C797  -2          A01X+067225Y+054075X0180Y0200     S2      
327GND              C797  -1          A01X+067540Y+054075X0180Y0200     S2      
327P3V3_STB_NODE1   R1053 -2          A01X+067540Y+053675X0180Y0200R180 S2      
327NNAME11077       R1053 -1          A01X+067225Y+053675X0180Y0200R180 S2      
327NNAME11077       R1054 -2          A01X+067225Y+054475X0180Y0200     S2      
327NNAME11120       R1054 -1          A01X+067540Y+054475X0180Y0200     S2      
327NNAME11101       R1066 -2          A01X+067225Y+054875X0180Y0200     S2      
327NNAME11120       R1066 -1          A01X+067540Y+054875X0180Y0200     S2      
327NNAME11101       U106  -4          A01X+068288Y+054707X0180Y0520R090 S2      
327P3V3_STB_NODE1   U106  -5          A01X+068288Y+053959X0180Y0520R090 S2      
317GND              VIA   -     D0100PA00X+067832Y+054075               S3      
317P3V3_STB_NODE1   VIA   -     D0100PA00X+068462Y+053592               S3      
317P3V3_STB_NODE1   VIA   -     D0100PA00X+067822Y+053675               S3      
317P5V_NODE1        VIA   -     D0100PA00X+067836Y+055743               S3      
317P5V_NODE1        VIA   -     D0100PA00X+067395Y+055731               S3      
317P5V_NODE1        VIA   -     D0100PA00X+067785Y+056252               S3      
317P5V_NODE1        VIA   -     D0100PA00X+067370Y+056252               S3      
317P5V_NODE1        VIA   -     D0100PA00X+067773Y+056771               S3      
317P5V_NODE1        VIA   -     D0100PA00X+067359Y+056770               S3      
327LAN2_MDI2_DN     VIA   -           A01X+067513Y+059169X0160Y0041     S2      
317P3V3_NODE1       VIA   -     D0100PA00X+067094Y+061207               S3      
327P1V9_LAN2        U138  -3          A01X+068339Y+062615X0320Y0610     S2      
327LAN2_MDI0_DN     U138  -2          A01X+067839Y+062615X0320Y0610     S2      
327LAN2_MDI0_DP     U138  -1          A01X+067339Y+062615X0320Y0610     S2      
327GND              C521  -2          A10X+068347Y+062577X0180Y0200R270 S1      
327P1V9_LAN2        C521  -1          A10X+068347Y+062892X0180Y0200R270 S1      
317P1V9_LAN2        VIA   -     D0100PA00X+068372Y+063173               S3      
327LAN2_P1_P        U138  -24         A01X+067339Y+066139X0320Y0610     S2      
327LAN2_P1_N        U138  -23         A01X+067839Y+066139X0320Y0610     S2      
327LAN2_P1_R        U138  -22         A01X+068339Y+066139X0320Y0610     S2      
317GND              VIA   -     D0100PA00X+068131Y+066667               S3      
317GND              VIA   -     D0100PA00X+067140Y+066615               S3      
317LAN2_P1_N        VIA   -     D0100PA00X+067839Y+066842               S1      
317LAN2_P1_P        VIA   -     D0100PA00X+067339Y+066842               S1      
317GND              VIA   -     D0100PA00X+066939Y+069541               S3      
317GND              H6    -1    D1500UA00X+068898Y+071949               S0      
317GND              VIA   -     D0100PA00X+067263Y+072075               S3      
317JTAG_CPLD2_TDI   VIA   -     D0100PA00X+067510Y+074930               S3      
317JTAG_CPLD2_TMS   VIA   -     D0100PA00X+067271Y+074624               S3      
317JTAG_CPLD2_TDO   VIA   -     D0100PA00X+067250Y+074918               S3      
317P3V3_NODE1       VIA   -     D0100PA00X+068450Y+078667               S3      
317N/C              VIA   -     D0100PA00X+067639Y+077844               S3      
317N/C              VIA   -     D0100PA00X+067749Y+078211               S3      
317N/C              VIA   -     D0100PA00X+067329Y+078286               S3      
317N/C              VIA   -     D0100PA00X+067723Y+078645               S3      
317N/C              VIA   -     D0100PA00X+066932Y+078385               S3      
317GND2             VIA   -     D0100PA00X+068148Y+077739               S1      
317GND36            VIA   -     D0100PA00X+068116Y+078346               S1      
317GND37            VIA   -     D0100PA00X+066981Y+078672               S1      
317GND3             VIA   -     D0100PA00X+067250Y+077958               S1      
327GND3             J18   -A15        A10X+067329Y+080787X0300Y1660R180 S1      
327N/C              J18   -A14        A10X+067723Y+080787X0300Y1660R180 S1      
327N/C              J18   -A13        A10X+068116Y+080787X0300Y1660R180 S1      
327GND2             J18   -A12        A10X+068510Y+080787X0300Y1660R180 S1      
327N/C              J18   -B15        A01X+067329Y+080787X0300Y1660R180 S2      
327N/C              J18   -B14        A01X+067723Y+080787X0300Y1660R180 S2      
327GND36            J18   -B13        A01X+068116Y+080787X0300Y1660R180 S2      
327P3V3_NODE1       J18   -B12        A01X+068510Y+080787X0300Y1660R180 S2      
317P3V3_NODE1       VIA   -     D0100PA00X+068352Y+078908               S3      
317P3V3_NODE1       VIA   -     D0100PA00X+068352Y+079208               S3      
317GND              VIA   -     D0100PA00X+068816Y+006446               S3      
317GND              VIA   -     D0100PA00X+068950Y+012044               S3      
327USBPWR_P0        D9    -C          A01X+069720Y+014014X0220Y0240R180 S2      
327GND              D9    -A          A01X+069385Y+014014X0220Y0240     S2      
317GND              VIA   -     D0100PA00X+069115Y+014014               S3      
317USBPWR_P0        VIA   -     D0100PA00X+069815Y+013679               S3      
327GND              C558  -2          A01X+069396Y+014507X0180Y0200     S2      
327USBPWR_P0        C558  -1          A01X+069711Y+014507X0180Y0200     S2      
327GND              C557  -2          A01X+069396Y+014957X0180Y0200     S2      
327USBPWR_P0        C557  -1          A01X+069711Y+014957X0180Y0200     S2      
317GND              VIA   -     D0100PA00X+069128Y+014957               S3      
317GND              VIA   -     D0100PA00X+069131Y+014507               S3      
317USBPWR_P0        VIA   -     D0100PA00X+068755Y+015423               S1      
317USBPWR_P0        VIA   -     D0100PA00X+069999Y+014963               S3      
317USBPWR_P0        VIA   -     D0100PA00X+070006Y+014498               S3      
327USB0_L_DN        U53   -6          A01X+069129Y+015854X0160Y0520R180 S2      
327USBPWR_P0        U53   -5          A01X+068755Y+015854X0160Y0520R180 S2      
327GND              U53   -2          A01X+068755Y+016818X0160Y0520R180 S2      
327USB1_L_DN        U53   -1          A01X+069129Y+016818X0160Y0520R180 S2      
317GND              VIA   -     D0100PA00X+068757Y+017229               S3      
317P5V_NODE1        VIA   -     D0100PA00X+069352Y+018638               S3      
317P5V_NODE1        VIA   -     D0100PA00X+069785Y+018644               S3      
327USBPWR_P1        FS4   -2          A01X+069523Y+020179X0400Y0710R090 S2      
327P5V_NODE1        FS4   -1          A01X+069523Y+019037X0400Y0710R090 S2      
317USBPWR_P1        VIA   -     D0100PA00X+068982Y+020016               S3      
317USBPWR_P1        VIA   -     D0100PA00X+068982Y+020349               S3      
317P5V_NODE1        VIA   -     D0100PA00X+068948Y+019114               S3      
317P5V_NODE1        VIA   -     D0100PA00X+068948Y+019462               S1      
327USBPWR_P1        D10   -C          A01X+069508Y+021213X0220Y0240     S2      
327GND              D10   -A          A01X+069843Y+021213X0220Y0240R180 S2      
327GND              C560  -2          A01X+069805Y+021687X0180Y0200R180 S2      
327USBPWR_P1        C560  -1          A01X+069490Y+021687X0180Y0200R180 S2      
317USBPWR_P1        VIA   -     D0100PA00X+069197Y+021682               S3      
317USBPWR_P1        VIA   -     D0100PA00X+069169Y+021210               S3      
317USBPWR_P1        VIA   -     D0100PA00X+069354Y+020572               S3      
317USBPWR_P1        VIA   -     D0100PA00X+069780Y+020588               S3      
327GND              C561  -2          A01X+069805Y+022137X0180Y0200R180 S2      
327USBPWR_P1        C561  -1          A01X+069490Y+022137X0180Y0200R180 S2      
317USBPWR_P1        VIA   -     D0100PA00X+069201Y+022116               S3      
317USBPWR_P1        VIA   -     D0100PA00X+068758Y+023303               S3      
327USB2_L_DN        U54   -6          A01X+069132Y+023734X0160Y0520R180 S2      
327USBPWR_P1        U54   -5          A01X+068758Y+023734X0160Y0520R180 S2      
327GND              U54   -2          A01X+068758Y+024699X0160Y0520R180 S2      
327USB3_L_DN        U54   -1          A01X+069132Y+024699X0160Y0520R180 S2      
317GND              VIA   -     D0100PA00X+068758Y+025177               S3      
317GND              VIA   -     D0100PA00X+068986Y+039213               S3      
317USB0_DP          VIA   -     D0100PA00X+068669Y+039252               S3      
317TP_U3TXDN1       VIA   -     D0100PA00X+068787Y+038678               S1      
317TP_U3TXDP1       VIA   -     D0100PA00X+068812Y+038104               S1      
317GND              VIA   -     D0100PA00X+068712Y+040700               S3      
317GND              VIA   -     D0100PA00X+068986Y+039814               S3      
317USB0_DN          VIA   -     D0100PA00X+068669Y+039752               S3      
317USB1_DP          VIA   -     D0100PA00X+068953Y+040784               S3      
317TP_U3TXDN2       VIA   -     D0100PA00X+068586Y+040397               S1      
317TP_U3TXDP2       VIA   -     D0100PA00X+069104Y+040174               S1      
317GND              VIA   -     D0100PA00X+068673Y+041335               S3      
317USB1_DN          VIA   -     D0100PA00X+068953Y+041284               S3      
327GND              C786  -2          A10X+068913Y+045497X0280Y0320R180 S1      
327P3V3_STB_NODE1   C791  -1          A10X+069483Y+046434X0280Y0320     S1      
327GND              C791  -2          A10X+069483Y+047014X0280Y0320     S1      
327P3V3_STB_NODE1   C786  -1          A10X+068913Y+046077X0280Y0320R180 S1      
327NNAME10640       U102  -D8         A01X+068508Y+046994X0193Y0193R180 S2      
327GND              U102  -D7         A01X+068902Y+046994X0193Y0193R180 S2      
327P3V3_STB_NODE1   U102  -D6         A01X+069296Y+046994X0193Y0193R180 S2      
327GND              U102  -D5         A01X+069689Y+046994X0193Y0193R180 S2      
327NNAME11003       U102  -C8         A01X+068508Y+046601X0193Y0193R180 S2      
327NNAME10757       U102  -C7         A01X+068902Y+046601X0193Y0193R180 S2      
327NNAME11121       U102  -C6         A01X+069296Y+046601X0193Y0193R180 S2      
327NNAME10711       U102  -C5         A01X+069689Y+046601X0193Y0193R180 S2      
327NNAME10900       U102  -B8         A01X+068508Y+046207X0193Y0193R180 S2      
327NNAME10782       U102  -B7         A01X+068902Y+046207X0193Y0193R180 S2      
327NNAME10842       U102  -B6         A01X+069296Y+046207X0193Y0193R180 S2      
327NNAME10044       U102  -B5         A01X+069689Y+046207X0193Y0193R180 S2      
327NNAME11119       U102  -A8         A01X+068508Y+045813X0193Y0193R180 S2      
327NNAME10114       U102  -A7         A01X+068902Y+045813X0193Y0193R180 S2      
327NNAME10047       U102  -A6         A01X+069296Y+045813X0193Y0193R180 S2      
327NNAME10702       U102  -A5         A01X+069689Y+045813X0193Y0193R180 S2      
317GND              VIA   -     D0100PA00X+068705Y+046798               S3      
317GND              VIA   -     D0100PA00X+069886Y+046798               S3      
317NNAME10757       VIA   -     D0100PA00X+068713Y+046413               S3      
327NNAME11121       VIA   -           A10X+069607Y+045890X0260Y0260     S1      
317NNAME11121       VIA   -     D0100PA00X+069107Y+046406               S3      
327NNAME11122       VIA   -           A10X+070059Y+046227X0260Y0260     S1      
317P3V3_STB_NODE1   VIA   -     D0100PA00X+069099Y+046798               S3      
327P3V3_STB_NODE1   C787  -1          A10X+069508Y+048091X0280Y0320     S1      
327GND              C787  -2          A10X+069508Y+048671X0280Y0320     S1      
327GND              C788  -2          A10X+069776Y+047549X0280Y0320R090 S1      
327P3V3_STB_NODE1   C789  -1          A10X+068672Y+047504X0280Y0320R270 S1      
327GND              C789  -2          A10X+069252Y+047504X0280Y0320R270 S1      
327NNAME10238       U102  -H8         A01X+068508Y+048569X0193Y0193R180 S2      
327NNAME10771       U102  -H7         A01X+068902Y+048569X0193Y0193R180 S2      
327NNAME10775       U102  -H6         A01X+069296Y+048569X0193Y0193R180 S2      
327NNAME11123       U102  -H5         A01X+069689Y+048569X0193Y0193R180 S2      
327NNAME10319       U102  -G8         A01X+068508Y+048176X0193Y0193R180 S2      
327GND              U102  -G7         A01X+068902Y+048176X0193Y0193R180 S2      
327P3V3_STB_NODE1   U102  -G6         A01X+069296Y+048176X0193Y0193R180 S2      
327GND              U102  -G5         A01X+069689Y+048176X0193Y0193R180 S2      
327CPLD_EXT_RST_N   U102  -F8         A01X+068508Y+047782X0193Y0193R180 S2      
327P3V3_STB_NODE1   U102  -F7         A01X+068902Y+047782X0193Y0193R180 S2      
327GND              U102  -F6         A01X+069296Y+047782X0193Y0193R180 S2      
327GND              U102  -F5         A01X+069689Y+047782X0193Y0193R180 S2      
327NNAME10541       U102  -E8         A01X+068508Y+047388X0193Y0193R180 S2      
327P3V3_STB_NODE1   U102  -E7         A01X+068902Y+047388X0193Y0193R180 S2      
327GND              U102  -E6         A01X+069296Y+047388X0193Y0193R180 S2      
327GND              U102  -E5         A01X+069689Y+047388X0193Y0193R180 S2      
317GND              VIA   -     D0100PA00X+069886Y+047191               S3      
317GND              VIA   -     D0100PA00X+069099Y+047191               S3      
317GND              VIA   -     D0100PA00X+069099Y+047979               S3      
317GND              VIA   -     D0100PA00X+068705Y+048372               S3      
317GND              VIA   -     D0100PA00X+069886Y+047979               S3      
317GND              VIA   -     D0100PA00X+069886Y+048372               S3      
317P3V3_STB_NODE1   VIA   -     D0100PA00X+068705Y+047979               S3      
317P3V3_STB_NODE1   VIA   -     D0100PA00X+069099Y+048372               S3      
317P3V3_STB_NODE1   VIA   -     D0100PA00X+068705Y+047191               S3      
317CPLD_ROW_LATCH   VIA   -     D0100PA00X+069868Y+048752               S3      
327CPLD1_RSV1       U102  -K8         A01X+068508Y+049357X0193Y0193R180 S2      
327CPLD1_RSV2       U102  -K7         A01X+068902Y+049357X0193Y0193R180 S2      
327CPLD1_RSV3       U102  -K6         A01X+069296Y+049357X0193Y0193R180 S2      
327NNAME10546       U102  -K5         A01X+069689Y+049357X0193Y0193R180 S2      
327NNAME11101       U102  -J8         A01X+068508Y+048963X0193Y0193R180 S2      
327NNAME11055       U102  -J7         A01X+068902Y+048963X0193Y0193R180 S2      
327NNAME11124       U102  -J6         A01X+069296Y+048963X0193Y0193R180 S2      
327NNAME10545       U102  -J5         A01X+069689Y+048963X0193Y0193R180 S2      
317NNAME10775       VIA   -     D0100PA00X+069099Y+048766               S3      
317NNAME10771       VIA   -     D0100PA00X+068705Y+048766               S3      
317CPLD1_RSV2       VIA   -     D0100PA00X+068902Y+049728               S1      
317CPLD1_RSV3       VIA   -     D0100PA00X+069296Y+050211               S3      
317NNAME11123       VIA   -     D0100PA00X+069482Y+049893               S1      
327NNAME11124       R1037 -2          A01X+069116Y+051276X0180Y0200R090 S2      
327GND              R1037 -1          A01X+069116Y+051591X0180Y0200R090 S2      
327NNAME11124       R1036 -2          A01X+068666Y+051276X0180Y0200R090 S2      
327P3V3_STB_NODE1   R1036 -1          A01X+068666Y+051591X0180Y0200R090 S2      
317GND              VIA   -     D0100PA00X+069116Y+051868               S3      
317NNAME11099       VIA   -     D0100PA00X+069252Y+050690               S3      
317NNAME10545       VIA   -     D0100PA00X+069649Y+051368               S3      
317NNAME11124       VIA   -     D0100PA00X+068973Y+050958               S1      
317NNAME10546       VIA   -     D0100PA00X+069689Y+050728               S1      
317NNAME10764       VIA   -     D0100PA00X+070072Y+051695               S3      
317P3V3_STB_NODE1   VIA   -     D0100PA00X+068666Y+051920               S3      
327P3V3_STB_NODE1   R1131 -2          A01X+069397Y+052371X0180Y0200R270 S2      
327NNAME11123       R1131 -1          A01X+069397Y+052056X0180Y0200R270 S2      
327NNAME10527       Q25   -E          A01X+069888Y+052923X0320Y0360     S2      
327NNAME11123       Q41   -C          A01X+068882Y+052828X0320Y0360R090 S2      
317P3V3_STB_NODE1   VIA   -     D0100PA00X+069844Y+052489               S3      
327N/C              U106  -1          A01X+069253Y+053959X0180Y0520R090 S2      
327NNAME11120       U106  -2          A01X+069253Y+054333X0180Y0520R090 S2      
327GND              U106  -3          A01X+069253Y+054707X0180Y0520R090 S2      
317NNAME11120       VIA   -     D0100PA00X+068677Y+054333               S1      
317P3V3_STB_NODE1   VIA   -     D0100PA00X+069415Y+053616               S3      
317P3V3_STB_NODE1   VIA   -     D0100PA00X+069004Y+053580               S3      
317P3V3_STB_NODE1   VIA   -     D0100PA00X+068718Y+053959               S3      
327GND              C439  -2          A01X+069568Y+056236X0440Y0540     S2      
317GND              VIA   -     D0100PA00X+069153Y+055979               S3      
317GND              VIA   -     D0100PA00X+069153Y+056379               S1      
327GND              C447  -2          A01X+069567Y+057838X0440Y0540     S2      
327GND              C446  -2          A01X+069567Y+057038X0440Y0540     S2      
317GND              VIA   -     D0100PA00X+069153Y+056779               S3      
317GND              VIA   -     D0100PA00X+069153Y+057179               S3      
317GND              VIA   -     D0100PA00X+069153Y+057579               S1      
317GND              VIA   -     D0100PA00X+069153Y+057979               S3      
327GND              C445  -2          A01X+069567Y+058638X0440Y0540     S2      
317GND              VIA   -     D0100PA00X+069153Y+058379               S1      
317GND              VIA   -     D0100PA00X+069153Y+058779               S3      
317GND              VIA   -     D0100PA00X+069560Y+059079               S3      
327LAN2_MDI3_DP     VIA   -           A01X+068525Y+059242X0160Y0041R045 S2      
327LAN2_MDI1_DN     VIA   -           A01X+069199Y+061062X0160Y0041R270 S2      
327LAN2_MDI1_DN     U138  -6          A01X+069839Y+062615X0320Y0610     S2      
327LAN2_MDI1_DP     U138  -5          A01X+069339Y+062615X0320Y0610     S2      
327P1V9_LAN2        U138  -4          A01X+068839Y+062615X0320Y0610     S2      
327GND              C523  -2          A10X+068747Y+062577X0180Y0200R270 S1      
327P1V9_LAN2        C523  -1          A10X+068747Y+062892X0180Y0200R270 S1      
317GND              VIA   -     D0100PA00X+068541Y+062125               S3      
317GND              VIA   -     D0100PA00X+068834Y+062129               S3      
327LAN2_MDI0_DP     VIA   -           A01X+068457Y+061500X0160Y0041R270 S2      
317P1V9_LAN2        VIA   -     D0100PA00X+068766Y+063180               S3      
317P1V9_LAN2        VIA   -     D0100PA00X+068564Y+063415               S1      
327LAN2_P2_R        U138  -21         A01X+068839Y+066139X0320Y0610     S2      
327LAN2_P2_P        U138  -20         A01X+069339Y+066139X0320Y0610     S2      
327LAN2_P2_N        U138  -19         A01X+069839Y+066139X0320Y0610     S2      
317GND              VIA   -     D0100PA00X+069272Y+067054               S3      
317GND              VIA   -     D0100PA00X+069883Y+067065               S3      
317LAN2_P2_N        VIA   -     D0100PA00X+069839Y+066724               S1      
317LAN2_P2_P        VIA   -     D0100PA00X+069339Y+066724               S1      
317GND              VIA   -     D0100PA00X+068910Y+068029               S3      
317GND              VIA   -     D0100PA00X+068851Y+073529               S3      
327N/C                    -1          A10X+069340Y+075820X0390Y0390R270 S1      
327N/C                    -1          A01X+069340Y+075820X0390Y0390R270 S2      
317NNAME11125       VIA   -     D0100PA00X+069960Y+077600               S1      
317NNAME11126       VIA   -     D0100PA00X+068970Y+077450               S1      
327NNAME11126       J18   -A11        A10X+069691Y+080787X0300Y1660R180 S1      
327NNAME11125       J18   -A10        A10X+070085Y+080787X0300Y1660R180 S1      
327I2C_PDB_R_SDA    J18   -B11        A01X+069691Y+080787X0300Y1660R180 S2      
327I2C_PDB_R_SCL    J18   -B10        A01X+070085Y+080787X0300Y1660R180 S2      
317LED_PWR_GD       D19   -3    D0400PA00X+071366Y+002071               S0      
317N53608970        D19   -2    D0400PA00X+070866Y+003071               S0      
317NNAME10769       D19   -1    D0400PA00X+070366Y+002071               S0      
327N53608970        R813  -1          A01X+070718Y+004385X0180Y0200R270 S2      
327LED_PWR_GD       R817  -2          A01X+071168Y+004385X0180Y0200R090 S2      
327GND              R813  -2          A01X+070718Y+004700X0180Y0200R270 S2      
327NNAME11099       R817  -1          A01X+071168Y+004700X0180Y0200R090 S2      
317GND              VIA   -     D0100PA00X+070718Y+005057               S3      
317NNAME11099       VIA   -     D0100PA00X+071168Y+005102               S1      
317GND              VIA   -     D0100PA00X+070638Y+007548               S3      
317GND              VIA   -     D0100PA00X+070813Y+010639               S3      
317GND              J14   -11   D0900PA00X+071158Y+014356               S0      
317USBPWR_P0        J14   -5    D0400PA00X+071298Y+015566               S0      
317USB1_L_DN        J14   -6    D0400PA00X+071298Y+016546               S0      
317USB1_L_DP        J14   -7    D0400PA00X+071298Y+017346               S0      
317GND              J14   -8    D0400PA00X+071298Y+018326               S0      
317GND              J14   -12   D0900PA00X+071158Y+019536               S0      
317GND              J15   -11   D0900PA00X+071158Y+022236               S0      
317GND              VIA   -     D0100PA00X+070169Y+021213               S3      
317GND              VIA   -     D0100PA00X+070095Y+021687               S3      
317USBPWR_P1        J15   -5    D0400PA00X+071298Y+023446               S0      
317GND              VIA   -     D0100PA00X+070099Y+022137               S3      
317USB3_L_DN        J15   -6    D0400PA00X+071298Y+024426               S0      
317USB3_L_DP        J15   -7    D0400PA00X+071298Y+025226               S0      
317GND              J15   -8    D0400PA00X+071298Y+026206               S0      
317GND              J15   -12   D0900PA00X+071158Y+027416               S0      
317NNAME10883       VIA   -     D0100PA00X+070177Y+033194               S3      
317GND              VIA   -     D0100PA00X+070794Y+044868               S3      
317GND              VIA   -     D0100PA00X+071464Y+045487               S3      
317GND              VIA   -     D0100PA00X+071224Y+045229               S1      
317NNAME11091       VIA   -     D0100PA00X+070273Y+045548               S3      
317NNAME10772       VIA   -     D0100PA00X+070455Y+044441               S1      
327P3V3_STB_NODE1   C782  -1          A10X+070640Y+046813X0280Y0320R270 S1      
327GND              C782  -2          A10X+071220Y+046813X0280Y0320R270 S1      
327P3V3_STB_NODE1   C783  -1          A10X+070640Y+046253X0280Y0320R270 S1      
327GND              C783  -2          A10X+071220Y+046253X0280Y0320R270 S1      
327P3V3_STB_NODE1   U102  -D4         A01X+070083Y+046994X0193Y0193R180 S2      
327NNAME10049       U102  -D3         A01X+070477Y+046994X0193Y0193R180 S2      
327NNAME10791       U102  -D2         A01X+070870Y+046994X0193Y0193R180 S2      
327NNAME11127       U102  -D1         A01X+071264Y+046994X0193Y0193R180 S2      
327NNAME11122       U102  -C4         A01X+070083Y+046601X0193Y0193R180 S2      
327NNAME11128       U102  -C3         A01X+070477Y+046601X0193Y0193R180 S2      
327NNAME11129       U102  -C2         A01X+070870Y+046601X0193Y0193R180 S2      
327NNAME10970       U102  -C1         A01X+071264Y+046601X0193Y0193R180 S2      
327NNAME11091       U102  -B4         A01X+070083Y+046207X0193Y0193R180 S2      
327NNAME10061       U102  -B3         A01X+070477Y+046207X0193Y0193R180 S2      
327NNAME10492       U102  -B2         A01X+070870Y+046207X0193Y0193R180 S2      
327NNAME11130       U102  -B1         A01X+071264Y+046207X0193Y0193R180 S2      
327NNAME10048       U102  -A4         A01X+070083Y+045813X0193Y0193R180 S2      
327NNAME10766       U102  -A3         A01X+070477Y+045813X0193Y0193R180 S2      
327NNAME10772       U102  -A2         A01X+070870Y+045813X0193Y0193R180 S2      
327NNAME10428       U102  -A1         A01X+071264Y+045813X0193Y0193R180 S2      
317NNAME10428       VIA   -     D0100PA00X+071553Y+045933               S3      
317NNAME11122       VIA   -     D0100PA00X+070280Y+046404               S3      
317P3V3_STB_NODE1   VIA   -     D0100PA00X+070280Y+046798               S3      
327P3V3_STB_NODE1   C788  -1          A10X+070356Y+047549X0280Y0320R090 S1      
327NNAME10764       U102  -H4         A01X+070083Y+048569X0193Y0193R180 S2      
327JTAG_CPLD1_TCK   U102  -H3         A01X+070477Y+048569X0193Y0193R180 S2      
327JTAG_CPLD1_TDI   U102  -H2         A01X+070870Y+048569X0193Y0193R180 S2      
327NNAME10843       U102  -H1         A01X+071264Y+048569X0193Y0193R180 S2      
327P3V3_STB_NODE1   U102  -G4         A01X+070083Y+048176X0193Y0193R180 S2      
327NNAME10034       U102  -G3         A01X+070477Y+048176X0193Y0193R180 S2      
327NNAME10500       U102  -G2         A01X+070870Y+048176X0193Y0193R180 S2      
327NNAME10742       U102  -G1         A01X+071264Y+048176X0193Y0193R180 S2      
327P3V3_STB_NODE1   U102  -F4         A01X+070083Y+047782X0193Y0193R180 S2      
327NNAME11069       U102  -F3         A01X+070477Y+047782X0193Y0193R180 S2      
327NNAME10077       U102  -F2         A01X+070870Y+047782X0193Y0193R180 S2      
327NNAME10059       U102  -F1         A01X+071264Y+047782X0193Y0193R180 S2      
327P3V3_STB_NODE1   U102  -E4         A01X+070083Y+047388X0193Y0193R180 S2      
327NNAME10701       U102  -E3         A01X+070477Y+047388X0193Y0193R180 S2      
327NNAME10670       U102  -E2         A01X+070870Y+047388X0193Y0193R180 S2      
327NNAME10543       U102  -E1         A01X+071264Y+047388X0193Y0193R180 S2      
317NNAME10049       VIA   -     D0100PA00X+070673Y+047191               S3      
317NNAME10670       VIA   -     D0100PA00X+071077Y+047597               S3      
317NNAME10742       VIA   -     D0100PA00X+071533Y+048112               S3      
317NNAME10034       VIA   -     D0100PA00X+070673Y+048372               S3      
317NNAME10077       VIA   -     D0100PA00X+071067Y+047979               S3      
317NNAME10701       VIA   -     D0100PA00X+070673Y+047585               S3      
317NNAME10791       VIA   -     D0100PA00X+071067Y+047191               S3      
317JTAG_CPLD1_TCK   VIA   -     D0100PA00X+070259Y+048375               S3      
317P3V3_STB_NODE1   VIA   -     D0100PA00X+070280Y+047191               S3      
317P3V3_STB_NODE1   VIA   -     D0100PA00X+070280Y+047979               S3      
317NNAME11069       VIA   -     D0100PA00X+070673Y+047979               S3      
327NNAME10542       U102  -K4         A01X+070083Y+049357X0193Y0193R180 S2      
327NNAME11131       U102  -K3         A01X+070477Y+049357X0193Y0193R180 S2      
327NNAME11132       U102  -K2         A01X+070870Y+049357X0193Y0193R180 S2      
327NNAME11133       U102  -K1         A01X+071264Y+049357X0193Y0193R180 S2      
327CPLD_ROW_LATCH   U102  -J4         A01X+070083Y+048963X0193Y0193R180 S2      
327CPLD_ROW_EN      U102  -J3         A01X+070477Y+048963X0193Y0193R180 S2      
327JTAG_CPLD1_TDO   U102  -J2         A01X+070870Y+048963X0193Y0193R180 S2      
327JTAG_CPLD1_TMS   U102  -J1         A01X+071264Y+048963X0193Y0193R180 S2      
317NNAME11131       VIA   -     D0100PA00X+070477Y+049888               S1      
317NNAME11133       VIA   -     D0100PA00X+071398Y+049808               S1      
327P3V3_STB_NODE1   R1041 -2          A01X+070774Y+051323X0180Y0200R180 S2      
327NNAME11131       R1041 -1          A01X+070459Y+051323X0180Y0200R180 S2      
327P3V3_STB_NODE1   R1046 -2          A01X+071282Y+051343X0180Y0200     S2      
327NNAME11132       R1046 -1          A01X+071597Y+051343X0180Y0200     S2      
317NNAME11132       VIA   -     D0100PA00X+071602Y+051695               S1      
317NNAME10542       VIA   -     D0100PA00X+070083Y+050404               S1      
317P3V3_STB_NODE1   VIA   -     D0100PA00X+070774Y+051014               S3      
317CPLD_ROW_EN      VIA   -     D0100PA00X+070792Y+050558               S1      
327NNAME11132       Q27   -C          A01X+071602Y+052126X0320Y0360     S2      
327GND              Q27   -E          A01X+071228Y+052913X0320Y0360     S2      
327NNAME11131       Q25   -C          A01X+070262Y+052136X0320Y0360     S2      
327NNAME11134       Q25   -B          A01X+070636Y+052923X0320Y0360     S2      
317GND              VIA   -     D0100PA00X+071228Y+052579               S3      
317NNAME11134       VIA   -     D0100PA00X+070636Y+053263               S1      
317NNAME10344       VIA   -     D0100PA00X+071626Y+052530               S1      
317P3V3_STB_NODE1   VIA   -     D0100PA00X+071282Y+051965               S3      
327GND              C799  -2          A01X+070102Y+054982X0180Y0200     S2      
327P3V3_STB_NODE1   C799  -1          A01X+070417Y+054982X0180Y0200     S2      
327GND              C798  -2          A01X+071059Y+054391X0440Y0540R180 S2      
327NNAME11120       C798  -1          A01X+070311Y+054391X0440Y0540R180 S2      
327P1V05_NODE1      R1043 -2          A01X+070315Y+053540X0180Y0200     S2      
327NNAME11134       R1043 -1          A01X+070630Y+053540X0180Y0200     S2      
317GND              VIA   -     D0100PA00X+071059Y+053910               S3      
317P1V05_NODE1      VIA   -     D0100PA00X+070117Y+053851               S3      
317P3V3_STB_NODE1   VIA   -     D0100PA00X+070826Y+054982               S3      
327GND              C448  -2          A01X+071456Y+056323X0280Y0320R090 S2      
327P3V3_NODE1       C439  -1          A01X+070316Y+056236X0440Y0540     S2      
317GND              VIA   -     D0100PA00X+070102Y+055366               S3      
317GND              VIA   -     D0100PA00X+071087Y+056323               S3      
327P3V3_NODE1       C447  -1          A01X+070315Y+057838X0440Y0540     S2      
327P3V3_NODE1       C446  -1          A01X+070315Y+057038X0440Y0540     S2      
327LAN2_CTRL_P1V9   R595  -1          A01X+071834Y+058165X0460Y0620R270 S2      
317LAN2_CTRL_P1V9   VIA   -     D0100PA00X+071330Y+057900               S3      
327P3V3_NODE1       C445  -1          A01X+070315Y+058638X0440Y0540     S2      
327NNAME11135       R595  -2          A01X+071834Y+059325X0460Y0620R270 S2      
317LAN2_CTRL_P1V9   VIA   -     D0100PA00X+071319Y+058303               S3      
317NNAME11135       VIA   -     D0100PA00X+071274Y+059310               S1      
327P1V9_LAN2        U138  -9          A01X+071339Y+062615X0320Y0610     S2      
327LAN2_MDI2_DN     U138  -8          A01X+070839Y+062615X0320Y0610     S2      
327LAN2_MDI2_DP     U138  -7          A01X+070339Y+062615X0320Y0610     S2      
327GND              C520  -2          A10X+071126Y+062572X0180Y0200R270 S1      
327P1V9_LAN2        C520  -1          A10X+071126Y+062887X0180Y0200R270 S1      
327GND              C524  -2          A10X+071576Y+062572X0180Y0200R270 S1      
327P1V9_LAN2        C524  -1          A10X+071576Y+062887X0180Y0200R270 S1      
317GND              VIA   -     D0100PA00X+071528Y+062028               S3      
317GND              VIA   -     D0100PA00X+071161Y+062038               S3      
317P1V9_LAN2        VIA   -     D0100PA00X+071273Y+063175               S3      
317P1V9_LAN2        VIA   -     D0100PA00X+071606Y+063175               S3      
317P1V9_LAN2        VIA   -     D0100PA00X+071374Y+063437               S1      
327LAN2_P3_P        U138  -18         A01X+070339Y+066139X0320Y0610     S2      
327LAN2_P3_N        U138  -17         A01X+070839Y+066139X0320Y0610     S2      
327LAN2_P3_R        U138  -16         A01X+071339Y+066139X0320Y0610     S2      
317GND              VIA   -     D0100PA00X+070357Y+067304               S3      
317GND              VIA   -     D0100PA00X+070766Y+067320               S3      
317LAN2_P3_N        VIA   -     D0100PA00X+070839Y+066977               S1      
317LAN2_P3_P        VIA   -     D0100PA00X+070339Y+066977               S1      
317GND              VIA   -     D0100PA00X+071391Y+068133               S3      
317LAN2_P4_P        VIA   -     D0100PA00X+071345Y+067764               S1      
317GND              VIA   -     D0100PA00X+070845Y+069549               S3      
317GND              VIA   -     D0100PA00X+070587Y+072183               S3      
317NNAME10792       VIA   -     D0100PA00X+070950Y+073680               S3      
327GND              C592  -2          A10X+070950Y+074043X0180Y0200R270 S1      
327NNAME11126       C592  -1          A10X+070950Y+074358X0180Y0200R270 S1      
327NNAME11126       R1294 -2          A01X+070940Y+074338X0180Y0200R270 S2      
327NNAME10792       R1294 -1          A01X+070940Y+074023X0180Y0200R270 S2      
327NNAME11126       R1295 -2          A01X+071340Y+074338X0180Y0200R270 S2      
327NNAME10792       R1295 -1          A01X+071340Y+074023X0180Y0200R270 S2      
317GND              VIA   -     D0100PA00X+070658Y+074043               S3      
317NNAME11136       VIA   -     D0100PA00X+070400Y+077080               S1      
317LAN2_P2_N        VIA   -     D0100PA00X+071625Y+076558               S3      
327NNAME11136       J18   -A9         A10X+070479Y+080787X0300Y1660R180 S1      
327GND              J18   -A8         A10X+070872Y+080787X0300Y1660R180 S1      
327LAN2_P4_N        J18   -A7         A10X+071266Y+080787X0300Y1660R180 S1      
327LAN2_P4_P        J18   -A6         A10X+071660Y+080787X0300Y1660R180 S1      
327GND              J18   -B9         A01X+070479Y+080787X0300Y1660R180 S2      
327GND              J18   -B8         A01X+070872Y+080787X0300Y1660R180 S2      
327GND              J18   -B7         A01X+071266Y+080787X0300Y1660R180 S2      
327LAN2_P2_N        J18   -B6         A01X+071660Y+080787X0300Y1660R180 S2      
317GND              VIA   -     D0100PA00X+070479Y+079127               S3      
317GND              VIA   -     D0100PA00X+070872Y+079109               S3      
317GND              VIA   -     D0100PA00X+070904Y+078751               S3      
317NNAME10041       VIA   -     D0100PA00X+071980Y+002492               S3      
327GND              CE2   -2          A01X+073228Y+010919X0630Y1190R180 S2      
317GND              VIA   -     D0100PA00X+072616Y+010932               S3      
317GND              VIA   -     D0100PA00X+072619Y+010533               S3      
327USBPWR_P0        CE2   -1          A01X+073228Y+012651X0630Y1190R180 S2      
317GND              VIA   -     D0100PA00X+072616Y+011251               S3      
317USBPWR_P0        VIA   -     D0100PA00X+072650Y+012347               S3      
317GND              J14   -9    D0900PA00X+073398Y+014356               S0      
317USBPWR_P0        VIA   -     D0100PA00X+072640Y+013030               S3      
317USBPWR_P0        VIA   -     D0100PA00X+072647Y+012666               S3      
317USBPWR_P0        J14   -1    D0400PA00X+072328Y+015566               S0      
317USB0_L_DN        J14   -2    D0400PA00X+072328Y+016546               S0      
317USB0_L_DP        J14   -3    D0400PA00X+072328Y+017346               S0      
317GND              J14   -4    D0400PA00X+072328Y+018326               S0      
317GND              J14   -10   D0900PA00X+073398Y+019536               S0      
317GND              J15   -9    D0900PA00X+073398Y+022236               S0      
317USBPWR_P1        J15   -1    D0400PA00X+072328Y+023446               S0      
317USB2_L_DN        J15   -2    D0400PA00X+072328Y+024426               S0      
317USB2_L_DP        J15   -3    D0400PA00X+072328Y+025226               S0      
317GND              J15   -4    D0400PA00X+072328Y+026206               S0      
317GND              J15   -10   D0900PA00X+073398Y+027416               S0      
327NNAME11137       R1027 -2          A01X+073157Y+045263X0180Y0200R090 S2      
327NNAME11130       R1027 -1          A01X+073157Y+045578X0180Y0200R090 S2      
327GND              R1029 -2          A01X+073157Y+044547X0180Y0200R090 S2      
327NNAME11137       R1029 -1          A01X+073157Y+044862X0180Y0200R090 S2      
317GND              VIA   -     D0100PA00X+073157Y+044214               S1      
317NNAME11130       VIA   -     D0100PA00X+072658Y+045564               S1      
327NNAME11129       R1246 -1          A01X+073151Y+046048X0180Y0200R180 S2      
327NNAME11127       R1247 -1          A01X+073167Y+046737X0180Y0200R180 S2      
317NNAME11128       VIA   -     D0100PA00X+073157Y+046404               S1      
317NNAME10970       VIA   -     D0100PA00X+072643Y+046537               S3      
317NNAME11129       VIA   -     D0100PA00X+072683Y+046082               S1      
317NNAME11127       VIA   -     D0100PA00X+072794Y+046994               S1      
317NNAME10319       VIA   -     D0100PA00X+073134Y+047672               S3      
317NNAME10059       VIA   -     D0100PA00X+072014Y+047833               S1      
317NNAME10500       VIA   -     D0100PA00X+071843Y+048337               S3      
317NNAME10843       VIA   -     D0100PA00X+072129Y+048438               S3      
317NNAME10543       VIA   -     D0100PA00X+071937Y+047244               S3      
317JTAG_CPLD1_TDI   VIA   -     D0100PA00X+072573Y+048679               S3      
317JTAG_CPLD1_TMS   VIA   -     D0100PA00X+072964Y+048685               S3      
327P3V3_NODE1       R1290 -2          A01X+073123Y+050010X0180Y0200     S2      
327JTAG_CPLD1_TMS   R1272 -2          A01X+073143Y+049600X0180Y0200     S2      
317P3V3_NODE1       VIA   -     D0100PA00X+072760Y+050010               S3      
317JTAG_CPLD1_TDO   VIA   -     D0100PA00X+072015Y+049163               S3      
327GND              R1120 -2          A01X+072683Y+051576X0180Y0200R270 S2      
327NNAME11133       R1120 -1          A01X+072683Y+051261X0180Y0200R270 S2      
327P3V3_STB_NODE1   R1121 -2          A01X+072238Y+051576X0180Y0200R270 S2      
327NNAME11133       R1121 -1          A01X+072238Y+051261X0180Y0200R270 S2      
327JTAG_CPLD1_TDO   R1286 -2          A01X+073123Y+050405X0180Y0200     S2      
317GND              VIA   -     D0100PA00X+072994Y+051576               S3      
317P3V3_STB_NODE1   VIA   -     D0100PA00X+071933Y+051576               S3      
327NNAME11138       Q27   -B          A01X+071976Y+052913X0320Y0360     S2      
317NNAME11138       VIA   -     D0100PA00X+071976Y+053243               S1      
327NNAME10344       R1047 -2          A01X+071659Y+053503X0180Y0200     S2      
327NNAME11138       R1047 -1          A01X+071974Y+053503X0180Y0200     S2      
327P3V3_NODE1       C448  -1          A01X+072036Y+056323X0280Y0320R090 S2      
327P3V3_NODE1       Q16   -3          A01X+072761Y+056418X0590Y0790R270 S2      
317P3V3_NODE1       VIA   -     D0100PA00X+072866Y+055893               S3      
317P3V3_NODE1       VIA   -     D0100PA00X+073125Y+055898               S3      
317P3V3_NODE1       VIA   -     D0100PA00X+072615Y+055900               S3      
317P3V3_NODE1       VIA   -     D0100PA00X+072045Y+055899               S3      
317P3V3_NODE1       VIA   -     D0100PA00X+072337Y+055891               S3      
327P3V3_NODE1       R594  -1          A01X+071823Y+056877X0280Y0320     S2      
327LAN2_CTRL_P1V9   R594  -2          A01X+071823Y+057457X0280Y0320     S2      
327LAN2_CTRL_P1V9   Q16   -1          A01X+072761Y+058218X0590Y0790R270 S2      
327P1V9_LAN2        Q16   -2          A01X+072761Y+057318X0590Y0790R270 S2      
327NNAME11135       C468  -1          A01X+072550Y+059326X0280Y0320R270 S2      
327P1V9_LAN2        C468  -2          A01X+073130Y+059326X0280Y0320R270 S2      
327LAN2_MDI3_DN     U138  -12         A01X+072839Y+062615X0320Y0610     S2      
327LAN2_MDI3_DP     U138  -11         A01X+072339Y+062615X0320Y0610     S2      
327P1V9_LAN2        U138  -10         A01X+071839Y+062615X0320Y0610     S2      
327GND              C522  -2          A10X+072026Y+062572X0180Y0200R270 S1      
327P1V9_LAN2        C522  -1          A10X+072026Y+062887X0180Y0200R270 S1      
317GND              VIA   -     D0100PA00X+072005Y+062048               S3      
317P1V9_LAN2        VIA   -     D0100PA00X+071909Y+063168               S3      
317P1V9_LAN2        VIA   -     D0100PA00X+071737Y+063447               S3      
317LAN2_P1_R        VIA   -     D0100PA00X+072783Y+064183               S1      
327LAN2_P4_R        U138  -15         A01X+071839Y+066139X0320Y0610     S2      
327LAN2_P4_P        U138  -14         A01X+072339Y+066139X0320Y0610     S2      
327LAN2_P4_N        U138  -13         A01X+072839Y+066139X0320Y0610     S2      
317LAN2_P3_R        VIA   -     D0100PA00X+072869Y+064983               S1      
327NNAME11125       R1073 -2          A01X+072888Y+068270X0180Y0200R180 S2      
327NNAME10818       R1073 -1          A01X+072573Y+068270X0180Y0200R180 S2      
327NNAME11125       R1313 -2          A01X+072898Y+069080X0180Y0200R180 S2      
327NNAME10818       R1313 -1          A01X+072583Y+069080X0180Y0200R180 S2      
327NNAME11125       R1315 -2          A01X+072888Y+068670X0180Y0200R180 S2      
327NNAME10818       R1315 -1          A01X+072573Y+068670X0180Y0200R180 S2      
317GND              VIA   -     D0100PA00X+071851Y+068153               S3      
317NNAME10818       VIA   -     D0100PA00X+072110Y+068940               S3      
317LAN2_P4_N        VIA   -     D0100PA00X+071845Y+067764               S1      
327NNAME11125       R1312 -2          A01X+072898Y+069880X0180Y0200R180 S2      
327NNAME10818       R1312 -1          A01X+072583Y+069880X0180Y0200R180 S2      
327NNAME11125       R1314 -2          A01X+072898Y+069480X0180Y0200R180 S2      
327NNAME10818       R1314 -1          A01X+072583Y+069480X0180Y0200R180 S2      
327NNAME11125       R1316 -2          A01X+072898Y+070280X0180Y0200R180 S2      
327NNAME10818       R1316 -1          A01X+072583Y+070280X0180Y0200R180 S2      
327NNAME11136       R1318 -2          A01X+072433Y+070780X0180Y0200     S2      
327NNAME10876       R1318 -1          A01X+072748Y+070780X0180Y0200     S2      
327NNAME11136       R1317 -2          A01X+072433Y+071980X0180Y0200     S2      
327NNAME10876       R1317 -1          A01X+072748Y+071980X0180Y0200     S2      
327NNAME11136       R1320 -2          A01X+072433Y+071580X0180Y0200     S2      
327NNAME10876       R1320 -1          A01X+072748Y+071580X0180Y0200     S2      
327NNAME11136       R1321 -2          A01X+072433Y+071180X0180Y0200     S2      
327NNAME10876       R1321 -1          A01X+072748Y+071180X0180Y0200     S2      
317NNAME10876       VIA   -     D0100PA00X+073120Y+071620               S3      
327GND              C594  -2          A10X+072950Y+073458X0180Y0200R090 S1      
327NNAME11125       C594  -1          A10X+072950Y+073143X0180Y0200R090 S1      
327NNAME11136       R1271 -2          A01X+072433Y+072780X0180Y0200     S2      
327NNAME10876       R1271 -1          A01X+072748Y+072780X0180Y0200     S2      
327NNAME11136       R1319 -2          A01X+072433Y+072380X0180Y0200     S2      
327NNAME10876       R1319 -1          A01X+072748Y+072380X0180Y0200     S2      
317GND              VIA   -     D0100PA00X+072950Y+073740               S3      
317NNAME11125       VIA   -     D0100PA00X+073080Y+072840               S3      
327GND              C596  -2          A10X+072950Y+074043X0180Y0200R270 S1      
327NNAME11136       C596  -1          A10X+072950Y+074358X0180Y0200R270 S1      
327NNAME11126       R1072 -2          A01X+072940Y+074338X0180Y0200R270 S2      
327NNAME10792       R1072 -1          A01X+072940Y+074023X0180Y0200R270 S2      
327NNAME11126       R1292 -2          A01X+072140Y+074338X0180Y0200R270 S2      
327NNAME10792       R1292 -1          A01X+072140Y+074023X0180Y0200R270 S2      
327NNAME11126       R1293 -2          A01X+071740Y+074338X0180Y0200R270 S2      
327NNAME10792       R1293 -1          A01X+071740Y+074023X0180Y0200R270 S2      
327NNAME11126       R1296 -2          A01X+072540Y+074338X0180Y0200R270 S2      
327NNAME10792       R1296 -1          A01X+072540Y+074023X0180Y0200R270 S2      
317NNAME11136       VIA   -     D0100PA00X+072950Y+074630               S3      
317GND              VIA   -     D0100PA00X+071815Y+076302               S3      
317GND              VIA   -     D0100PA00X+072110Y+076290               S3      
317LAN2_P2_P        VIA   -     D0100PA00X+072125Y+076558               S3      
317GND              VIA   -     D0100PA00X+072757Y+077528               S3      
317GND              VIA   -     D0100PA00X+073099Y+077533               S3      
317LAN2_P1_N        VIA   -     D0100PA00X+072693Y+077849               S3      
317LAN2_P1_P        VIA   -     D0100PA00X+073193Y+077849               S3      
327GND              J18   -A5         A10X+072053Y+080787X0300Y1660R180 S1      
327LAN2_P3_N        J18   -A4         A10X+072447Y+080787X0300Y1660R180 S1      
327LAN2_P3_P        J18   -A3         A10X+072841Y+080787X0300Y1660R180 S1      
327GND              J18   -A2         A10X+073235Y+080787X0300Y1660R180 S1      
327LAN2_P2_P        J18   -B5         A01X+072053Y+080787X0300Y1660R180 S2      
327GND              J18   -B4         A01X+072447Y+080787X0300Y1660R180 S2      
327LAN2_P1_N        J18   -B3         A01X+072841Y+080787X0300Y1660R180 S2      
327LAN2_P1_P        J18   -B2         A01X+073235Y+080787X0300Y1660R180 S2      
317GND              VIA   -     D0100PA00X+072179Y+079141               S3      
317GND              VIA   -     D0100PA00X+072259Y+078789               S3      
317TACKOVER_EN_N    J32   -1    D0480PA00X+073997Y+002936               S0      
317GND              J32   -2    D0480PA00X+074997Y+002936               S0      
327N/C                    -1          A10X+074558Y+006287X0390Y0390R270 S1      
327N/C                    -1          A01X+074558Y+006287X0390Y0390R270 S2      
317GND              VIA   -     D0100PA00X+073862Y+010935               S3      
317GND              VIA   -     D0100PA00X+073865Y+010536               S3      
317P5V_NODE1        VIA   -     D0100PA00X+074476Y+010371               S3      
317P5V_NODE1        VIA   -     D0100PA00X+074479Y+010694               S3      
317P5V_NODE1        VIA   -     D0100PA00X+074771Y+010029               S3      
327USBPWR_P0        FS3   -2          A01X+074871Y+012554X0400Y0710R090 S2      
327P5V_NODE1        FS3   -1          A01X+074871Y+011413X0400Y0710R090 S2      
317GND              VIA   -     D0100PA00X+073862Y+011254               S3      
317USBPWR_P0        VIA   -     D0100PA00X+073837Y+012340               S3      
317P5V_NODE1        VIA   -     D0100PA00X+074507Y+011018               S3      
317USBPWR_P0        VIA   -     D0100PA00X+073827Y+013023               S3      
317USBPWR_P0        VIA   -     D0100PA00X+073834Y+012659               S3      
317USBPWR_P0        VIA   -     D0100PA00X+074708Y+012982               S3      
317JTAG_CPLD3_TCK   VIA   -     D0100PA00X+074760Y+032353               S3      
317JTAG_CPLD3_TMS   VIA   -     D0100PA00X+074522Y+032725               S3      
327NNAME11139       U101  -3          A01X+074602Y+045083X0400Y0500R270 S2      
327NNAME11137       U101  -2          A01X+073722Y+044683X0400Y0500R270 S2      
327GND              U101  -1          A01X+073722Y+045483X0400Y0500R270 S2      
317GND              VIA   -     D0100PA00X+074140Y+045483               S3      
317NNAME11137       VIA   -     D0100PA00X+073631Y+045077               S1      
327NNAME10207       R1246 -2          A01X+073466Y+046048X0180Y0200R180 S2      
327NNAME10204       R1247 -2          A01X+073482Y+046737X0180Y0200R180 S2      
317NNAME10204       VIA   -     D0100PA00X+073735Y+046433               S1      
317NNAME10207       VIA   -     D0100PA00X+073735Y+045982               S3      
327JTAG_CPLD1_TMS   R1034 -2          A01X+073695Y+048364X0180Y0200     S2      
327P3V3_STB_NODE1   R1034 -1          A01X+074010Y+048364X0180Y0200     S2      
327JTAG_CPLD1_TDI   R1035 -2          A01X+073698Y+047898X0180Y0200     S2      
327P3V3_STB_NODE1   R1035 -1          A01X+074013Y+047898X0180Y0200     S2      
327JTAG_CPLD1_TDI   R1285 -2          A01X+073693Y+047500X0180Y0200     S2      
327NNAME11140       R1285 -1          A01X+074008Y+047500X0180Y0200     S2      
317GND              VIA   -     D0100PA00X+074278Y+048764               S3      
317P3V3_STB_NODE1   VIA   -     D0100PA00X+074336Y+047898               S3      
317P3V3_STB_NODE1   VIA   -     D0100PA00X+074315Y+048350               S3      
327NNAME11140       VIA   -           A01X+074600Y+047500X0300Y0300     S2      
327JTAG_CPLD1_TCK   R1033 -2          A01X+073684Y+048764X0180Y0200     S2      
327GND              R1033 -1          A01X+073999Y+048764X0180Y0200     S2      
327GND              R1269 -2          A01X+074508Y+049680X0180Y0200R180 S2      
327NNAME11141       R1269 -1          A01X+074193Y+049680X0180Y0200R180 S2      
327NNAME10949       R1290 -1          A01X+073438Y+050010X0180Y0200     S2      
327NNAME11141       R1268 -2          A01X+074193Y+050100X0180Y0200     S2      
327NNAME10859       R1268 -1          A01X+074508Y+050100X0180Y0200     S2      
327NNAME11141       R1272 -1          A01X+073458Y+049600X0180Y0200     S2      
327JTAG_CPLD1_TCK   R1287 -2          A01X+073943Y+049250X0180Y0200     S2      
327NNAME11142       R1287 -1          A01X+074258Y+049250X0180Y0200     S2      
317NNAME11099       VIA   -     D0100PA00X+073813Y+050275               S3      
317JTAG_CPLD1_TCK   VIA   -     D0100PA00X+073282Y+048944               S3      
317NNAME11141       VIA   -     D0100PA00X+073458Y+049258               S1      
317NNAME11142       VIA   -     D0100PA00X+074550Y+049250               S1      
327NNAME10949       R1286 -1          A01X+073438Y+050405X0180Y0200     S2      
317P1V9_LAN2        VIA   -     D0100PA00X+074402Y+056614               S1      
327P1V9_LAN2        Q16   -4          A01X+074991Y+057318X0790Y1500     S2      
317P1V9_LAN2        VIA   -     D0100PA00X+074409Y+057507               S3      
317P1V9_LAN2        VIA   -     D0100PA00X+074395Y+057883               S1      
317P1V9_LAN2        VIA   -     D0100PA00X+074405Y+057183               S1      
317P1V9_LAN2        VIA   -     D0100PA00X+074747Y+058554               S3      
317P1V9_LAN2        VIA   -     D0100PA00X+074746Y+058232               S3      
327P1V9_LAN2        VIA   -           A10X+074043Y+061641X0260Y0260R090 S1      
327N54134271        C541  -1          A01X+074744Y+064167X0460Y0620R270 S2      
327LAN2_P1_R        R1277 -2          A01X+073768Y+064183X0180Y0200     S2      
327N54134271        R1277 -1          A01X+074083Y+064183X0180Y0200     S2      
327GND              C541  -2          A01X+074744Y+065327X0460Y0620R270 S2      
327LAN2_P4_R        R1280 -2          A01X+073768Y+065383X0180Y0200     S2      
327N54134271        R1280 -1          A01X+074083Y+065383X0180Y0200     S2      
327LAN2_P3_R        R1279 -2          A01X+073768Y+064983X0180Y0200     S2      
327N54134271        R1279 -1          A01X+074083Y+064983X0180Y0200     S2      
327LAN2_P2_R        R1278 -2          A01X+073768Y+064583X0180Y0200     S2      
327N54134271        R1278 -1          A01X+074083Y+064583X0180Y0200     S2      
317N54134271        VIA   -     D0100PA00X+074400Y+064792               S1      
317LAN2_P2_R        VIA   -     D0100PA00X+073321Y+064583               S1      
317LAN2_P4_R        VIA   -     D0100PA00X+073254Y+065383               S1      
327GND              J18   -A1         A10X+073628Y+080590X0300Y1260R180 S1      
327GND              J18   -B1         A01X+073628Y+080787X0300Y1660R180 S2      
317GND              VIA   -     D0100PA00X+073446Y+078865               S3      
317GND              VIA   -     D0100PA00X+073446Y+079165               S3      
327GND              C556  -2          A01X+075749Y+010518X0440Y0540R180 S2      
327P5V_NODE1        C556  -1          A01X+075001Y+010518X0440Y0540R180 S2      
317GND              VIA   -     D0100PA00X+076259Y+010653               S3      
317GND              VIA   -     D0100PA00X+076263Y+010330               S3      
317P5V_NODE1        VIA   -     D0100PA00X+075108Y+010029               S3      
317USBPWR_P0        VIA   -     D0100PA00X+075458Y+012402               S3      
317P5V_NODE1        VIA   -     D0100PA00X+074807Y+011021               S3      
317P5V_NODE1        VIA   -     D0100PA00X+075118Y+011021               S3      
317USBPWR_P0        VIA   -     D0100PA00X+075461Y+012725               S3      
317USBPWR_P0        VIA   -     D0100PA00X+075093Y+012982               S3      
317P5V_STB_NODE1    VIA   -     D0100PA00X+075043Y+031433               S3      
317P5V_STB_NODE1    VIA   -     D0100PA00X+075035Y+031134               S3      
317JTAG_CPLD3_TDO   VIA   -     D0100PA00X+075070Y+032377               S3      
317JTAG_CPLD3_TDI   VIA   -     D0100PA00X+075323Y+032826               S3      
317JTAG_CPLD2_TDI   VIA   -     D0100PA00X+075940Y+033484               S3      
317JTAG_CPLD2_TMS   VIA   -     D0100PA00X+075485Y+033506               S3      
317JTAG_CPLD2_TDO   VIA   -     D0100PA00X+075550Y+033779               S3      
327GND              C781  -2          A01X+075500Y+044653X0180Y0200R180 S2      
327NNAME11139       C781  -1          A01X+075185Y+044653X0180Y0200R180 S2      
327P12V_AUX         R1026 -2          A01X+075500Y+045553X0180Y0200R180 S2      
327NNAME11139       R1026 -1          A01X+075185Y+045553X0180Y0200R180 S2      
327GND              R1028 -2          A01X+075500Y+045103X0180Y0200R180 S2      
327NNAME11139       R1028 -1          A01X+075185Y+045103X0180Y0200R180 S2      
317GND              VIA   -     D0100PA00X+075822Y+044653               S1      
317GND              VIA   -     D0100PA00X+075782Y+045103               S3      
317P12V_AUX         VIA   -     D0100PA00X+075849Y+045553               S3      
317NNAME11139       VIA   -     D0100PA00X+074872Y+045533               S1      
317NNAME10319       VIA   -     D0100PA00X+075850Y+046950               S3      
327GND              R1266 -2          A01X+075508Y+047500X0180Y0200R180 S2      
327NNAME11140       R1266 -1          A01X+075193Y+047500X0180Y0200R180 S2      
327NNAME11140       R1265 -2          A01X+075193Y+047900X0180Y0200     S2      
327NNAME10845       R1265 -1          A01X+075508Y+047900X0180Y0200     S2      
317GND              VIA   -     D0100PA00X+075750Y+047400               S3      
327GND              R1270 -2          A01X+075208Y+049250X0180Y0200R180 S2      
327NNAME11142       R1270 -1          A01X+074893Y+049250X0180Y0200R180 S2      
327NNAME11142       R1267 -2          A01X+074893Y+048850X0180Y0200     S2      
327NNAME10860       R1267 -1          A01X+075208Y+048850X0180Y0200     S2      
317GND              VIA   -     D0100PA00X+074830Y+049680               S3      
327GND              C460  -2          A01X+076198Y+055951X0180Y0200R180 S2      
327P1V9_LAN2        C460  -1          A01X+075883Y+055951X0180Y0200R180 S2      
327P1V9_LAN2        C476  -1          A01X+075751Y+056457X0280Y0320R270 S2      
327GND              C476  -2          A01X+076331Y+056457X0280Y0320R270 S2      
327P1V9_LAN2        C475  -1          A01X+075761Y+057047X0280Y0320R270 S2      
327GND              C475  -2          A01X+076341Y+057047X0280Y0320R270 S2      
327P1V9_LAN2        C474  -1          A01X+075894Y+057766X0440Y0540R180 S2      
327P1V9_LAN2        C473  -1          A01X+075893Y+058579X0440Y0540R180 S2      
317P1V9_LAN2        VIA   -     D0100PA00X+075173Y+058305               S3      
317GND              VIA   -     D0100PA00X+075296Y+065397               S1      
317GND              VIA   -     D0100PA00X+074952Y+065837               S3      
317NNAME10769       VIA   -     D0100PA00X+076525Y+035779               S3      
317NNAME10041       VIA   -     D0100PA00X+076561Y+036119               S3      
317GND              VIA   -     D0100PA00X+076684Y+056129               S3      
317GND              VIA   -     D0100PA00X+076692Y+056408               S3      
317GND              VIA   -     D0100PA00X+076695Y+055832               S3      
327GND              C474  -2          A01X+076642Y+057766X0440Y0540R180 S2      
317GND              VIA   -     D0100PA00X+076682Y+056990               S3      
317GND              VIA   -     D0100PA00X+076690Y+056723               S3      
317GND              VIA   -     D0100PA00X+076690Y+057287               S3      
317GND              VIA   -     D0100PA00X+077111Y+057864               S1      
317GND              VIA   -     D0100PA00X+077085Y+057576               S3      
327GND              C473  -2          A01X+076641Y+058579X0440Y0540R180 S2      
317GND              VIA   -     D0100PA00X+077071Y+058405               S3      
317GND              VIA   -     D0100PA00X+077085Y+058703               S1      
P  NNAME10000 UART_RI_P6_LS_N
P  NNAME10001 UART_DTR_P6_L_N
P  NNAME10002 UART_RI_P5_LS_N
P  NNAME10003 UART_DTR_P5_L_N
P  NNAME10004 SMB_MUX_CPU_ICS_NODE1_CLK
P  NNAME10005 PV_VDDR_NODE1_VREF_RW
P  NNAME10006 SMB_MUX_CPU_ICS_NODE1_DAT
P  NNAME10007 PV_VDDR_NODE1_VREF_LM321
P  NNAME10008 UART_RTS_P6_L_N
P  NNAME10009 UART_CTS_P6_L_N
P  NNAME10010 UART_DSR_P6_L_N
P  NNAME10011 UART_RTS_P5_L_N
P  NNAME10012 UART_CTS_P5_L_N
P  NNAME10013 UART_DSR_P5_L_N
P  NNAME10014 SMB_DIMM_NODE1_CLK
P  NNAME10015 SMB_DIMM_NODE1_DAT
P  NNAME10016 PV_VDDR_NODE1_VREF_R
P  NNAME10017 UART_DTR_P2_L_N
P  NNAME10018 UART_RTS_P2_L_N
P  NNAME10019 UART_CTS_P2_L_N
P  NNAME10020 SW_P1V05_NODE1_VIN_FLT
P  NNAME10021 VSENSE_P1V05_NODE1_P
P  NNAME10022 P1V05_NODE1_TRIP
P  NNAME10023 P1V05_NODE1_COMP
P  NNAME10024 P1V05_NODE1_VSNS
P  NNAME10025 UART_DSR_P2_L_N
P  NNAME10026 CONSOLE_SELECT_N
P  NNAME10027 BMC_NODE1_GFX_RED
P  NNAME10028 I2C_VIDREAR_5V_SDA
P  NNAME10029 BMC_NODE1_GFX_GREEN
P  NNAME10030 BMC_NODE1_GFX_BLUE
P  NNAME10031 I2C_VIDREAR_5V_SCL
P  NNAME10032 SW_P1V05_NODE1_DRVH
P  NNAME10033 SW_P1V05_NODE1_DRVL
P  NNAME10034 PWRGD_NODE1_P1V05_PG
P  NNAME10035 P1V05_NODE1_MODE
P  NNAME10036 SW_P1V05_NODE1_BT
P  NNAME10037 SW_P1V05_NODE1_PH
P  NNAME10038 VSENSE_P1V05_NODE1_N
P  NNAME10039 P1V05_NODE1_VREFIN
P  NNAME10040 P1V05_NODE1_VREF
P  NNAME10041 ATTENTION_LED_R
P  NNAME10042 SMB_BMC_NODE1_DDC_DAT
P  NNAME10043 SMB_BMC_NODE1_DDC_CLK
P  NNAME10044 FM_CPLD_NODE1_P1V05_EN
P  NNAME10045 BMC_NODE1_GFX_VSYNC
P  NNAME10046 BMC_NODE1_GFX_HSYNC
P  NNAME10047 FM_CPLD_NODE1_P1V5_SUS_EN
P  NNAME10048 FM_CPLD_NODE1_P1V538_BMC_EN
P  NNAME10049 PWRGD_NODE1_P1V538_BMC_PG
P  NNAME10050 LAN1_CTRL_P1V9_R
P  NNAME10051 UART_CTS_P1_L_N
P  NNAME10052 VR_NODE1_VDDR_1V5_CNTL
P  NNAME10053 P2E_CPU_NIC1_NODE1_TX_DN
P  NNAME10054 P2E_CPU_NIC1_NODE1_TX_DP
P  NNAME10055 P2E_CPU_NIC2_NODE1_RX_DN
P  NNAME10056 P2E_CPU_NIC2_NODE1_RX_DP
P  NNAME10057 P2E_CPU_NIC2_NODE1_TX_DN
P  NNAME10058 P2E_CPU_NIC2_NODE1_TX_DP
P  NNAME10059 PWRGD_NODE1_P1V5_SUS_PG
P  NNAME10060 P1V5_SUS_NODE1_ADJ
P  NNAME10061 FM_CPLD_NODE1_P1V5_EN
P  NNAME10062 FM_CPLD_NODE1_P1V5_EN_G
P  NNAME10063 P1V538_BMC_NODE1
P  NNAME10064 P1V538_BMC_NODE1_ADJ
P  NNAME10065 P1V538_STB_NODE1_ADJ_S
P  NNAME10066 CM_PWR_CTL_IN_R
P  NNAME10067 VR_HSC_NODE1_GATE
P  NNAME10068 SMB_CPU_NODE1_BMC_CLK
P  NNAME10069 SMB_CPU_NODE1_BMC_DAT
P  NNAME10070 VR_HSC_NODE1_GATE_R
P  NNAME10071 VR_HSC_NODE1_TIMER
P  NNAME10072 UART_RI_P6_L_N_R
P  NNAME10073 UART_RI_P5_L_N_R
P  NNAME10074 UART_DTR_P1_L_N
P  NNAME10075 UART_DSR_P1_L_N
P  NNAME10076 PV_VDDR_NODE1_VID0
P  NNAME10077 PWRGD_NODE1_PVDDR_STB_PG
P  NNAME10078 PV_VDDR_NODE1_VREF
P  NNAME10079 PV_VDDR_NODE1_V0
P  NNAME10080 PV_VDDR_NODE1_V1
P  NNAME10081 VSENSE_PV_VDDR_NODE1_N
P  NNAME10082 VSENSE_PV_VDDR_NODE1_P
P  NNAME10083 PV_VDDR_NODE1_SLEW
P  NNAME10084 PV_VDDR_NODE1_TRIP
P  NNAME10085 P1V5_NODE1_DDR3_VREF0_D
P  NNAME10086 P2E_CPU_NIC1_NODE1_TX_C_DN
P  NNAME10087 P2E_CPU_SATA_NODE1_RX_DP
P  NNAME10088 P2E_CPU_SATA_NODE1_RX_DN
P  NNAME10089 P2E_CPU_NIC2_NODE1_TX_C_DP
P  NNAME10090 P2E_CPU_NIC2_NODE1_TX_C_DN
P  NNAME10091 P2E_CPU_NIC1_NODE1_TX_C_DP
P  NNAME10092 TP_CPU_NODE1_RP0_PERN3
P  NNAME10093 TP_CPU_NODE1_RP0_PERP5
P  NNAME10094 TP_CPU_NODE1_RP0_PERN5
P  NNAME10095 TP_CPU_NODE1_RP0_PERP7
P  NNAME10096 TP_CPU_NODE1_RP0_PETN3
P  NNAME10097 P1V8_VCCASFRHPLL_NODE1
P  NNAME10098 PD_CPU_NODE1_RP1_PERN
P  NNAME10099 PD_CPU_NODE1_RP1_PERP
P  NNAME10100 P1V5_NODE1_AJ21
P  NNAME10101 PD_CPU_NODE1_RP2_PERP
P  NNAME10102 PD_NODE1_NTB_PERP
P  NNAME10103 PD_CPU_NODE1_RP2_PERN
P  NNAME10104 PD_CPU_NODE1_W1
P  NNAME10105 PD_CPU_NODE1_Y2
P  NNAME10106 PD_NODE1_NTB_PERN
P  NNAME10107 SMB_CPU_NODE1_MEM_ICS_CLK_R
P  NNAME10108 FM_CPLD_NODE1_P1V5_EN_LV
P  NNAME10109 P0V75_BMC_VTTREF_NODE1
P  NNAME10110 SMB_BMC_NODE1_HSC_ALERT_L
P  NNAME10111 VSENSE_HSC_NODE1
P  NNAME10112 SMB_BMC_NODE1_HSC_ALERT_R_L
P  NNAME10113 UART_RTS_P1_L_N
P  NNAME10114 FM_CPLD_NODE1_PVDDR_STB_EN
P  NNAME10115 SW_PV_VDDR_NODE1_VIN_FLT
P  NNAME10116 PV_VDDR_NODE1_VID1
P  NNAME10117 PV_VDDR_NODE1_EN
P  NNAME10118 SW_PV_VDDR_NODE1_DRVL
P  NNAME10119 SW_PV_VDDR_NODE1_DRVH
P  NNAME10120 SW_PV_VDDR_NODE1_PH
P  NNAME10121 SW_PV_VDDR_NODE1_BT
P  NNAME10122 PV_VDDR_NODE1_MODE
P  NNAME10123 M1_DQ_NODE1_DQ0
P  NNAME10124 M1_DQ_NODE1_DQ4
P  NNAME10125 M1_DQ_NODE1_DQ5
P  NNAME10126 TP_CPU_NODE1_RP0_PLLMON1
P  NNAME10127 TP_CPU_NODE1_RP0_PERP1
P  NNAME10128 TP_CPU_NODE1_RP0_PERP3
P  NNAME10129 P2E_CPU_PCIE_SW_NODE1_TX_DN
P  NNAME10130 P2E_CPU_PCIE_SW_NODE1_TX_C_DN
P  NNAME10131 P2E_CPU_PCIE_SW_NODE1_TX_DP
P  NNAME10132 P2E_CPU_PCIE_SW_NODE1_TX_C_DP
P  NNAME10133 TP_CPU_NODE1_RP0_PERN7
P  NNAME10134 TP_CPU_NODE1_HPLL_MONP
P  NNAME10135 TP_CPU_NODE1_HPLL_MONN
P  NNAME10136 SMB_CPU_NODE1_BMC_CLK_RR
P  NNAME10137 SMB_CPU_NODE1_XDP_CLK_R
P  NNAME10138 SMB_CPU_NODE1_XDP_CLK
P  NNAME10139 P3V3_STB_NODE1_FB
P  NNAME10140 BMC_NODE1_DDR_MA13
P  NNAME10141 BMC_NODE1_DDR_RST_L
P  NNAME10142 BMC_NODE1_DDR_MA9
P  NNAME10143 BMC_NODE1_DDR_MA7
P  NNAME10144 BMC_NODE1_DDR_MA2
P  NNAME10145 BMC_NODE1_DDR_MA5
P  NNAME10146 BMC_NODE1_DDR_MA0
P  NNAME10147 BMC_NODE1_DDR_MA3
P  NNAME10148 BMC_NODE1_DDR_BA2
P  NNAME10149 BMC_NODE1_DDR_BA0
P  NNAME10150 BMC_NODE1_DDR_WE_L
P  NNAME10151 BMC_NODE1_DDR_CS_L
P  NNAME10152 TP_BMC_NODE1_DDR3_CS1_L
P  NNAME10153 BMC_NODE1_DDR_CAS_L
P  NNAME10154 BMC_NODE1_DDR_ODT
P  NNAME10155 BMC_NODE1_DDR_RAS_L
P  NNAME10156 TP_BMC_NODE1_DDR3_ODT_1NC
P  NNAME10157 BMC_NODE1_DDR_D1
P  NNAME10158 BMC_NODE1_DDR_DQS0_DN
P  NNAME10159 BMC_NODE1_DDR_D5
P  NNAME10160 BMC_NODE1_DDR_DQS0_DP
P  NNAME10161 BMC_NODE1_DDR_D4
P  NNAME10162 BMC_NODE1_DDR_D7
P  NNAME10163 BMC_NODE1_DDR_DM1
P  NNAME10164 BMC_NODE1_DDR_D11
P  NNAME10165 BMC_NODE1_DDR_D12
P  NNAME10166 BMC_NODE1_DDR_D14
P  NNAME10167 BMC_NODE1_DDR_D15
P  NNAME10168 LAN1_NC_SI_CLK_IN
P  NNAME10169 LAN1_NC_SI_RXD1
P  NNAME10170 LAN1_NC_SI_CRS_DV
P  NNAME10171 M1_DQ_NODE1_DQ8
P  NNAME10172 M1_DQ_NODE1_DQ3
P  NNAME10173 M1_DQ_NODE1_DQ2
P  NNAME10174 M1_DQ_NODE1_DQ1
P  NNAME10175 M1_DQ_NODE1_DQ6
P  NNAME10176 M1_DQ_NODE1_DQ13
P  NNAME10177 M1_DQ_NODE1_DQ7
P  NNAME10178 M_DDR3_NODE1_DQS0P
P  NNAME10179 M_DDR3_NODE1_DQS0N
P  NNAME10180 M1_DQ_NODE1_DQ12
P  NNAME10181 M1_DQ_NODE1_DQ10
P  NNAME10182 P2E_CPU_SATA_NODE1_TX_DP
P  NNAME10183 P2E_CPU_SATA_NODE1_TX_C_DP
P  NNAME10184 P2E_CPU_SATA_NODE1_TX_DN
P  NNAME10185 P2E_CPU_SATA_NODE1_TX_C_DN
P  NNAME10186 TP_CPU_NODE1_RP0_PLLMON0
P  NNAME10187 TP_CPU_NODE1_RP0_PERN1
P  NNAME10188 P2E_CPU_NIC1_NODE1_RX_DN
P  NNAME10189 P2E_CPU_NIC1_NODE1_RX_DP
P  NNAME10190 TP_CPU_NODE1_RP0_PETP3
P  NNAME10191 CLK_100M_PCIE_RP0_NODE1_DN
P  NNAME10192 CLK_100M_PCIE_RP0_NODE1_DP
P  NNAME10193 TP_CPU_NODE1_RP0_PETP5
P  NNAME10194 P2E_CPU_PCIE_SW_NODE1_RX_DP
P  NNAME10195 P2E_CPU_PCIE_SW_NODE1_RX_DN
P  NNAME10196 TP_CPU_NODE1_RP0_PETP7
P  NNAME10197 PD_CPU_NODE1_AN5
P  NNAME10198 PD_CPU_NODE1_AL5
P  NNAME10199 SMB_CPU_NODE1_BMC_DAT_RR
P  NNAME10200 SMB_CPU_NODE1_MEM_ICS_DAT_R
P  NNAME10201 A_SOC_NODE1_THERMDA
P  NNAME10202 SMB_TEMP1_NODE1_ALERT_R_L
P  NNAME10203 A_SOC_NODE1_THERMDC
P  NNAME10204 PWRGD_NODE1_P3V3_STB_PG
P  NNAME10205 P3V3_STB_NODE1_VREG5
P  NNAME10206 P3V3_STB_NODE1_EN
P  NNAME10207 PWRGD_NODE1_P5V_STB_PG
P  NNAME10208 P3V3_STB_NODE1_SS
P  NNAME10209 FM_BMC_NODE1_RESET_L
P  NNAME10210 BMC_NODE1_DDR_MA8
P  NNAME10211 BMC_NODE1_DDR_MA14
P  NNAME10212 BMC_NODE1_DDR_MA6
P  NNAME10213 BMC_NODE1_DDR_MA11
P  NNAME10214 BMC_NODE1_DDR_MA4
P  NNAME10215 BMC_NODE1_DDR_MA1
P  NNAME10216 BMC_NODE1_DDR_BA1
P  NNAME10217 BMC_NODE1_DDR_MA12
P  NNAME10218 BMC_NODE1_DDR_MA10
P  NNAME10219 TP_BMC_NODE1_DDR3_MA15
P  NNAME10220 BMC_NODE1_DDR3_ZQ
P  NNAME10221 BMC_NODE1_DDR_CLK_DN
P  NNAME10222 BMC_NODE1_DDR_CLK_DP
P  NNAME10223 BMC_NODE1_DDR_D6
P  NNAME10224 BMC_NODE1_DDR_D0
P  NNAME10225 BMC_NODE1_DDR_D2
P  NNAME10226 BMC_NODE1_DDR_D3
P  NNAME10227 BMC_NODE1_DDR_DM0
P  NNAME10228 BMC_NODE1_DDR_D8
P  NNAME10229 BMC_NODE1_DDR_D13
P  NNAME10230 BMC_NODE1_DDR_DQS1_DP
P  NNAME10231 BMC_NODE1_DDR_D9
P  NNAME10232 BMC_NODE1_DDR_DQS1_DN
P  NNAME10233 BMC_NODE1_DDR_D10
P  NNAME10234 LAN1_NC_SI_TDX0
P  NNAME10235 LAN1_NC_SI_TX_EN
P  NNAME10236 LAN1_NC_SI_RXD0
P  NNAME10237 LAN1_NC_SI_TDX1
P  NNAME10238 CPLD_THRMTRIP_LOG_N
P  NNAME10239 M_DDR3_NODE1_DQS1P
P  NNAME10240 M_DDR3_NODE1_DQS1N
P  NNAME10241 M1_DQ_NODE1_DQ9
P  NNAME10242 M1_DQ_NODE1_DQ11
P  NNAME10243 M1_DQ_NODE1_DQ14
P  NNAME10244 M_NODE1_DIMM_RST_L
P  NNAME10245 M1_DQ_NODE1_DQ21
P  NNAME10246 TP_CPU_NODE1_RP0_PETN7
P  NNAME10247 TP_CPU_NODE1_RP0_PETN5
P  NNAME10248 TP_CPU_NODE1_RP0_PETN1
P  NNAME10249 TP_CPU_NODE1_RP0_PETP1
P  NNAME10250 PD_CPU_NODE1_AM23
P  NNAME10251 TP_P1V8_VCCABGTS_NODE1
P  NNAME10252 SMB_CPU_NODE1_XDP_DAT_R
P  NNAME10253 TP_CPU_NODE1_SOC_THERMATP0
P  NNAME10254 P1V5_NODE1_AA21
P  NNAME10255 PD_NODE1_NTB_CLKINP
P  NNAME10256 PD_NODE1_NTB_CLKINN
P  NNAME10257 SMB_CPU_NODE1_XDP_DAT
P  NNAME10258 TP_TEMP1_NODE1_1
P  NNAME10259 TP_TEMP1_NODE1_2
P  NNAME10260 TP_TEMP1_NODE1_3
P  NNAME10261 SMB_TEMP1_NODE1_ALERT_L
P  NNAME10262 SW_P3V3_STB_NODE1_BT
P  NNAME10263 SW_P3V3_STB_NODE1_PH
P  NNAME10264 TP_BMC_NODE1_DDR3_ZQ1
P  NNAME10265 BMC_NODE1_DDR_CKE
P  NNAME10266 TP_BMC_NODE1_DDR3_CE1_NC1
P  NNAME10267 SPI_LAN1_NVM_CS_N
P  NNAME10268 SPI_LAN1_NVM_SI
P  NNAME10269 IRQ_LVC3_CPU_NODE1_WAKE_L
P  NNAME10270 SPI_LAN1_NVM_SO
P  NNAME10271 SPI_LAN1_NVM_SK
P  NNAME10272 CLK_100M_NIC1_NODE1_DP
P  NNAME10273 CLK_100M_NIC1_NODE1_DN
P  NNAME10274 PCIE_LAN1_RX_C_DP
P  NNAME10275 PCIE_LAN1_RX_C_DN
P  NNAME10276 LAN1_LED_LINK_100_N
P  NNAME10277 LAN1_LED_LINK_1000_N
P  NNAME10278 PSU6_DC_OK_R_BUF
P  NNAME10279 PSU5_DC_OK_R_BUF
P  NNAME10280 PSU4_DC_OK_R_BUF
P  NNAME10281 M_DDR3_NODE1_DQS2P
P  NNAME10282 M_DDR3_NODE1_DQS2N
P  NNAME10283 M1_DQ_NODE1_DQ17
P  NNAME10284 M1_DQ_NODE1_DQ16
P  NNAME10285 M1_DQ_NODE1_DQ20
P  NNAME10286 M1_DQ_NODE1_DQ15
P  NNAME10287 M1_DQ_NODE1_DQ26
P  NNAME10288 M1_DQ_NODE1_DQ30
P  NNAME10289 M1_DQ_NODE1_DQ31
P  NNAME10290 M_DDR3_NODE1_DQS3N
P  NNAME10291 M1_DQ_NODE1_DQ24
P  NNAME10292 M1_DQ_NODE1_DQ28
P  NNAME10293 M_DDR3_NODE1_DQS3P
P  NNAME10294 M1_DQ_NODE1_DQ18
P  NNAME10295 A_NODE1_RP0_RCOMP
P  NNAME10296 P1V5_SFRPLL_NODE1
P  NNAME10297 P1V5_NODE1_AM21
P  NNAME10298 PD_CPU_NODE1_AJ23
P  NNAME10299 PD_NODE1_NTB_RCOMP
P  NNAME10300 A_CPU_NODE1_SOC_THERMREFNPAD
P  NNAME10301 TP_CPU_NODE1_SOC_THERMATP1
P  NNAME10302 CLK_100M_CPU_NODE1_DP
P  NNAME10303 CLK_100M_CPU_NODE1_DN
P  NNAME10304 PD_CPU_NODE1_DFX_GPIO_GRP0_7
P  NNAME10305 PD_CPU_NODE1_DFX_GPIO_GRP0_1
P  NNAME10306 PD_CPU_NODE1_DFX_GPIO_GRP1_7
P  NNAME10307 A_CPU0_NODE1_THERMDC
P  NNAME10308 A_CPU0_NODE1_THERMDA
P  NNAME10309 PU_CPU_NODE1_DFX_GPIO_GRP1_5
P  NNAME10310 A_CPU1_NODE1_THERMDC
P  NNAME10311 A_CPU1_NODE1_THERMDA
P  NNAME10312 PU_TEMP1_NODE1_SYS_SHDN_L
P  NNAME10313 PU_EMC1428_NODE1_TRIP
P  NNAME10314 BMC_NODE1_OSC1_VDD
P  NNAME10315 BMC_NODE1_OSC1_EN
P  NNAME10316 BMC_NODE1_V1PLLAV12
P  NNAME10317 P1V26_BMC_NODE1
P  NNAME10318 LAN1_NVM_CS_N_R
P  NNAME10319 FM_CPLD_NODE1_CPU_RESET_L
P  NNAME10320 PCH_I2C_ALERT_N
P  NNAME10321 PSU1_DC_OK_R_BUF
P  NNAME10322 PSU2_DC_OK_R_BUF
P  NNAME10323 PSU3_DC_OK_R_BUF
P  NNAME10324 UART_T1_NODE1_RXD_R
P  NNAME10325 UART_T1_NODE1_TXD_R
P  NNAME10326 UART_T1_NODE4_TXD_R
P  NNAME10327 M1_DQ_NODE1_DQ25
P  NNAME10328 M1_DQ_NODE1_DQ19
P  NNAME10329 M1_DQ_NODE1_DQ22
P  NNAME10330 M1_DQ_NODE1_DQ23
P  NNAME10331 M1_DQ_NODE1_DQ29
P  NNAME10332 M_DDR3_NODE1_MON1P
P  NNAME10333 M_DDR3_NODE1_MA12
P  NNAME10334 M_DDR3_NODE1_CMDPU
P  NNAME10335 M_DDR3_NODE1_ODTPU
P  NNAME10336 M_DDR3_NODE1_MA14
P  NNAME10337 M1_DQ_NODE1_DQ27
P  NNAME10338 M_DDR3_NODE1_MA15
P  NNAME10339 M_DDR3_NODE1_BS2
P  NNAME10340 M_DDR3_NODE1_DQPU
P  NNAME10341 PWRGD_NODE1_DDR3_SYSPWRGD
P  NNAME10342 P1V05_VCCACLK_DDR3_NODE1
P  NNAME10343 A_CPU_NODE1_MV_GPIO_RCOMP
P  NNAME10344 FM_NODE1_DFX_GPIO_GRP05
P  NNAME10345 PD_CPU_NODE1_DFX_GPIO_GRP0_6
P  NNAME10346 PD_CPU_NODE1_DFX_GPIO_GRP0_4
P  NNAME10347 PD_CPU_NODE1_DFX_GPIO_GRP0_3
P  NNAME10348 PD_CPU_NODE1_DFX_GPIO_GRP0_2
P  NNAME10349 PD_CPU_NODE1_DFX_GPIO_GRP0_0
P  NNAME10350 PU_CPU_NODE1_DFX_GPIO_GRP1_6
P  NNAME10351 PU_CPU_NODE1_DFX_GPIO_GRP1_3
P  NNAME10352 PD_CPU_NODE1_DFX_GPIO_GRP1_0
P  NNAME10353 PD_CPU_NODE1_DFX_GPIO_GRP1_2
P  NNAME10354 H_CPU_NODE1_THRM_LS_L
P  NNAME10355 BMC_NODE1_CLK_24M_R
P  NNAME10356 BMC_NODE1_HPLLAV33
P  NNAME10357 BMC_NODE1_CLK_24M
P  NNAME10358 BMC_NODE1_MPLLAV33
P  NNAME10359 BMC_NODE1_USBVREF
P  NNAME10360 BMC_NODE1_DDR_IOZ
P  NNAME10361 BMC_NODE1_GFX_VSYNC_R
P  NNAME10362 BMC_NODE1_GFX_HSYNC_R
P  NNAME10363 BMC_NODE1_DACRSET
P  NNAME10364 LAN1_NVM_HOLD_N
P  NNAME10365 UART_T1_NODE1_RXD
P  NNAME10366 UART_T1_NODE4_TXD
P  NNAME10367 UART_T2_NODE4_TXD
P  NNAME10368 UART_T1_NODE4_RXD
P  NNAME10369 UART_T2_NODE4_RXD
P  NNAME10370 UART_T1_NODE1_TXD
P  NNAME10371 UART_T2_NODE4_TXD_R
P  NNAME10372 UART_T1_NODE4_RXD_R
P  NNAME10373 UART_T2_NODE4_RXD_R
P  NNAME10374 UART_T1_NODE3_TXD_R
P  NNAME10375 UART_T2_NODE3_TXD_R
P  NNAME10376 UART_T1_NODE3_RXD_R
P  NNAME10377 UART_T2_NODE3_RXD_R
P  NNAME10378 M_DDR3_NODE1_ECC1
P  NNAME10379 M_DDR3_NODE1_ECC0
P  NNAME10380 M_DDR3_NODE1_ECC4
P  NNAME10381 M_DDR3_NODE1_MON1N
P  NNAME10382 M_DDR3_NODE1_MA8
P  NNAME10383 M_DDR3_NODE1_MON2P
P  NNAME10384 M_DDR3_NODE1_MA9
P  NNAME10385 M_DDR3_NODE1_MA6
P  NNAME10386 M_DDR3_NODE1_MA2
P  NNAME10387 M_DDR3_NODE1_MA5
P  NNAME10388 M_DDR3_NODE1_MA4
P  NNAME10389 M_DDR3_NODE1_MA0
P  NNAME10390 M_DDR3_NODE1_MA1
P  NNAME10391 M_DDR3_NODE1_MA3
P  NNAME10392 M_DDR3_NODE1_CK1P
P  NNAME10393 M_DDR3_NODE1_MON2N
P  NNAME10394 M_DDR3_NODE1_MA7
P  NNAME10395 M_DDR3_NODE1_MA11
P  NNAME10396 P1V05_VCCPLL_DDR3_NODE1
P  NNAME10397 PV_VDDR_VCCCLK_DDR3_NODE1
P  NNAME10398 M_DDR3_NODE1_CK0P
P  NNAME10399 TP_CPU_NODE1_VCCCPU1VIDSI0GT1P0
P  NNAME10400 VSENSE_VSS_CPU_NODE1
P  NNAME10401 TP_CPU_NODE1_VCCCPU0VIDSI0GT1P0
P  NNAME10402 VSENSE_VCC_CPU_NODE1
P  NNAME10403 A_CPU_NODE1_HV_GPIO_RCOMP
P  NNAME10404 TP_CPU_NODE1_EXTBGREF
P  NNAME10405 SPI_CPU_NODE1_MISO
P  NNAME10406 LPC_CPU_NODE1_LAD3_R
P  NNAME10407 LPC_CPU_NODE1_LAD1_R
P  NNAME10408 TP_CPU_NODE1_RSVD_MVT1
P  NNAME10409 SPI_CPU_NODE1_SCLK_R
P  NNAME10410 PD_CPU_NODE1_DFX_GPIO_GRP1_1
P  NNAME10411 TP_CPU1_NODE1_SFRANAD
P  NNAME10412 TP_SPI_CPU_NODE1_CS1_L
P  NNAME10413 LPC_CPU_NODE1_LAD2_R
P  NNAME10414 TP_CPU_NODE1_RSVD_MVT0
P  NNAME10415 A_CPU_NODE1_NTB_CROSSLK_MODE
P  NNAME10416 PD_CPU_NODE1_DFX_GPIO_GRP1_4
P  NNAME10417 TP_CPU0_NODE1_SFRANAD
P  NNAME10418 SPI_CPU_NODE1_CS0_R_L
P  NNAME10419 LPC_CPU_NODE1_LAD2
P  NNAME10420 SPI_CPU_NODE1_SCLK
P  NNAME10421 LPC_CPU_NODE1_LAD1
P  NNAME10422 LPC_CPU_NODE1_LAD3
P  NNAME10423 LPC_CPU_NODE1_LAD0
P  NNAME10424 IRQ_CPU_NODE1_SERIAL
P  NNAME10425 SPI_CPU_NODE1_CS0_L
P  NNAME10426 BMC_NODE1_DACAV33
P  NNAME10427 FM_CPLD_NODE1_P5V_EN_LV
P  NNAME10428 FM_CPLD_NODE1_P5V_EN
P  NNAME10429 FM_CPLD_NODE1_P5V_NODE1_EN_G
P  NNAME10430 UART_T1_NODE2_TXD
P  NNAME10431 UART_T1_NODE3_TXD
P  NNAME10432 UART_T2_NODE3_RXD
P  NNAME10433 UART_T1_NODE3_RXD
P  NNAME10434 UART_T1_NODE2_TXD_R
P  NNAME10435 UART_T2_NODE2_TXD_R
P  NNAME10436 UART_T2_NODE2_TXD
P  NNAME10437 UART_T2_NODE3_TXD
P  NNAME10438 UART_T2_NODE2_RXD
P  NNAME10439 UART_T2_NODE2_RXD_R
P  NNAME10440 UART_T1_NODE2_RXD_R
P  NNAME10441 UART_T2_NODE1_TXD_R
P  NNAME10442 M_DDR3_NODE1_DQSECCP
P  NNAME10443 M_DDR3_NODE1_DQSECCN
P  NNAME10444 M_DDR3_NODE1_ECC6
P  NNAME10445 M_DDR3_NODE1_ECC5
P  NNAME10446 M_DDR3_NODE1_CKE1
P  NNAME10447 M_DDR3_NODE1_BS0
P  NNAME10448 M_DDR3_NODE1_CKE0
P  NNAME10449 M_DDR3_NODE1_WE_L
P  NNAME10450 M_DDR3_NODE1_CS1_L
P  NNAME10451 M_DDR3_NODE1_CAS_L
P  NNAME10452 M_DDR3_NODE1_CS0_L
P  NNAME10453 M_DDR3_NODE1_RAS_L
P  NNAME10454 M_DDR3_NODE1_MA10
P  NNAME10455 M_DDR3_NODE1_ODT1
P  NNAME10456 M_DDR3_NODE1_MA13
P  NNAME10457 PWRGD_NODE1_DDR3_DRAM_POK
P  NNAME10458 M_DDR3_NODE1_BS1
P  NNAME10459 CLK_100M_DDR3_NODE1_DP
P  NNAME10460 CLK_100M_DDR3_NODE1_DN
P  NNAME10461 M_DDR3_NODE1_CK1N
P  NNAME10462 M_DDR3_NODE1_ODT0
P  NNAME10463 M_DDR3_NODE1_CK0N
P  NNAME10464 PD_CPU_NODE1_PUNIT_ST_ADDR1
P  NNAME10465 TP_CPU_NODE1_VCCCPU1VIDSI0GT1_1
P  NNAME10466 TP_CPU_NODE1_VCCCPU0VIDSI0GT1_1
P  NNAME10467 PD_CPU_NODE1_PUNIT_ST_ADDR0
P  NNAME10468 PD_CPU_NODE1_SPD_EN_L
P  NNAME10469 P1V05_VCCPLLCPU0SIO_NODE1
P  NNAME10470 P1V05_VCCPLLCPU1SIO_NODE1
P  NNAME10471 A_CPU_NODE1_LV_GPIO_RCOMP
P  NNAME10472 PD_CPU_NODE1_BRD_ID1
P  NNAME10473 CLK_14M_CPU_NODE1
P  NNAME10474 P1V05_SUS_NODE1
P  NNAME10475 NODE1_BIOS_MB_REV_ID0
P  NNAME10476 SPC_CPU_NODE1_DSR_L
P  NNAME10477 IRQ_CPU_NODE1_SERIAL_R
P  NNAME10478 SPC_CPU_NODE1_DCD_L
P  NNAME10479 LPC_CPU_NODE1_LAD0_R
P  NNAME10480 SPI_CPU_NODE1_MOSI_R
P  NNAME10481 LPC_CPU_NODE1_FRAME_L_R
P  NNAME10482 H_CPU_NODE1_ERR0_R
P  NNAME10483 LPC_CPU_NODE1_CLKRUN_L
P  NNAME10484 LPC_CPU_NODE1_R_CLKOUT0
P  NNAME10485 LPC_CPU_NODE1_R_CLKOUT1
P  NNAME10486 SPC_CPU_NODE1_DTR_L
P  NNAME10487 SPC_CPU_NODE1_RI_L
P  NNAME10488 SPC_CPU_NODE1_CTS_L
P  NNAME10489 FM_CPLD_NODE1_P1V8_SUS_EN_LV
P  NNAME10490 SPI_CPU_NODE1_MOSI
P  NNAME10491 FM_CPLD_NODE1_P1V8_EN_G
P  NNAME10492 FM_CPLD_NODE1_P1V8_EN
P  NNAME10493 FM_CPLD_NODE1_P1V8_EN_LV
P  NNAME10494 BMC_NODE1_ADCAV33
P  NNAME10495 BMC_NODE1_ADCREXT
P  NNAME10496 UART_T1_NODE2_RXD
P  NNAME10497 UART_T2_NODE1_RXD
P  NNAME10498 UART_T2_NODE1_TXD
P  NNAME10499 UART_T2_NODE1_RXD_R
P  NNAME10500 PWRGD_NODE1_P3V3_PG
P  NNAME10501 P3V3_NODE1_VREG5
P  NNAME10502 FM_CPLD_NODE1_P3V3_S_EN
P  NNAME10503 FM_CPLD_NODE1_P3V3_EN
P  NNAME10504 M_DDR3_NODE1_ECC3
P  NNAME10505 M_DDR3_NODE1_ECC2
P  NNAME10506 M_DDR3_NODE1_ECC7
P  NNAME10507 P1V5_NODE1_DDR3_VREF_A_A
P  NNAME10508 M1_DQ_NODE1_DQ39
P  NNAME10509 M_DDR3_NODE1_DQS4N
P  NNAME10510 M1_DQ_NODE1_DQ34
P  NNAME10511 M1_DQ_NODE1_DQ32
P  NNAME10512 M_DDR3_NODE1_DQS4P
P  NNAME10513 M1_DQ_NODE1_DQ33
P  NNAME10514 M1_DQ_NODE1_DQ36
P  NNAME10515 M1_DQ_NODE1_DQ38
P  NNAME10516 M1_DQ_NODE1_DQ46
P  NNAME10517 M1_DQ_NODE1_DQ47
P  NNAME10518 XDP_CPU_NODE1_VISA14
P  NNAME10519 XDP_CPU_NODE1_VISA0
P  NNAME10520 XDP_CPU_NODE1_VISA3
P  NNAME10521 M1_DQ_NODE1_DQ44
P  NNAME10522 XDP_CPU_NODE1_VISA16
P  NNAME10523 XDP_CPU_NODE1_VISA10
P  NNAME10524 TP_CPU0_NODE1_HFPLL
P  NNAME10525 XDP_CPU_NODE1_VISA1
P  NNAME10526 XDP_CPU_NODE1_VISA4
P  NNAME10527 FM_CPU_NODE1_OWDTOUT
P  NNAME10528 XDP_CPU_NODE1_VISA9
P  NNAME10529 XDP_CPU_NODE1_VISA15
P  NNAME10530 XDP_CPU_NODE1_VISA13
P  NNAME10531 XDP_CPU_NODE1_VISA7
P  NNAME10532 TP_CPU1_NODE1_HFPLL
P  NNAME10533 PD_CPU_NODE1_HVMGEAR_SEL
P  NNAME10534 XDP_CPU_NODE1_PRDY_L
P  NNAME10535 TP_CPU_NODE1_IERR_LV
P  NNAME10536 FM_CPU_NODE1_JTAG_POK
P  NNAME10537 PD_CPU_NODE1_MEM_SPEED1
P  NNAME10538 PU_CPU_NODE1_MEM_SPEED0
P  NNAME10539 H_CPU_NODE1_PROCHOT_R
P  NNAME10540 CLK_33K_CPU_NODE1_SUSCLK_RR
P  NNAME10541 FM_CPU_NODE1_RSTWARN
P  NNAME10542 FM_CPU_NODE1_SLPMODE
P  NNAME10543 FM_CPLD_NODE1_PWR_BTN_CPU
P  NNAME10544 TP_CPU_NODE1_M52
P  NNAME10545 FM_CPU_NODE1_RSTRDY_L
P  NNAME10546 FM_CPU_NODE1_SLPRDY_L
P  NNAME10547 H_CPU_NODE1_ERR1
P  NNAME10548 NODE1_BIOS_MB_REV_ID1
P  NNAME10549 H_CPU_NODE1_ERR2
P  NNAME10550 SPC_CPU_NODE1_RTS_L
P  NNAME10551 PD_CPU_NODE1_BOOTDEVSEL
P  NNAME10552 H_CPU_NODE1_ERR1_R
P  NNAME10553 CPU_NODE1_PROCHOT_N
P  NNAME10554 TP_CPU_NODE1_C2F_LP_MODE
P  NNAME10555 H_CPU_NODE1_ERR2_R
P  NNAME10556 PU_CPU_NODE1_BRD_ID0
P  NNAME10557 PD_CPU_NODE1_NODE_ID
P  NNAME10558 TP_CPU_NODE1_ADR_COMPLETE
P  NNAME10559 LPC_CPU_NODE1_FRAME_L
P  NNAME10560 LPC_CPU_NODE1_CLKOUT0
P  NNAME10561 LPC_CPU_NODE1_CLKOUT1
P  NNAME10562 FM_CPLD_NODE1_P1V8_SUS_EN
P  NNAME10563 FM_CPLD_NODE1_P1V8_SUS_EN_G
P  NNAME10564 IRQ_LVC3_CPU_NODE1_WAKE_R_L
P  NNAME10565 RST_BMC_NODE1_PERST_L
P  NNAME10566 BMC_NODE1_VCC_1V8_PCIE
P  NNAME10567 CLK_100M_BMC_NODE1_DP
P  NNAME10568 CLK_100M_BMC_NODE1_DN
P  NNAME10569 TP_BMC_NODE1_ADCVREFN
P  NNAME10570 TP_BMC_NODE1_ADCVREFP
P  NNAME10571 BMC_NODE1_JTAG_TMS
P  NNAME10572 BMC_NODE1_JTAG_TDI
P  NNAME10573 UART_T3_NODE4_RXD
P  NNAME10574 UART_T3_NODE4_TXD_R
P  NNAME10575 UART_T3_NODE4_TXD
P  NNAME10576 UART_T3_NODE4_RXD_R
P  NNAME10577 UART_T3_NODE3_TXD_R
P  NNAME10578 UART_T3_NODE3_RXD_R
P  NNAME10579 UART_T4_NODE4_TXD_R
P  NNAME10580 SW_P3V3_NODE1_BT
P  NNAME10581 SW_P3V3_NODE1_PH
P  NNAME10582 M1_DQ_NODE1_DQ35
P  NNAME10583 M1_DQ_NODE1_DQ37
P  NNAME10584 M_DDR3_NODE1_DQS5P
P  NNAME10585 M_DDR3_NODE1_DQS5N
P  NNAME10586 M1_DQ_NODE1_DQ43
P  NNAME10587 M1_DQ_NODE1_DQ40
P  NNAME10588 M1_DQ_NODE1_DQ42
P  NNAME10589 M1_DQ_NODE1_DQ50
P  NNAME10590 M1_DQ_NODE1_DQ54
P  NNAME10591 M1_DQ_NODE1_DQ41
P  NNAME10592 M1_DQ_NODE1_DQ45
P  NNAME10593 XDP_CPU_NODE1_VISA17
P  NNAME10594 M1_DQ_NODE1_DQ51
P  NNAME10595 XDP_CPU_NODE1_VISA6
P  NNAME10596 XDP_CPU_NODE1_VISA5
P  NNAME10597 XDP_CPU_NODE1_VISA2
P  NNAME10598 M_DDR3_NODE1_DQS6N
P  NNAME10599 M1_DQ_NODE1_DQ55
P  NNAME10600 M_DDR3_NODE1_DQS6P
P  NNAME10601 M1_DQ_NODE1_DQ57
P  NNAME10602 M1_DQ_NODE1_DQ49
P  NNAME10603 M1_DQ_NODE1_DQ53
P  NNAME10604 M1_DQ_NODE1_DQ52
P  NNAME10605 M1_DQ_NODE1_DQ56
P  NNAME10606 XDP_CPU_NODE1_VISA8
P  NNAME10607 XDP_CPU_NODE1_VISA11
P  NNAME10608 XDP_CPU_NODE1_VISA12
P  NNAME10609 M1_DQ_NODE1_DQ62
P  NNAME10610 M1_DQ_NODE1_DQ61
P  NNAME10611 M1_DQ_NODE1_DQ59
P  NNAME10612 M_DDR3_NODE1_DQS7P
P  NNAME10613 M_DDR3_NODE1_DQS7N
P  NNAME10614 M1_DQ_NODE1_DQ63
P  NNAME10615 M1_DQ_NODE1_DQ60
P  NNAME10616 SVID_CPU_NODE1_PVCCP_DAT_R
P  NNAME10617 H_CPU_NODE1_THRMTRIP_L
P  NNAME10618 PWRGD_CPU_NODE1_EPWRGOOD
P  NNAME10619 XDP_CPU_NODE1_PREQ_L
P  NNAME10620 XDP_SOC_CPU_NODE1_TCK
P  NNAME10621 XDP_SOC_CPU_NODE1_TRST_L
P  NNAME10622 SVID_CPU_NODE1_PVCCP_CLK
P  NNAME10623 XDP_SOC_CPU_NODE1_TMS
P  NNAME10624 A_CPU_NODE1_AE64_PU
P  NNAME10625 SVID_CPU_NODE1_PVCCP_ALERT_R_L
P  NNAME10626 XDP_SOC_CPU_NODE1_TDO
P  NNAME10627 RST_CPU_NODE1_SRTCRST_L
P  NNAME10628 XTAL_CPU_NODE1_X1PAD
P  NNAME10629 LPC_CPU_NODE1_CLK0_DS
P  NNAME10630 XTAL_CPU_NODE1_X2PAD
P  NNAME10631 SPI_CPU_NODE1_WP_R_L
P  NNAME10632 TP_CPU_NODE1_K62
P  NNAME10633 USB_NODE1_SMI_L
P  NNAME10634 NODE1_BIOS_MB_REV_ID2
P  NNAME10635 FM_CPLD_NODE1_CPU_RSMRST_L
P  NNAME10636 A_CPU_NODE1_RTC_EXTPAD
P  NNAME10637 VR_CPU_NODE1_INTVRMEN
P  NNAME10638 FM_CPLD_NODE1_SYS_PG
P  NNAME10639 H_CPU_NODE1_ERR0
P  NNAME10640 FM_CPLD_NODE1_BMC_PERST_L
P  NNAME10641 PE_SW_BMC_PERST_L
P  NNAME10642 P2E_CPU_BMC_NODE1_TX_DN
P  NNAME10643 P2E_CPU_BMC_NODE1_TX_DP
P  NNAME10644 P2E_CPU_BMC_NODE1_RX_C_DP
P  NNAME10645 P2E_CPU_BMC_NODE1_RX_C_DN
P  NNAME10646 BMC_NODE1_VCC_1V8_PCIEA
P  NNAME10647 PD_BMC_NODE1_PEREXT
P  NNAME10648 BMC_NODE1_JTAG_TCK
P  NNAME10649 BMC_NODE1_JTAG_TRST
P  NNAME10650 SW_P5V_STB_NODE1_PH
P  NNAME10651 UART_T3_NODE1_TXD
P  NNAME10652 UART_T3_NODE2_RXD
P  NNAME10653 UART_T3_NODE3_RXD
P  NNAME10654 UART_T3_NODE3_TXD
P  NNAME10655 UART_T4_NODE4_TXD
P  NNAME10656 UART_T4_NODE3_TXD
P  NNAME10657 UART_T4_NODE4_RXD
P  NNAME10658 UART_T4_NODE3_RXD
P  NNAME10659 UART_T4_NODE3_TXD_R
P  NNAME10660 UART_T3_NODE2_TXD_R
P  NNAME10661 UART_T3_NODE2_RXD_R
P  NNAME10662 UART_T4_NODE4_RXD_R
P  NNAME10663 UART_T4_NODE3_RXD_R
P  NNAME10664 UART_T3_NODE1_TXD_R
P  NNAME10665 TP_DDR3_NODE1_CS3_L
P  NNAME10666 M1_DQ_NODE1_DQ48
P  NNAME10667 M1_DQ_NODE1_DQ58
P  NNAME10668 SVID_CPU_NODE1_PVCCP_DAT
P  NNAME10669 XDP_SOC_CPU_NODE1_TDI
P  NNAME10670 CLK_33K_CPU_NODE1_SUSCLK
P  NNAME10671 CLK_33K_CPU_NODE1_SUSCLK_R
P  NNAME10672 FM_OSC_NODE1_OSC_NC
P  NNAME10673 P2E_CPU_BMC_NODE1_RX_DP
P  NNAME10674 P2E_CPU_BMC_NODE1_RX_DN
P  NNAME10675 SW_P5V_STB_NODE1_BT
P  NNAME10676 P5V_STB_NODE1_EN
P  NNAME10677 UART_T3_NODE2_TXD
P  NNAME10678 UART_T3_NODE1_RXD
P  NNAME10679 UART_T4_NODE2_RXD
P  NNAME10680 UART_T4_NODE2_TXD_R
P  NNAME10681 UART_T4_NODE2_TXD
P  NNAME10682 UART_T4_NODE1_TXD_R
P  NNAME10683 UART_T3_NODE1_RXD_R
P  NNAME10684 UART_T4_NODE2_RXD_R
P  NNAME10685 UART_T4_NODE1_RXD_R
P  NNAME10686 TP_DDR3_NODE1_CS2_L
P  NNAME10687 H_CPU_NODE1_PROCHOT_L
P  NNAME10688 SVID_CPU_NODE1_PVCCP_ALERT_L
P  NNAME10689 SPI_CPU_NODE1_WP_L
P  NNAME10690 FM_CPLD_NODE1_P3V3_SUS_EN_LV
P  NNAME10691 FM_CPLD_NODE1_P3V3_SUS_EN
P  NNAME10692 P1V26_BMC_NODE1_ADJ
P  NNAME10693 P5V_STB_NODE1_SS
P  NNAME10694 P5V_STB_NODE1_VREG5
P  NNAME10695 P5V_STB_NODE1_FB
P  NNAME10696 P5V_STB_NODE1_EN_P
P  NNAME10697 UART_T4_NODE1_RXD
P  NNAME10698 UART_T5_NODE4_TXD_R
P  NNAME10699 FM_CPLD_NODE1_P3V3_SUS_EN_G
P  NNAME10700 P1V26_STB_NODE1_ADJ_S
P  NNAME10701 PWRGD_NODE1_P1V26_BMC_PG
P  NNAME10702 FM_CPLD_NODE1_P1V26_BMC_EN
P  NNAME10703 UART_T4_NODE1_TXD
P  NNAME10704 UART_T6_NODE3_TXD
P  NNAME10705 UART_T6_NODE4_TXD
P  NNAME10706 UART_T5_NODE3_RXD
P  NNAME10707 UART_T5_NODE4_RXD_R
P  NNAME10708 UART_T5_NODE3_TXD_R
P  NNAME10709 SPI_CPU_NODE1_MISO_R
P  NNAME10710 SPI_CPU_NODE1_HOLD_L
P  NNAME10711 FM_CPLD_NODE1_LPCRST_L
P  NNAME10712 UART_T5_NODE1_TXD
P  NNAME10713 CPLD_FAN_MAX_CTRL
P  NNAME10714 UART_T5_NODE1_RXD
P  NNAME10715 UART_T6_NODE1_TXD
P  NNAME10716 UART_T5_NODE4_RXD
P  NNAME10717 UART_T5_NODE4_TXD
P  NNAME10718 UART_T5_NODE3_TXD
P  NNAME10719 UART_T5_NODE2_RXD
P  NNAME10720 UART_T5_NODE2_TXD
P  NNAME10721 UART_T6_NODE1_RXD
P  NNAME10722 UART_T6_NODE3_RXD
P  NNAME10723 UART_T6_NODE2_RXD
P  NNAME10724 UART_T6_NODE2_TXD
P  NNAME10725 CPLD_UART_DTR_P4_N
P  NNAME10726 CPLD_UART_TX_P4
P  NNAME10727 CPLD_UART_RX_P4
P  NNAME10728 CPLD_UART_RI_P4_N
P  NNAME10729 CPLD_UART_RTS_P4_N
P  NNAME10730 UART_T6_NODE4_RXD
P  NNAME10731 UART_T6_NODE3_TXD_R
P  NNAME10732 UART_T6_NODE4_TXD_R
P  NNAME10733 UART_T6_NODE4_RXD_R
P  NNAME10734 UART_T6_NODE3_RXD_R
P  NNAME10735 UART_T5_NODE2_TXD_R
P  NNAME10736 UART_T5_NODE3_RXD_R
P  NNAME10737 UART_T5_NODE2_RXD_R
P  NNAME10738 TPM_LPC_SERIRQ_PORT80_NODE1
P  NNAME10739 LPC_CPU_TPM_LAD3
P  NNAME10740 LPC_CPU_TPM_LAD2
P  NNAME10741 FM_CPLD_NODE1_P1V05_SUS_EN
P  NNAME10742 PWRGD_NODE1_P1V05_SUS_PG
P  NNAME10743 POWER_SW1_PWR_CTR_N
P  NNAME10744 UART_T5_NODE1_TXD_R
P  NNAME10745 UART_T6_NODE1_TXD_R
P  NNAME10746 UART_T6_NODE2_TXD_R
P  NNAME10747 UART_T5_NODE1_RXD_R
P  NNAME10748 UART_T6_NODE2_RXD_R
P  NNAME10749 TP_BIOS_NODE1_PORT80_ID0
P  NNAME10750 LPC_CPU_TPM_LAD1
P  NNAME10751 LPC_CPU_TPM_LAD0
P  NNAME10752 P1V05_SUS_NODE1_ADJ
P  NNAME10753 P1V05_SUS_NODE1_ADJ_S
P  NNAME10754 SW_P1V8_STB_NODE1_PH
P  NNAME10755 I2C_SCL_FANCTRL2_R
P  NNAME10756 I2C_SCL_FANCTRL1_R
P  NNAME10757 CM_STATUS_LED_N
P  NNAME10758 ATTENTION_LED_N
P  NNAME10759 TP_P3V3_NODE1_INIT_L
P  NNAME10760 TP_NODE1_ERR_OUT_DIMM0
P  NNAME10761 VR_PVCCP_NODE1_VCC
P  NNAME10762 VR_PVCCP_NODE1_TSEN_R
P  NNAME10763 H_CPU_NODE1_VR_HOT_L
P  NNAME10764 PWRGD_NODE1_PVCCP_PG
P  NNAME10765 SW_P1V8_STB_NODE1_BT
P  NNAME10766 FM_CPLD_NODE1_P1V8_STB_EN
P  NNAME10767 FNACTRL2_TMP_IN
P  NNAME10768 POWER_SW3_PWR_CTR_N
P  NNAME10769 CM_STATUS_LED_R
P  NNAME10770 PV_VTT_DDR_NODE1
P  NNAME10771 XDP_CPU_NODE1_PWROK_STALL_L
P  NNAME10772 XDP_CPU_NODE1_PWROK
P  NNAME10773 XDP_CPU_NODE1_PWROK_R
P  NNAME10774 XDP_CPU_NODE1_PG_RST_R
P  NNAME10775 FM_CPU_NODE1_XDP_PG_RST
P  NNAME10776 P1V05_STB_NODE1_XDP_A
P  NNAME10777 ISENSE_PVCCP_NODE1_ISEN1N
P  NNAME10778 VR_PVCCP_NODE1_ISEN1P_RR
P  NNAME10779 VR_PVCCP_NODE1_LGATE1
P  NNAME10780 VR_PVCCP_NODE1_EN
P  NNAME10781 VR_PVCCP_NODE1_PVCC
P  NNAME10782 FM_CPLD_NODE1_PVCCP_EN
P  NNAME10783 SVID_CPU_NODE1_CLK_R
P  NNAME10784 SVID_CPU_NODE1_DAT_R
P  NNAME10785 AGND_PVCCP_NODE1
P  NNAME10786 VR_PVCCP_NODE1_IBIAS
P  NNAME10787 P1V8_STB_NODE1_SS
P  NNAME10788 P1V8_STB_NODE1_VREG5
P  NNAME10789 P1V8_STB_NODE1_FB
P  NNAME10790 FM_CPLD_NODE1_P1V8_STB_S_EN
P  NNAME10791 PWRGD_NODE1_P1V8_STB_PG
P  NNAME10792 POWER_SW1_PWR_CTR_12V
P  NNAME10793 I2C_ALERT_FNACTRL2_N
P  NNAME10794 I2C_SDA_FANCTRL2_R
P  NNAME10795 FNACTRL1_TMP_IN
P  NNAME10796 I2C_SDA_FANCTRL1_R
P  NNAME10797 I2C_ALERT_FNACTRL1_N
P  NNAME10798 POWER_SW2_PWR_CTR_N
P  NNAME10799 UART_T6_NODE1_RXD_R
P  NNAME10800 RST_NODE1_CPU_XDP_RSTIN_L
P  NNAME10801 P1V05_STB_NODE1_XDP_B
P  NNAME10802 CLK_100M_XDP_NODE1_DN
P  NNAME10803 CLK_100M_XDP_NODE1_DP
P  NNAME10804 ISENSE_PVCCP_NODE1_ISEN1P
P  NNAME10805 VR_PVCCP_NODE1_PHASE1
P  NNAME10806 VR_PVCCP_NODE1_BOOT1
P  NNAME10807 VR_PVCCP_NODE1_UGATE1
P  NNAME10808 VR_PVCCP_NODE1_RGND
P  NNAME10809 VR_PVCCP_NODE1_FB
P  NNAME10810 VR_PVCCP_NODE1_COMP
P  NNAME10811 VR_PVCCP_NODE1_ISEN1P_CC
P  NNAME10812 VR_PVCCP_NODE1_TONSET
P  NNAME10813 VR_PVCCP_NODE1_OCSET
P  NNAME10814 VR_PVCCP_NODE1_TSEN
P  NNAME10815 VR_PVCCP_NODE1_ICCMAX
P  NNAME10816 VR_PVCCP_NODE1_TEMPMAX
P  NNAME10817 VR_PVCCP_NODE1_SETINI
P  NNAME10818 POWER_SW2_PWR_CTR_12V
P  NNAME10819 I2C_PSU2_SCL_MOS
P  NNAME10820 UART_T7_NODE4_RXD
P  NNAME10821 UART_T7_NODE4_TXD_R
P  NNAME10822 UART_T7_NODE4_RXD_R
P  NNAME10823 UART_T7_NODE3_TXD_R
P  NNAME10824 PV_VTT_DDR_NODE1_REFOUT
P  NNAME10825 PV_VTT_DDR_NODE1_VOSNS
P  NNAME10826 SW_VR_PVCCP_NODE1_VIN_FLT
P  NNAME10827 VR_PVCCP_NODE1_TONSET_R
P  NNAME10828 I2C_PSU2_SDA_MOS
P  NNAME10829 I2C_PSU1_SDA_MOS
P  NNAME10830 I2C_PSU1_SCL_MOS
P  NNAME10831 UART_T7_NODE3_TXD
P  NNAME10832 UART_T8_NODE4_TXD_R
P  NNAME10833 UART_T7_NODE3_RXD
P  NNAME10834 UART_T7_NODE2_RXD
P  NNAME10835 UART_T8_NODE4_RXD
P  NNAME10836 UART_T7_NODE2_TXD_R
P  NNAME10837 UART_T7_NODE2_TXD
P  NNAME10838 UART_T7_NODE3_RXD_R
P  NNAME10839 UART_T8_NODE4_RXD_R
P  NNAME10840 UART_T7_NODE2_RXD_R
P  NNAME10841 UART_T8_NODE3_TXD_R
P  NNAME10842 FM_CPLD_NODE1_PVTT_DDR_EN
P  NNAME10843 PWRGD_NODE1_PVTT_DDR_PG
P  NNAME10844 PV_VTT_DDR_NODE1_REFIN
P  NNAME10845 SIO_JTAG_CPLD1_TDI_R
P  NNAME10846 VR_PVCCP_NODE1_COMP_RC
P  NNAME10847 VR_PVCCP_NODE1_FB_RR
P  NNAME10848 VR_PVCCP_NODE1_VSEN
P  NNAME10849 VR_PVCCP_NODE1_FB_RC
P  NNAME10850 I2C_COM3_SDA_RC
P  NNAME10851 UART_T8_NODE2_TXD_R
P  NNAME10852 UART_T8_NODE3_RXD
P  NNAME10853 UART_T7_NODE1_RXD
P  NNAME10854 UART_T7_NODE1_TXD_R
P  NNAME10855 UART_T7_NODE1_TXD
P  NNAME10856 UART_T7_NODE1_RXD_R
P  NNAME10857 UART_T8_NODE3_RXD_R
P  NNAME10858 UART_T8_NODE2_RXD_R
P  NNAME10859 SIO_JTAG_CPLD1_TMS_R
P  NNAME10860 SIO_JTAG_CPLD1_TCK_R
P  NNAME10861 SIO_JTAG_CPLD3_TDI_R
P  NNAME10862 SIO_JTAG_CPLD3_TMS_R
P  NNAME10863 SIO_JTAG_CPLD3_TDO
P  NNAME10864 SIO_JTAG_CPLD3_TCK_R
P  NNAME10865 LPC_CPU_NODE1_LAD3_SIO
P  NNAME10866 LPC_CPU_NODE1_LAD2_SIO
P  NNAME10867 LPC_CPU_NODE1_LAD1_SIO
P  NNAME10868 LPC_CPU_NODE1_LAD0_SIO
P  NNAME10869 LPC_CPU_NODE1_FRAME_SIO_L
P  NNAME10870 IRQ_CPU_NODE1_SERIAL_SIO
P  NNAME10871 P3V0_BAT_NODE1_R
P  NNAME10872 P2E_CPU_BMC_NODE1_TX_C_DP
P  NNAME10873 P2E_CPU_BMC_NODE1_TX_C_DN
P  NNAME10874 P2E_CPU_PCIE_SW_NODE1_RX_C_DN
P  NNAME10875 P2E_CPU_PCIE_SW_NODE1_RX_C_DP
P  NNAME10876 POWER_SW3_PWR_CTR_12V
P  NNAME10877 I2C_PSU3_SDA_MOS
P  NNAME10878 I2C_PSU3_SCL_MOS
P  NNAME10879 UART_T8_NODE1_RXD
P  NNAME10880 UART_T8_NODE2_RXD
P  NNAME10881 UART_T8_NODE1_TXD_R
P  NNAME10882 UART_T8_NODE1_RXD_R
P  NNAME10883 CPLD_UART_RI_P3_N
P  NNAME10884 SATA_SPI_CLK_NODE1
P  NNAME10885 SATA_SPI_DO_NODE1
P  NNAME10886 P1V05_CLK_NODE1_R
P  NNAME10887 CLK_100M_PCIE_SW_NODE1_C_DN
P  NNAME10888 CLK_100M_PCIE_SW_NODE1_C_DP
P  NNAME10889 UART_T9_NODE4_RXD
P  NNAME10890 UART_T9_NODE4_RXD_R
P  NNAME10891 UART_T9_NODE4_TXD_R
P  NNAME10892 UART_T9_NODE3_TXD_R
P  NNAME10893 UART_T9_NODE3_RXD_R
P  NNAME10894 SIO_JTAG_CPLD3_TMS
P  NNAME10895 SIO_JTAG_CPLD3_TCK
P  NNAME10896 SIO_JTAG_CPLD3_TDI
P  NNAME10897 UART_RI_P3_BUFFER_N
P  NNAME10898 XTAL_CLK_NODE1_X2
P  NNAME10899 XTAL_CLK_NODE1_X1
P  NNAME10900 FM_CPLD_NODE1_CLK_PG
P  NNAME10901 FM_CPLD_CLK_R_PG_NODE1_R
P  NNAME10902 P1V05_CLK_NODE1
P  NNAME10903 P2E_CPU_USB_NODE1_RX_DN
P  NNAME10904 PE_SW_USB_PERST_L
P  NNAME10905 CLK_100M_PCIE_SW_NODE1_DN
P  NNAME10906 CLK_100M_PCIE_SW_NODE1_DP
P  NNAME10907 UART_T8_NODE4_TXD
P  NNAME10908 UART_T8_NODE3_TXD
P  NNAME10909 UART_T8_NODE2_TXD
P  NNAME10910 UART_T8_NODE1_TXD
P  NNAME10911 UART_T7_NODE4_TXD
P  NNAME10912 UART_T10_NODE2_TXD_R
P  NNAME10913 UART_T10_NODE4_RXD
P  NNAME10914 UART_T9_NODE3_TXD
P  NNAME10915 UART_T10_NODE4_TXD_R
P  NNAME10916 UART_T10_NODE4_RXD_R
P  NNAME10917 UART_T9_NODE2_RXD_R
P  NNAME10918 UART_T9_NODE2_TXD_R
P  NNAME10919 UART_T10_NODE3_TXD_R
P  NNAME10920 UART_T10_NODE3_RXD_R
P  NNAME10921 UART_T9_NODE1_TXD_R
P  NNAME10922 SIO_JTAG_CPLD2_TDI
P  NNAME10923 SIO_JTAG_CPLD2_TMS
P  NNAME10924 UART_RTS_P4_R_N
P  NNAME10925 UART_DTR_P4_R_N
P  NNAME10926 SATA_SPI_CS_NODE1
P  NNAME10927 SATA_SPI_DI_NODE1
P  NNAME10928 SATA_SPI_DI_NODE1_R
P  NNAME10929 CLP_ITP_EN_NODE1
P  NNAME10930 CLK_25M_SATA_NODE1
P  NNAME10931 CLK_25M_SATA_NODE1_R
P  NNAME10932 CLK_100M_USB_NODE1_DP
P  NNAME10933 CLK_100M_USB_NODE1_DN
P  NNAME10934 P2E_CPU_USB_NODE1_TX_DP
P  NNAME10935 P2E_CPU_USB_NODE1_TX_C_DP
P  NNAME10936 P2E_CPU_USB_NODE1_RX_DP
P  NNAME10937 P2E_CPU_USB_NODE1_TX_C_DN
P  NNAME10938 PCIE_SW_SCAN_EN
P  NNAME10939 UART_T9_NODE2_RXD
P  NNAME10940 UART_T9_NODE2_TXD
P  NNAME10941 UART_T9_NODE1_RXD
P  NNAME10942 UART_T9_NODE1_TXD
P  NNAME10943 UART_T10_NODE3_RXD
P  NNAME10944 UART_T9_NODE3_RXD
P  NNAME10945 UART_T10_NODE2_RXD
P  NNAME10946 UART_T10_NODE2_RXD_R
P  NNAME10947 UART_T9_NODE1_RXD_R
P  NNAME10948 UART_T10_NODE1_TXD_R
P  NNAME10949 SIO_JTAG_CPLD1_TDO
P  NNAME10950 SIO_CPLD_RSV3_R
P  NNAME10951 SIO_CPLD_RSV2_R
P  NNAME10952 SIO_CPLD_RSV1_R
P  NNAME10953 SIO_JTAG_CPLD2_TCK
P  NNAME10954 UART_RTS_P3_R_N
P  NNAME10955 UART_DTR_P3_R_N
P  NNAME10956 SATA_VCONT_NODE1
P  NNAME10957 P3V3_CLK_NODE1_R
P  NNAME10958 CLKREQA_NODE1_N
P  NNAME10959 CLK_14M_CPU_NODE1_R
P  NNAME10960 CLKREQB_NODE1_N
P  NNAME10961 CLKREQC_NODE1_N
P  NNAME10962 CLK_100M_NIC2_NODE1_DP
P  NNAME10963 CLK_100M_NIC2_NODE1_DN
P  NNAME10964 CLK_100M_SATA_NODE1_DP
P  NNAME10965 CLK_100M_SATA_NODE1_DN
P  NNAME10966 P2E_CPU_USB_NODE1_TX_DN
P  NNAME10967 PCIE_SW_P0_ERR_R
P  NNAME10968 PCIE_SW_EEPROM_DAT
P  NNAME10969 PCIE_SW_EEPROM_CLK
P  NNAME10970 FM_CPLD_PCIE_SW_PERST_L
P  NNAME10971 UART_T9_NODE4_TXD
P  NNAME10972 UART_T10_NODE1_TXD
P  NNAME10973 UART_T10_NODE1_RXD
P  NNAME10974 UART_T10_NODE1_RXD_R
P  NNAME10975 UART_T11_NODE4_TXD_R
P  NNAME10976 SIO_JTAG_CPLD2_TMS_R
P  NNAME10977 SIO_JTAG_CPLD2_TDI_R
P  NNAME10978 SIO_JTAG_CPLD2_TDO
P  NNAME10979 SIO_JTAG_CPLD2_TCK_R
P  NNAME10980 SATA_NODE1_GPIO2
P  NNAME10981 SATA_NODE1_GPIO1
P  NNAME10982 LED_SATA_NODE1_GPIO0
P  NNAME10983 LED_SATA_NODE1_R
P  NNAME10984 SATA_SPI_CLK_NODE1_R
P  NNAME10985 SATA_SPI_CS_NODE1_R
P  NNAME10986 SATA_SPI_DO_NODE1_R
P  NNAME10987 P1V5_CLK_NODE1_R
P  NNAME10988 PCIE_SW_SLOTCLK
P  NNAME10989 PCIE_SW_I2C_SDA
P  NNAME10990 PCIE_SW_I2C_SCL
P  NNAME10991 PCIE_SW_P0_CTCDIS
P  NNAME10992 PCIE_SW_PWR_SAV
P  NNAME10993 PCIE_SW_P2_CTCDIS
P  NNAME10994 PCIE_SW_P1_CTCDIS
P  NNAME10995 UART_T10_NODE2_TXD
P  NNAME10996 UART_T10_NODE3_TXD
P  NNAME10997 UART_T11_NODE4_TXD
P  NNAME10998 UART_T11_NODE4_RXD
P  NNAME10999 UART_T11_NODE4_RXD_R
P  NNAME11000 UART_T11_NODE3_TXD_R
P  NNAME11001 UART_T11_NODE3_RXD_R
P  NNAME11002 UART_T12_NODE4_TXD_R
P  NNAME11003 FM_CPLD_NODE1_SATA_PERST_L
P  NNAME11004 IRQ_LVC3_SATA_NODE1_WAKE_L
P  NNAME11005 UART_T10_NODE4_TXD
P  NNAME11006 UART_T11_NODE2_TXD
P  NNAME11007 UART_T11_NODE1_RXD
P  NNAME11008 UART_T11_NODE1_TXD
P  NNAME11009 UART_T11_NODE3_TXD
P  NNAME11010 UART_T12_NODE2_TXD
P  NNAME11011 UART_T12_NODE1_RXD
P  NNAME11012 UART_T12_NODE1_TXD
P  NNAME11013 UART_T11_NODE3_RXD
P  NNAME11014 UART_T11_NODE2_RXD
P  NNAME11015 UART_T12_NODE2_RXD
P  NNAME11016 CPLD_UART_RTS_P3_N
P  NNAME11017 UART_T12_NODE4_RXD
P  NNAME11018 UART_T12_NODE4_TXD
P  NNAME11019 UART_T12_NODE3_RXD
P  NNAME11020 UART_T12_NODE3_TXD
P  NNAME11021 CPLD_UART_DTR_P3_N
P  NNAME11022 CPLD_UART_TX_P3
P  NNAME11023 CPLD_UART_RX_P3
P  NNAME11024 UART_T12_NODE3_TXD_R
P  NNAME11025 UART_T11_NODE2_TXD_R
P  NNAME11026 UART_T12_NODE3_RXD_R
P  NNAME11027 UART_T12_NODE4_RXD_R
P  NNAME11028 UART_T11_NODE1_TXD_R
P  NNAME11029 UART_T11_NODE2_RXD_R
P  NNAME11030 UART_T11_NODE1_RXD_R
P  NNAME11031 SATA_NODE1_GPIO5
P  NNAME11032 PU_SATA_NODE1_GPIO4
P  NNAME11033 SATA_NODE1_GPIO3
P  NNAME11034 P1V8_SATA_VAA2_1_NODE1
P  NNAME11035 NODE1_USB_TESTMODE
P  NNAME11036 SATA_NODE1_ISET
P  NNAME11037 SATA_NODE1_XTLOUT
P  NNAME11038 P1V8_SATA_VAA1_NODE1
P  NNAME11039 SATA_A_NODE1_TX_P0
P  NNAME11040 SATA_A_NODE1_TX_N0
P  NNAME11041 P1V8_SATA_VAA2_0_NODE1
P  NNAME11042 SATA_A_NODE1_RX_N0
P  NNAME11043 SATA_A_NODE1_RX_P0
P  NNAME11044 P1V8_SATA_AVDD_NODE1
P  NNAME11045 P2E_CPU_SATA_NODE1_RX_C_DP
P  NNAME11046 P2E_CPU_SATA_NODE1_RX_C_DN
P  NNAME11047 UART_T12_NODE2_TXD_R
P  NNAME11048 UART_T12_NODE2_RXD_R
P  NNAME11049 UART_T12_NODE1_TXD_R
P  NNAME11050 UART_T12_NODE1_RXD_R
P  NNAME11051 SPI_USB_NODE1_WP_L
P  NNAME11052 SPI_USB_NODE1_SI
P  NNAME11053 SPI_USB_NODE1_SI_R
P  NNAME11054 FM_CPLD_NODE1_USB_PONRST_L
P  NNAME11055 RST_BTN_NODE1_L
P  NNAME11056 RST_BTN_NODE1_C_L
P  NNAME11057 LAN2_LED_LINK_100_N
P  NNAME11058 LAN2_LED_LINK_1000_N
P  NNAME11059 PCIE_LAN2_RX_C_DP
P  NNAME11060 PCIE_LAN2_RX_C_DN
P  NNAME11061 SPI_LAN2_NVM_CS_N
P  NNAME11062 SPI_USB_NODE1_CSB_N
P  NNAME11063 FM_CPLD_NODE1_USB_PERST_L
P  NNAME11064 SPI_LAN2_NVM_SO
P  NNAME11065 LAN2_NVM_CS_N_R
P  NNAME11066 CPLD_UART_RI_P4_LS_N
P  NNAME11067 CPLD_UART_RX_P3_R
P  NNAME11068 CPLD_UART_RTS_P4_R_N
P  NNAME11069 PWRGD_NODE1_P1V0
P  NNAME11070 SPI_USB_NODE1_CLK
P  NNAME11071 SPI_USB_NODE1_SO
P  NNAME11072 SPI_USB_NODE1_HOLD_L
P  NNAME11073 USB_NODE1_PECREQ_L
P  NNAME11074 P2E_CPU_USB_NODE1_RX_C_DP
P  NNAME11075 P2E_CPU_USB_NODE1_RX_C_DN
P  NNAME11076 LED_CPU_NODE1_CPLD_D
P  NNAME11077 PWR_BTN_NODE1_L
P  NNAME11078 SPI_LAN2_NVM_SK
P  NNAME11079 SPI_LAN2_NVM_SI
P  NNAME11080 LAN2_NC_SI_TDX0
P  NNAME11081 LAN2_NC_SI_TDX1
P  NNAME11082 LAN2_NC_SI_TX_EN
P  NNAME11083 UART_RI_RP6_L_N
P  NNAME11084 CPLD_UART_DTR_P4_R_N
P  NNAME11085 UART_DTR_RP6_L_N
P  NNAME11086 UART_RTS_RP6_L_N
P  NNAME11087 CPLD_UART_RI_P3_LS_N
P  NNAME11088 UART_RI_RP5_L_N_R
P  NNAME11089 UART_CTS_RP5_L_N
P  NNAME11090 UART_RI_RP6_L_N_R
P  NNAME11091 FM_CPLD_NODE1_P1V0_EN
P  NNAME11092 SPI_USB_NODE1_CLK_R
P  NNAME11093 SPI_USB_NODE1_CSB_R_L
P  NNAME11094 SPI_USB_NODE1_R_SO
P  NNAME11095 FM_NODE1_DDR3_SYSPWRGD_R_L
P  NNAME11096 TP_CPLD_NODE1_IO39
P  NNAME11097 FM_NODE1_DDR3_DRAM_POK_R_L
P  NNAME11098 FM_CPLD_NODE1_JTAG_POK_R_L
P  NNAME11099 LED_PWR_NODE1_L
P  NNAME11100 LED_CPU_NODE1_CPLD
P  NNAME11101 FM_CPLD_NODE1_PWR_BTN_L
P  NNAME11102 LAN2_NC_SI_RXD0
P  NNAME11103 LAN2_NC_SI_RXD1
P  NNAME11104 LAN2_NC_SI_CRS_DV
P  NNAME11105 LAN2_NC_SI_CLK_IN
P  NNAME11106 LAN2_NVM_HOLD_N
P  NNAME11107 UART_RI_RP5_L_N
P  NNAME11108 CPLD_UART_RX_P4_R
P  NNAME11109 CPLD_UART_DTR_P3_R_N
P  NNAME11110 UART_DTR_RP5_L_N
P  NNAME11111 UART_RTS_RP5_L_N
P  NNAME11112 CPLD_UART_RTS_P3_R_N
P  NNAME11113 FM_CPLD_NODE1_BMC_SRST_L
P  NNAME11114 TP_FM_CPLD_NODE1_BMC_EXTRST_L
P  NNAME11115 FM_NODE1_DDR3_DRAM_POK_L
P  NNAME11116 FM_NODE1_DDR3_SYSPWRGD_L
P  NNAME11117 FM_CPLD_NODE1_JTAG_POK_L
P  NNAME11118 UART_DSR_RP6_L_N
P  NNAME11119 TP_FM_CPLD_NODE1_P1V0_STB_EN
P  NNAME11120 PWR_BTN_NODE1_C_L
P  NNAME11121 TP_FM_CPLD_NODE1_SSI_PERST_L
P  NNAME11122 TP_FM_CPLD_NODE1_PWR_BTN_BMC
P  NNAME11123 CPLD_CPU_THRMTRIP_N
P  NNAME11124 FM_CPLD_NODE1_DEBUG_MODE
P  NNAME11125 POWER_SW2_PWR_CTR_12V_R
P  NNAME11126 POWER_SW1_PWR_CTR_12V_R
P  NNAME11127 PWRGD_NODE1_P3V3_STB_PG_CPLD
P  NNAME11128 TP_FM_CPLD_NODE1_P3V3_STB_SW_EN
P  NNAME11129 PWRGD_NODE1_P5V_STB_PG_CPLD
P  NNAME11130 PWRGD_NODE1_P12V_PG
P  NNAME11131 FM_CPLD_NODE1_WDT
P  NNAME11132 FM_NODE1_CORE0_1_RST_L
P  NNAME11133 SYS_AUTO_POWER_ON_N
P  NNAME11134 FM_CPLD_NODE1_WDT_R
P  NNAME11135 LAN2_CTRL_P1V9_R
P  NNAME11136 POWER_SW3_PWR_CTR_12V_R
P  NNAME11137 PWRGD_NODE1_P12V_PG_R
P  NNAME11138 FM_NODE1_DFX_GPIO_GRP05_R
P  NNAME11139 P12V_NODE1_PWRGD_EN
P  NNAME11140 SIO_JTAG_CPLD1_TDI
P  NNAME11141 SIO_JTAG_CPLD1_TMS
P  NNAME11142 SIO_JTAG_CPLD1_TCK
999
